G04 ================== begin FILE IDENTIFICATION RECORD ==================*
G04 Layout Name:  15126-1b.brd*
G04 Film Name:    SE_REF_L5*
G04 File Format:  Gerber RS274X*
G04 File Origin:  Cadence Allegro 16.6-2015-S079*
G04 Origin Date:  Fri Feb 10 17:23:35 2017*
G04 *
G04 Layer:  BOARD GEOMETRY/PANEL_OUTLINE*
G04 Layer:  BOARD GEOMETRY/SE_REF_L5_TBL*
G04 Layer:  BOARD GEOMETRY/SE_REF_L5_L5*
G04 *
G04 Offset:    (0.00 0.00)*
G04 Mirror:    No*
G04 Mode:      Positive*
G04 Rotation:  0*
G04 FullContactRelief:  No*
G04 UndefLineWidth:     6.00*
G04 ================== end FILE IDENTIFICATION RECORD ====================*
%FSLAX35Y35*MOIN*%
%IR0*IPPOS*OFA0.00000B0.00000*MIA0B0*SFA1.00000B1.00000*%
%ADD10C,.02*%
%ADD11C,.006*%
%ADD12C,.0035*%
%ADD13C,.00352*%
%ADD14C,.0056*%
G75*
%LPD*%
G75*
G54D10*
G01X2026678Y631398D02*
Y527448D01*
G01D02*
X2761678D01*
G01X2026678Y562098D02*
X2761678D01*
G01X2026678Y596748D02*
X2761678D01*
G01X2026678Y631398D02*
X2761678D01*
G01X2201678D02*
Y527448D01*
G01X2446678Y631398D02*
Y527448D01*
G01X2551678Y631398D02*
Y527448D01*
G01X2761678Y631398D02*
Y527448D01*
G54D11*
G01X-17372Y-95792D02*
Y-113292D01*
G01X-22394Y-95792D02*
X-12350D01*
G01X-3584Y-113292D02*
Y-95792D01*
G01Y-104250D02*
X-2492Y-102792D01*
X-1400Y-101917D01*
X346Y-101626D01*
X1656Y-101917D01*
X3185Y-103084D01*
X3840Y-104834D01*
Y-113292D01*
G01X17628Y-101626D02*
Y-113292D01*
G01Y-96959D02*
X17191Y-96667D01*
Y-96084D01*
X17628Y-95792D01*
X18065Y-96084D01*
Y-96667D01*
X17628Y-96959D01*
G01X31853Y-111251D02*
X32945Y-112417D01*
X34473Y-113292D01*
X35783D01*
X37093Y-112709D01*
X37966Y-111834D01*
X38403Y-110668D01*
X38185Y-108917D01*
X37311Y-108042D01*
X33381Y-106292D01*
X32508Y-104250D01*
X32945Y-102792D01*
X33818Y-101917D01*
X35128Y-101626D01*
X36438Y-101917D01*
X37748Y-102792D01*
G01X67071Y-117667D02*
X68600Y-118834D01*
X70346Y-119125D01*
X71874Y-118834D01*
X73185Y-117376D01*
X74058Y-115334D01*
Y-101626D01*
G01Y-103959D02*
X73185Y-102792D01*
X71874Y-101917D01*
X70346Y-101626D01*
X68600Y-102209D01*
X67508Y-103375D01*
X66634Y-105417D01*
X66198Y-107459D01*
X66416Y-109209D01*
X67290Y-111251D01*
X68600Y-112709D01*
X70346Y-113292D01*
X71656Y-113000D01*
X73185Y-111834D01*
X74058Y-110668D01*
G01X84353Y-105417D02*
X91340D01*
X90685Y-103375D01*
X89593Y-102209D01*
X88065Y-101626D01*
X86536Y-101917D01*
X85226Y-102792D01*
X84353Y-104834D01*
X83916Y-106584D01*
Y-108334D01*
X84353Y-110084D01*
X85445Y-111834D01*
X86755Y-113000D01*
X88283Y-113292D01*
X89811Y-112709D01*
X91340Y-110959D01*
G01X102071Y-113292D02*
Y-101626D01*
G01Y-103959D02*
X103163Y-102792D01*
X104255Y-101917D01*
X105783Y-101626D01*
X106874Y-101917D01*
X108185Y-102792D01*
G01X118698Y-113292D02*
Y-95792D01*
G01Y-104542D02*
X119790Y-102792D01*
X121100Y-101917D01*
X122410Y-101626D01*
X124374Y-102209D01*
X125685Y-103375D01*
X126558Y-105417D01*
Y-107750D01*
X126121Y-110084D01*
X125248Y-111834D01*
X123720Y-113000D01*
X122410Y-113292D01*
X121100Y-113000D01*
X119790Y-112126D01*
X118698Y-110668D01*
G01X136853Y-105417D02*
X143840D01*
X143185Y-103375D01*
X142093Y-102209D01*
X140565Y-101626D01*
X139036Y-101917D01*
X137726Y-102792D01*
X136853Y-104834D01*
X136416Y-106584D01*
Y-108334D01*
X136853Y-110084D01*
X137945Y-111834D01*
X139255Y-113000D01*
X140783Y-113292D01*
X142311Y-112709D01*
X143840Y-110959D01*
G01X154571Y-113292D02*
Y-101626D01*
G01Y-103959D02*
X155663Y-102792D01*
X156755Y-101917D01*
X158283Y-101626D01*
X159374Y-101917D01*
X160685Y-102792D01*
G01X192628Y-101626D02*
Y-113292D01*
G01Y-96959D02*
X192191Y-96667D01*
Y-96084D01*
X192628Y-95792D01*
X193065Y-96084D01*
Y-96667D01*
X192628Y-96959D01*
G01X206853Y-111251D02*
X207945Y-112417D01*
X209473Y-113292D01*
X210783D01*
X212093Y-112709D01*
X212966Y-111834D01*
X213403Y-110668D01*
X213185Y-108917D01*
X212311Y-108042D01*
X208381Y-106292D01*
X207508Y-104250D01*
X207945Y-102792D01*
X208818Y-101917D01*
X210128Y-101626D01*
X211438Y-101917D01*
X212748Y-102792D01*
G01X241634Y-117667D02*
X243163Y-118834D01*
X244473Y-119125D01*
X246220Y-118542D01*
X247530Y-117084D01*
X248185Y-114458D01*
Y-101626D01*
G01Y-96959D02*
X247748Y-96667D01*
Y-96084D01*
X248185Y-95792D01*
X248621Y-96084D01*
Y-96667D01*
X248185Y-96959D01*
G01X258916Y-101626D02*
Y-109792D01*
X259790Y-111834D01*
X261100Y-113000D01*
X262628Y-113292D01*
X264156Y-113000D01*
X265466Y-111834D01*
X266340Y-109792D01*
G01Y-113292D02*
Y-101626D01*
G01X276853Y-111251D02*
X277945Y-112417D01*
X279473Y-113292D01*
X280783D01*
X282093Y-112709D01*
X282966Y-111834D01*
X283403Y-110668D01*
X283185Y-108917D01*
X282311Y-108042D01*
X278381Y-106292D01*
X277508Y-104250D01*
X277945Y-102792D01*
X278818Y-101917D01*
X280128Y-101626D01*
X281438Y-101917D01*
X282748Y-102792D01*
G01X297628Y-95792D02*
Y-113292D01*
G01X294571Y-101626D02*
X300685D01*
G01X331318Y-113292D02*
Y-98417D01*
X331755Y-96959D01*
X332628Y-96084D01*
X333938Y-95792D01*
X335248Y-96375D01*
X335903Y-97834D01*
G01X333283Y-102792D02*
X328916D01*
G01X350128Y-113292D02*
X348818Y-113000D01*
X347508Y-111834D01*
X346634Y-109792D01*
X346198Y-107459D01*
X346634Y-105125D01*
X347508Y-103084D01*
X348818Y-101917D01*
X350128Y-101626D01*
X351438Y-101917D01*
X352748Y-103084D01*
X353621Y-105125D01*
X353840Y-107459D01*
X353621Y-109792D01*
X352748Y-111834D01*
X351438Y-113000D01*
X350128Y-113292D01*
G01X364571D02*
Y-101626D01*
G01Y-103959D02*
X365663Y-102792D01*
X366755Y-101917D01*
X368283Y-101626D01*
X369374Y-101917D01*
X370685Y-102792D01*
G01X398043Y-118542D02*
X399353Y-119125D01*
X401100Y-118542D01*
X402191Y-117376D01*
X403065Y-115917D01*
X404374Y-111251D01*
X407213Y-101626D01*
G01X400226D02*
X404374Y-111251D01*
G01X420128Y-113292D02*
X418818Y-113000D01*
X417508Y-111834D01*
X416634Y-109792D01*
X416198Y-107459D01*
X416634Y-105125D01*
X417508Y-103084D01*
X418818Y-101917D01*
X420128Y-101626D01*
X421438Y-101917D01*
X422748Y-103084D01*
X423621Y-105125D01*
X423840Y-107459D01*
X423621Y-109792D01*
X422748Y-111834D01*
X421438Y-113000D01*
X420128Y-113292D01*
G01X433916Y-101626D02*
Y-109792D01*
X434790Y-111834D01*
X436100Y-113000D01*
X437628Y-113292D01*
X439156Y-113000D01*
X440466Y-111834D01*
X441340Y-109792D01*
G01Y-113292D02*
Y-101626D01*
G01X452071Y-113292D02*
Y-101626D01*
G01Y-103959D02*
X453163Y-102792D01*
X454255Y-101917D01*
X455783Y-101626D01*
X456874Y-101917D01*
X458185Y-102792D01*
G01X487071Y-113292D02*
Y-101626D01*
G01Y-103959D02*
X488163Y-102792D01*
X489255Y-101917D01*
X490783Y-101626D01*
X491874Y-101917D01*
X493185Y-102792D01*
G01X504353Y-105417D02*
X511340D01*
X510685Y-103375D01*
X509593Y-102209D01*
X508065Y-101626D01*
X506536Y-101917D01*
X505226Y-102792D01*
X504353Y-104834D01*
X503916Y-106584D01*
Y-108334D01*
X504353Y-110084D01*
X505445Y-111834D01*
X506755Y-113000D01*
X508283Y-113292D01*
X509811Y-112709D01*
X511340Y-110959D01*
G01X523818Y-113292D02*
Y-98417D01*
X524255Y-96959D01*
X525128Y-96084D01*
X526438Y-95792D01*
X527748Y-96375D01*
X528403Y-97834D01*
G01X525783Y-102792D02*
X521416D01*
G01X539353Y-105417D02*
X546340D01*
X545685Y-103375D01*
X544593Y-102209D01*
X543065Y-101626D01*
X541536Y-101917D01*
X540226Y-102792D01*
X539353Y-104834D01*
X538916Y-106584D01*
Y-108334D01*
X539353Y-110084D01*
X540445Y-111834D01*
X541755Y-113000D01*
X543283Y-113292D01*
X544811Y-112709D01*
X546340Y-110959D01*
G01X557071Y-113292D02*
Y-101626D01*
G01Y-103959D02*
X558163Y-102792D01*
X559255Y-101917D01*
X560783Y-101626D01*
X561874Y-101917D01*
X563185Y-102792D01*
G01X574353Y-105417D02*
X581340D01*
X580685Y-103375D01*
X579593Y-102209D01*
X578065Y-101626D01*
X576536Y-101917D01*
X575226Y-102792D01*
X574353Y-104834D01*
X573916Y-106584D01*
Y-108334D01*
X574353Y-110084D01*
X575445Y-111834D01*
X576755Y-113000D01*
X578283Y-113292D01*
X579811Y-112709D01*
X581340Y-110959D01*
G01X591416Y-113292D02*
Y-101626D01*
G01Y-104542D02*
X592290Y-103084D01*
X593600Y-101917D01*
X595346Y-101626D01*
X596874Y-101917D01*
X598185Y-103084D01*
X598840Y-105125D01*
Y-113292D01*
G01X616121Y-103084D02*
X614593Y-101917D01*
X613283Y-101626D01*
X611536Y-102209D01*
X610226Y-103375D01*
X609353Y-105417D01*
X609134Y-107459D01*
X609353Y-109501D01*
X610226Y-111251D01*
X611536Y-112709D01*
X613283Y-113292D01*
X614811Y-112709D01*
X616121Y-111542D01*
G01X626853Y-105417D02*
X633840D01*
X633185Y-103375D01*
X632093Y-102209D01*
X630565Y-101626D01*
X629036Y-101917D01*
X627726Y-102792D01*
X626853Y-104834D01*
X626416Y-106584D01*
Y-108334D01*
X626853Y-110084D01*
X627945Y-111834D01*
X629255Y-113000D01*
X630783Y-113292D01*
X632311Y-112709D01*
X633840Y-110959D01*
G01X665128Y-95792D02*
Y-113292D01*
G01X662071Y-101626D02*
X668185D01*
G01X682628Y-113292D02*
X681318Y-113000D01*
X680008Y-111834D01*
X679134Y-109792D01*
X678698Y-107459D01*
X679134Y-105125D01*
X680008Y-103084D01*
X681318Y-101917D01*
X682628Y-101626D01*
X683938Y-101917D01*
X685248Y-103084D01*
X686121Y-105125D01*
X686340Y-107459D01*
X686121Y-109792D01*
X685248Y-111834D01*
X683938Y-113000D01*
X682628Y-113292D01*
G01X716318D02*
Y-98417D01*
X716755Y-96959D01*
X717628Y-96084D01*
X718938Y-95792D01*
X720248Y-96375D01*
X720903Y-97834D01*
G01X718283Y-102792D02*
X713916D01*
G01X735128Y-101626D02*
Y-113292D01*
G01Y-96959D02*
X734691Y-96667D01*
Y-96084D01*
X735128Y-95792D01*
X735565Y-96084D01*
Y-96667D01*
X735128Y-96959D01*
G01X748916Y-113292D02*
Y-101626D01*
G01Y-104542D02*
X749790Y-103084D01*
X751100Y-101917D01*
X752846Y-101626D01*
X754374Y-101917D01*
X755685Y-103084D01*
X756340Y-105125D01*
Y-113292D01*
G01X774058Y-95792D02*
Y-113292D01*
G01Y-110668D02*
X773185Y-112126D01*
X771874Y-113000D01*
X770346Y-113292D01*
X768600Y-112709D01*
X767290Y-111251D01*
X766416Y-109501D01*
X766198Y-107459D01*
X766416Y-105417D01*
X767290Y-103667D01*
X768600Y-102209D01*
X770346Y-101626D01*
X771874Y-101917D01*
X772966Y-102501D01*
X774058Y-103667D01*
G01X805128Y-95792D02*
Y-113292D01*
G01X802071Y-101626D02*
X808185D01*
G01X818916Y-113292D02*
Y-95792D01*
G01Y-104250D02*
X820008Y-102792D01*
X821100Y-101917D01*
X822846Y-101626D01*
X824156Y-101917D01*
X825685Y-103084D01*
X826340Y-104834D01*
Y-113292D01*
G01X836853Y-105417D02*
X843840D01*
X843185Y-103375D01*
X842093Y-102209D01*
X840565Y-101626D01*
X839036Y-101917D01*
X837726Y-102792D01*
X836853Y-104834D01*
X836416Y-106584D01*
Y-108334D01*
X836853Y-110084D01*
X837945Y-111834D01*
X839255Y-113000D01*
X840783Y-113292D01*
X842311Y-112709D01*
X843840Y-110959D01*
G01X870543D02*
X872290Y-112417D01*
X874255Y-113292D01*
X876001D01*
X877748Y-112417D01*
X879058Y-110959D01*
X879713Y-108917D01*
X879276Y-106876D01*
X878185Y-105125D01*
X876220Y-103959D01*
X873600Y-103375D01*
X872071Y-102209D01*
X871416Y-100167D01*
X871853Y-98125D01*
X872945Y-96667D01*
X874473Y-95792D01*
X876001D01*
X877530Y-96375D01*
X878840Y-97834D01*
G01X896995Y-113292D02*
X888261D01*
Y-95792D01*
X896995D01*
G01X893501Y-104250D02*
X888261D01*
G01X927628Y-101626D02*
Y-113292D01*
G01Y-96959D02*
X927191Y-96667D01*
Y-96084D01*
X927628Y-95792D01*
X928065Y-96084D01*
Y-96667D01*
X927628Y-96959D01*
G01X938578Y-113292D02*
Y-101626D01*
G01Y-104834D02*
X939233Y-103375D01*
X940325Y-102209D01*
X941853Y-101626D01*
X943381Y-102209D01*
X944473Y-103375D01*
X945128Y-104834D01*
Y-113292D01*
G01Y-104834D02*
X945783Y-103375D01*
X946874Y-102209D01*
X948403Y-101626D01*
X949931Y-102209D01*
X951023Y-103375D01*
X951678Y-105125D01*
Y-113292D01*
G01X958698Y-119125D02*
Y-101626D01*
G01Y-104250D02*
X959790Y-102792D01*
X960881Y-101917D01*
X962628Y-101626D01*
X964156Y-101917D01*
X965685Y-103375D01*
X966340Y-105417D01*
X966558Y-107459D01*
X966340Y-109501D01*
X965685Y-111542D01*
X964374Y-112709D01*
X962628Y-113292D01*
X961100Y-113000D01*
X959571Y-112126D01*
X958698Y-110959D01*
G01X976853Y-105417D02*
X983840D01*
X983185Y-103375D01*
X982093Y-102209D01*
X980565Y-101626D01*
X979036Y-101917D01*
X977726Y-102792D01*
X976853Y-104834D01*
X976416Y-106584D01*
Y-108334D01*
X976853Y-110084D01*
X977945Y-111834D01*
X979255Y-113000D01*
X980783Y-113292D01*
X982311Y-112709D01*
X983840Y-110959D01*
G01X1001558Y-95792D02*
Y-113292D01*
G01Y-110668D02*
X1000685Y-112126D01*
X999374Y-113000D01*
X997846Y-113292D01*
X996100Y-112709D01*
X994790Y-111251D01*
X993916Y-109501D01*
X993698Y-107459D01*
X993916Y-105417D01*
X994790Y-103667D01*
X996100Y-102209D01*
X997846Y-101626D01*
X999374Y-101917D01*
X1000466Y-102501D01*
X1001558Y-103667D01*
G01X1019058Y-113292D02*
Y-101626D01*
G01Y-103667D02*
X1018185Y-102501D01*
X1016874Y-101917D01*
X1015346Y-101626D01*
X1013818Y-102209D01*
X1012508Y-103375D01*
X1011634Y-105125D01*
X1011198Y-107459D01*
X1011634Y-109792D01*
X1012508Y-111542D01*
X1013818Y-112709D01*
X1015346Y-113292D01*
X1016874Y-113000D01*
X1018185Y-112126D01*
X1019058Y-110959D01*
G01X1028916Y-113292D02*
Y-101626D01*
G01Y-104542D02*
X1029790Y-103084D01*
X1031100Y-101917D01*
X1032846Y-101626D01*
X1034374Y-101917D01*
X1035685Y-103084D01*
X1036340Y-105125D01*
Y-113292D01*
G01X1053621Y-103084D02*
X1052093Y-101917D01*
X1050783Y-101626D01*
X1049036Y-102209D01*
X1047726Y-103375D01*
X1046853Y-105417D01*
X1046634Y-107459D01*
X1046853Y-109501D01*
X1047726Y-111251D01*
X1049036Y-112709D01*
X1050783Y-113292D01*
X1052311Y-112709D01*
X1053621Y-111542D01*
G01X1064353Y-105417D02*
X1071340D01*
X1070685Y-103375D01*
X1069593Y-102209D01*
X1068065Y-101626D01*
X1066536Y-101917D01*
X1065226Y-102792D01*
X1064353Y-104834D01*
X1063916Y-106584D01*
Y-108334D01*
X1064353Y-110084D01*
X1065445Y-111834D01*
X1066755Y-113000D01*
X1068283Y-113292D01*
X1069811Y-112709D01*
X1071340Y-110959D01*
G01X1102628Y-95792D02*
Y-113292D01*
G01X1099571Y-101626D02*
X1105685D01*
G01X1117071Y-113292D02*
Y-101626D01*
G01Y-103959D02*
X1118163Y-102792D01*
X1119255Y-101917D01*
X1120783Y-101626D01*
X1121874Y-101917D01*
X1123185Y-102792D01*
G01X1141558Y-113292D02*
Y-101626D01*
G01Y-103667D02*
X1140685Y-102501D01*
X1139374Y-101917D01*
X1137846Y-101626D01*
X1136318Y-102209D01*
X1135008Y-103375D01*
X1134134Y-105125D01*
X1133698Y-107459D01*
X1134134Y-109792D01*
X1135008Y-111542D01*
X1136318Y-112709D01*
X1137846Y-113292D01*
X1139374Y-113000D01*
X1140685Y-112126D01*
X1141558Y-110959D01*
G01X1158621Y-103084D02*
X1157093Y-101917D01*
X1155783Y-101626D01*
X1154036Y-102209D01*
X1152726Y-103375D01*
X1151853Y-105417D01*
X1151634Y-107459D01*
X1151853Y-109501D01*
X1152726Y-111251D01*
X1154036Y-112709D01*
X1155783Y-113292D01*
X1157311Y-112709D01*
X1158621Y-111542D01*
G01X1169353Y-105417D02*
X1176340D01*
X1175685Y-103375D01*
X1174593Y-102209D01*
X1173065Y-101626D01*
X1171536Y-101917D01*
X1170226Y-102792D01*
X1169353Y-104834D01*
X1168916Y-106584D01*
Y-108334D01*
X1169353Y-110084D01*
X1170445Y-111834D01*
X1171755Y-113000D01*
X1173283Y-113292D01*
X1174811Y-112709D01*
X1176340Y-110959D01*
G01X1186853Y-111251D02*
X1187945Y-112417D01*
X1189473Y-113292D01*
X1190783D01*
X1192093Y-112709D01*
X1192966Y-111834D01*
X1193403Y-110668D01*
X1193185Y-108917D01*
X1192311Y-108042D01*
X1188381Y-106292D01*
X1187508Y-104250D01*
X1187945Y-102792D01*
X1188818Y-101917D01*
X1190128Y-101626D01*
X1191438Y-101917D01*
X1192748Y-102792D01*
G01X1225128Y-101626D02*
Y-113292D01*
G01Y-96959D02*
X1224691Y-96667D01*
Y-96084D01*
X1225128Y-95792D01*
X1225565Y-96084D01*
Y-96667D01*
X1225128Y-96959D01*
G01X1238916Y-113292D02*
Y-101626D01*
G01Y-104542D02*
X1239790Y-103084D01*
X1241100Y-101917D01*
X1242846Y-101626D01*
X1244374Y-101917D01*
X1245685Y-103084D01*
X1246340Y-105125D01*
Y-113292D01*
G01X1277628D02*
Y-95792D01*
G01X1299058Y-113292D02*
Y-101626D01*
G01Y-103667D02*
X1298185Y-102501D01*
X1296874Y-101917D01*
X1295346Y-101626D01*
X1293818Y-102209D01*
X1292508Y-103375D01*
X1291634Y-105125D01*
X1291198Y-107459D01*
X1291634Y-109792D01*
X1292508Y-111542D01*
X1293818Y-112709D01*
X1295346Y-113292D01*
X1296874Y-113000D01*
X1298185Y-112126D01*
X1299058Y-110959D01*
G01X1308043Y-118542D02*
X1309353Y-119125D01*
X1311100Y-118542D01*
X1312191Y-117376D01*
X1313065Y-115917D01*
X1314374Y-111251D01*
X1317213Y-101626D01*
G01X1310226D02*
X1314374Y-111251D01*
G01X1326853Y-105417D02*
X1333840D01*
X1333185Y-103375D01*
X1332093Y-102209D01*
X1330565Y-101626D01*
X1329036Y-101917D01*
X1327726Y-102792D01*
X1326853Y-104834D01*
X1326416Y-106584D01*
Y-108334D01*
X1326853Y-110084D01*
X1327945Y-111834D01*
X1329255Y-113000D01*
X1330783Y-113292D01*
X1332311Y-112709D01*
X1333840Y-110959D01*
G01X1344571Y-113292D02*
Y-101626D01*
G01Y-103959D02*
X1345663Y-102792D01*
X1346755Y-101917D01*
X1348283Y-101626D01*
X1349374Y-101917D01*
X1350685Y-102792D01*
G01X1378261Y-95792D02*
Y-113292D01*
X1386995D01*
G01X1395325Y-110668D02*
X1396634Y-112126D01*
X1398163Y-113000D01*
X1400128Y-113292D01*
X1402093Y-112709D01*
X1403621Y-111542D01*
X1404713Y-109501D01*
X1404931Y-107167D01*
X1404495Y-104834D01*
X1403403Y-103375D01*
X1401874Y-102209D01*
X1400346Y-101917D01*
X1398818Y-102209D01*
X1396853Y-103375D01*
X1397508Y-95792D01*
X1403403D01*
G01X1417628Y-113875D02*
X1417191Y-113584D01*
Y-113000D01*
X1417628Y-112709D01*
X1418065Y-113000D01*
Y-113584D01*
X1417628Y-113875D01*
G01X2083125Y539822D02*
X2084434Y538364D01*
X2085963Y537490D01*
X2087928Y537198D01*
X2089893Y537781D01*
X2091421Y538948D01*
X2092513Y540989D01*
X2092731Y543323D01*
X2092295Y545656D01*
X2091203Y547115D01*
X2089674Y548281D01*
X2088146Y548573D01*
X2086618Y548281D01*
X2084653Y547115D01*
X2085308Y554698D01*
X2091203D01*
G01X2105428D02*
X2103681Y554115D01*
X2102371Y552656D01*
X2101498Y550907D01*
X2100843Y548573D01*
X2100625Y545948D01*
X2100843Y543323D01*
X2101498Y540989D01*
X2102371Y539239D01*
X2103681Y537781D01*
X2105428Y537198D01*
X2107174Y537781D01*
X2108485Y539239D01*
X2109358Y540989D01*
X2110013Y543323D01*
X2110231Y545948D01*
X2110013Y548573D01*
X2109358Y550907D01*
X2108485Y552656D01*
X2107174Y554115D01*
X2105428Y554698D01*
G01X2122928Y536615D02*
X2122491Y536906D01*
Y537490D01*
X2122928Y537781D01*
X2123365Y537490D01*
Y536906D01*
X2122928Y536615D01*
G01X2140428Y554698D02*
X2138681Y554115D01*
X2137371Y552656D01*
X2136498Y550907D01*
X2135843Y548573D01*
X2135625Y545948D01*
X2135843Y543323D01*
X2136498Y540989D01*
X2137371Y539239D01*
X2138681Y537781D01*
X2140428Y537198D01*
X2142174Y537781D01*
X2143485Y539239D01*
X2144358Y540989D01*
X2145013Y543323D01*
X2145231Y545948D01*
X2145013Y548573D01*
X2144358Y550907D01*
X2143485Y552656D01*
X2142174Y554115D01*
X2140428Y554698D01*
G01X2090548Y571848D02*
Y589348D01*
X2082469Y576806D01*
X2093387D01*
G01X2105428Y589348D02*
X2103681Y588765D01*
X2102371Y587306D01*
X2101498Y585557D01*
X2100843Y583223D01*
X2100625Y580598D01*
X2100843Y577973D01*
X2101498Y575639D01*
X2102371Y573889D01*
X2103681Y572431D01*
X2105428Y571848D01*
X2107174Y572431D01*
X2108485Y573889D01*
X2109358Y575639D01*
X2110013Y577973D01*
X2110231Y580598D01*
X2110013Y583223D01*
X2109358Y585557D01*
X2108485Y587306D01*
X2107174Y588765D01*
X2105428Y589348D01*
G01X2122928Y571265D02*
X2122491Y571556D01*
Y572140D01*
X2122928Y572431D01*
X2123365Y572140D01*
Y571556D01*
X2122928Y571265D01*
G01X2140428Y589348D02*
X2138681Y588765D01*
X2137371Y587306D01*
X2136498Y585557D01*
X2135843Y583223D01*
X2135625Y580598D01*
X2135843Y577973D01*
X2136498Y575639D01*
X2137371Y573889D01*
X2138681Y572431D01*
X2140428Y571848D01*
X2142174Y572431D01*
X2143485Y573889D01*
X2144358Y575639D01*
X2145013Y577973D01*
X2145231Y580598D01*
X2145013Y583223D01*
X2144358Y585557D01*
X2143485Y587306D01*
X2142174Y588765D01*
X2140428Y589348D01*
G01X2050308Y623998D02*
X2055548D01*
G01X2052928D02*
Y606498D01*
G01X2050308D02*
X2055548D01*
G01X2064751D02*
Y623998D01*
X2070428Y609415D01*
X2076105Y623998D01*
Y606498D01*
G01X2083561D02*
Y623998D01*
X2088801D01*
X2090548Y623123D01*
X2091858Y621081D01*
X2092295Y618748D01*
X2091858Y616415D01*
X2090766Y614665D01*
X2088801Y613789D01*
X2083561D01*
G01X2104336Y600665D02*
X2102153Y603581D01*
X2101061Y606498D01*
Y618164D01*
X2102153Y621081D01*
X2104336Y623998D01*
G01X2122928Y606498D02*
X2121181Y606790D01*
X2119653Y607956D01*
X2118343Y609706D01*
X2117469Y611748D01*
X2117033Y614081D01*
Y616415D01*
X2117469Y618748D01*
X2118343Y620790D01*
X2119653Y622539D01*
X2121181Y623706D01*
X2122928Y623998D01*
X2124674Y623706D01*
X2126203Y622539D01*
X2127513Y620790D01*
X2128387Y618748D01*
X2128823Y616415D01*
Y614081D01*
X2128387Y611748D01*
X2127513Y609706D01*
X2126203Y607956D01*
X2124674Y606790D01*
X2122928Y606498D01*
G01X2136716D02*
Y623998D01*
G01Y615540D02*
X2137808Y616998D01*
X2138900Y617873D01*
X2140646Y618164D01*
X2141956Y617873D01*
X2143485Y616706D01*
X2144140Y614956D01*
Y606498D01*
G01X2151378D02*
Y618164D01*
G01Y614956D02*
X2152033Y616415D01*
X2153125Y617581D01*
X2154653Y618164D01*
X2156181Y617581D01*
X2157273Y616415D01*
X2157928Y614956D01*
Y606498D01*
G01Y614956D02*
X2158583Y616415D01*
X2159674Y617581D01*
X2161203Y618164D01*
X2162731Y617581D01*
X2163823Y616415D01*
X2164478Y614665D01*
Y606498D01*
G01X2176520Y600665D02*
X2178703Y603581D01*
X2179795Y606498D01*
Y618164D01*
X2178703Y621081D01*
X2176520Y623998D01*
G01X2028643Y643481D02*
X2030390Y642023D01*
X2032355Y641148D01*
X2034101D01*
X2035848Y642023D01*
X2037158Y643481D01*
X2037813Y645523D01*
X2037376Y647564D01*
X2036285Y649315D01*
X2034320Y650481D01*
X2031700Y651065D01*
X2030171Y652231D01*
X2029516Y654273D01*
X2029953Y656315D01*
X2031045Y657773D01*
X2032573Y658648D01*
X2034101D01*
X2035630Y658065D01*
X2036940Y656606D01*
G01X2055095Y641148D02*
X2046361D01*
Y658648D01*
X2055095D01*
G01X2051601Y650190D02*
X2046361D01*
G01X2083108Y658648D02*
X2088348D01*
G01X2085728D02*
Y641148D01*
G01X2083108D02*
X2088348D01*
G01X2097551D02*
Y658648D01*
X2103228Y644065D01*
X2108905Y658648D01*
Y641148D01*
G01X2116361D02*
Y658648D01*
X2121601D01*
X2123348Y657773D01*
X2124658Y655731D01*
X2125095Y653398D01*
X2124658Y651065D01*
X2123566Y649315D01*
X2121601Y648439D01*
X2116361D01*
G01X2142595Y641148D02*
X2133861D01*
Y658648D01*
X2142595D01*
G01X2139101Y650190D02*
X2133861D01*
G01X2150925Y641148D02*
Y658648D01*
X2155291D01*
X2157038Y657773D01*
X2158348Y656606D01*
X2159440Y654857D01*
X2160313Y652814D01*
X2160531Y649898D01*
X2160313Y646981D01*
X2159440Y644939D01*
X2158348Y643189D01*
X2157038Y642023D01*
X2155291Y641148D01*
X2150925D01*
G01X2167769D02*
X2173228Y658648D01*
X2178687Y641148D01*
G01X2176721Y647273D02*
X2169734D01*
G01X2185706Y641148D02*
Y658648D01*
X2195750Y641148D01*
Y658648D01*
G01X2213031Y657189D02*
X2211721Y658065D01*
X2210193Y658648D01*
X2208446D01*
X2206481Y657773D01*
X2204953Y656315D01*
X2203861Y654564D01*
X2202988Y651648D01*
X2202769Y649023D01*
X2203206Y646398D01*
X2203861Y644648D01*
X2205171Y642898D01*
X2206700Y641731D01*
X2208228Y641148D01*
X2209756D01*
X2211285Y641731D01*
X2212595Y642606D01*
X2213687Y643772D01*
G01X2230095Y641148D02*
X2221361D01*
Y658648D01*
X2230095D01*
G01X2226601Y650190D02*
X2221361D01*
G01X2260728Y658648D02*
Y641148D01*
G01X2255706Y658648D02*
X2265750D01*
G01X2272769Y641148D02*
X2278228Y658648D01*
X2283687Y641148D01*
G01X2281721Y647273D02*
X2274734D01*
G01X2297474Y650481D02*
X2298348Y651356D01*
X2299003Y652814D01*
X2299440Y654857D01*
X2299003Y656606D01*
X2298130Y657773D01*
X2296601Y658648D01*
X2290706D01*
Y641148D01*
X2297911D01*
X2299440Y642314D01*
X2300313Y644065D01*
X2300750Y646106D01*
X2300313Y648148D01*
X2299003Y649898D01*
X2297474Y650481D01*
X2290706D01*
G01X2308861Y658648D02*
Y641148D01*
X2317595D01*
G01X2335095D02*
X2326361D01*
Y658648D01*
X2335095D01*
G01X2331601Y650190D02*
X2326361D01*
G01X2348228Y640565D02*
X2347791Y640856D01*
Y641440D01*
X2348228Y641731D01*
X2348665Y641440D01*
Y640856D01*
X2348228Y640565D01*
G01Y648439D02*
X2347791Y648731D01*
Y649315D01*
X2348228Y649606D01*
X2348665Y649315D01*
Y648731D01*
X2348228Y648439D01*
G01X2378861Y658648D02*
Y641148D01*
X2387595D01*
G01X2395925Y643772D02*
X2397234Y642314D01*
X2398763Y641440D01*
X2400728Y641148D01*
X2402693Y641731D01*
X2404221Y642898D01*
X2405313Y644939D01*
X2405531Y647273D01*
X2405095Y649606D01*
X2404003Y651065D01*
X2402474Y652231D01*
X2400946Y652523D01*
X2399418Y652231D01*
X2397453Y651065D01*
X2398108Y658648D01*
X2404003D01*
G01X2230128Y623998D02*
X2233184Y606498D01*
X2236678Y623998D01*
X2240171Y606498D01*
X2243228Y623998D01*
G01X2251558D02*
X2256798D01*
G01X2254178D02*
Y606498D01*
G01X2251558D02*
X2256798D01*
G01X2266875D02*
Y623998D01*
X2271241D01*
X2272988Y623123D01*
X2274298Y621956D01*
X2275390Y620207D01*
X2276263Y618164D01*
X2276481Y615248D01*
X2276263Y612331D01*
X2275390Y610289D01*
X2274298Y608539D01*
X2272988Y607373D01*
X2271241Y606498D01*
X2266875D01*
G01X2289178Y623998D02*
Y606498D01*
G01X2284156Y623998D02*
X2294200D01*
G01X2302093Y606498D02*
Y623998D01*
G01X2311263D02*
Y606498D01*
G01Y615248D02*
X2302093D01*
G01X2323086Y600665D02*
X2320903Y603581D01*
X2319811Y606498D01*
Y618164D01*
X2320903Y621081D01*
X2323086Y623998D01*
G01X2335128Y606498D02*
Y618164D01*
G01Y614956D02*
X2335783Y616415D01*
X2336875Y617581D01*
X2338403Y618164D01*
X2339931Y617581D01*
X2341023Y616415D01*
X2341678Y614956D01*
Y606498D01*
G01Y614956D02*
X2342333Y616415D01*
X2343424Y617581D01*
X2344953Y618164D01*
X2346481Y617581D01*
X2347573Y616415D01*
X2348228Y614665D01*
Y606498D01*
G01X2359178Y618164D02*
Y606498D01*
G01Y622831D02*
X2358741Y623123D01*
Y623706D01*
X2359178Y623998D01*
X2359615Y623706D01*
Y623123D01*
X2359178Y622831D01*
G01X2376678Y606498D02*
Y623998D01*
G01X2390903Y608539D02*
X2391995Y607373D01*
X2393523Y606498D01*
X2394833D01*
X2396143Y607081D01*
X2397016Y607956D01*
X2397453Y609122D01*
X2397235Y610873D01*
X2396361Y611748D01*
X2392431Y613498D01*
X2391558Y615540D01*
X2391995Y616998D01*
X2392868Y617873D01*
X2394178Y618164D01*
X2395488Y617873D01*
X2396798Y616998D01*
G01X2412770Y600665D02*
X2414953Y603581D01*
X2416045Y606498D01*
Y618164D01*
X2414953Y621081D01*
X2412770Y623998D01*
G01X2293125Y540698D02*
X2294434Y538656D01*
X2296181Y537490D01*
X2298146Y537198D01*
X2299893Y537490D01*
X2301640Y538948D01*
X2302731Y540698D01*
X2302950Y542448D01*
X2302513Y544489D01*
X2300985Y545948D01*
X2299456Y546531D01*
X2297491D01*
G01X2299456D02*
X2300766Y547406D01*
X2301858Y548864D01*
X2302295Y550614D01*
X2301858Y552365D01*
X2300766Y553823D01*
X2298801Y554698D01*
X2296836Y554406D01*
X2294871Y553239D01*
G01X2315428Y536615D02*
X2314991Y536906D01*
Y537490D01*
X2315428Y537781D01*
X2315865Y537490D01*
Y536906D01*
X2315428Y536615D01*
G01X2328125Y539822D02*
X2329434Y538364D01*
X2330963Y537490D01*
X2332928Y537198D01*
X2334893Y537781D01*
X2336421Y538948D01*
X2337513Y540989D01*
X2337731Y543323D01*
X2337295Y545656D01*
X2336203Y547115D01*
X2334674Y548281D01*
X2333146Y548573D01*
X2331618Y548281D01*
X2329653Y547115D01*
X2330308Y554698D01*
X2336203D01*
G01X2346280Y551781D02*
X2347590Y553531D01*
X2349118Y554406D01*
X2350865Y554698D01*
X2353048Y554115D01*
X2354576Y552656D01*
X2355013Y550907D01*
X2354795Y549156D01*
X2353921Y547698D01*
X2349555Y544781D01*
X2347590Y542740D01*
X2346280Y539822D01*
X2345843Y537198D01*
X2355013D01*
G01X2301875Y574472D02*
X2303184Y573014D01*
X2304713Y572140D01*
X2306678Y571848D01*
X2308643Y572431D01*
X2310171Y573598D01*
X2311263Y575639D01*
X2311481Y577973D01*
X2311045Y580306D01*
X2309953Y581765D01*
X2308424Y582931D01*
X2306896Y583223D01*
X2305368Y582931D01*
X2303403Y581765D01*
X2304058Y589348D01*
X2309953D01*
G01X2324178Y571265D02*
X2323741Y571556D01*
Y572140D01*
X2324178Y572431D01*
X2324615Y572140D01*
Y571556D01*
X2324178Y571265D01*
G01X2337530Y579139D02*
X2339058Y581181D01*
X2340368Y582348D01*
X2342115Y582931D01*
X2343643Y582348D01*
X2344735Y581181D01*
X2345608Y579431D01*
X2345826Y577390D01*
X2345608Y575639D01*
X2344735Y573889D01*
X2343424Y572431D01*
X2341896Y571848D01*
X2340150Y572431D01*
X2338621Y574181D01*
X2337748Y576806D01*
X2337530Y579723D01*
X2337966Y583514D01*
X2338621Y585557D01*
X2339713Y587598D01*
X2341241Y589056D01*
X2342770Y589348D01*
X2344298Y588765D01*
X2345390Y587306D01*
G01X2485843Y539531D02*
X2487590Y538073D01*
X2489555Y537198D01*
X2491301D01*
X2493048Y538073D01*
X2494358Y539531D01*
X2495013Y541573D01*
X2494576Y543614D01*
X2493485Y545365D01*
X2491520Y546531D01*
X2488900Y547115D01*
X2487371Y548281D01*
X2486716Y550323D01*
X2487153Y552365D01*
X2488245Y553823D01*
X2489773Y554698D01*
X2491301D01*
X2492830Y554115D01*
X2494140Y552656D01*
G01X2512295Y537198D02*
X2503561D01*
Y554698D01*
X2512295D01*
G01X2508801Y546240D02*
X2503561D01*
G01X2485843Y574181D02*
X2487590Y572723D01*
X2489555Y571848D01*
X2491301D01*
X2493048Y572723D01*
X2494358Y574181D01*
X2495013Y576223D01*
X2494576Y578264D01*
X2493485Y580015D01*
X2491520Y581181D01*
X2488900Y581765D01*
X2487371Y582931D01*
X2486716Y584973D01*
X2487153Y587015D01*
X2488245Y588473D01*
X2489773Y589348D01*
X2491301D01*
X2492830Y588765D01*
X2494140Y587306D01*
G01X2512295Y571848D02*
X2503561D01*
Y589348D01*
X2512295D01*
G01X2508801Y580890D02*
X2503561D01*
G01X2472928Y623998D02*
Y606498D01*
G01X2467906Y623998D02*
X2477950D01*
G01X2490428Y606498D02*
Y614373D01*
X2486061Y623998D01*
G01X2494795D02*
X2490428Y614373D01*
G01X2503561Y606498D02*
Y623998D01*
X2508801D01*
X2510548Y623123D01*
X2511858Y621081D01*
X2512295Y618748D01*
X2511858Y616415D01*
X2510766Y614665D01*
X2508801Y613789D01*
X2503561D01*
G01X2529795Y606498D02*
X2521061D01*
Y623998D01*
X2529795D01*
G01X2526301Y615540D02*
X2521061D01*
G01X2573561Y606498D02*
Y623998D01*
X2579020D01*
X2580766Y623123D01*
X2581858Y621956D01*
X2582295Y619623D01*
X2581858Y617289D01*
X2580548Y615831D01*
X2579020Y614956D01*
X2573561D01*
G01X2579020D02*
X2582295Y606498D01*
G01X2592153Y614373D02*
X2599140D01*
X2598485Y616415D01*
X2597393Y617581D01*
X2595865Y618164D01*
X2594336Y617873D01*
X2593026Y616998D01*
X2592153Y614956D01*
X2591716Y613206D01*
Y611456D01*
X2592153Y609706D01*
X2593245Y607956D01*
X2594555Y606790D01*
X2596083Y606498D01*
X2597611Y607081D01*
X2599140Y608831D01*
G01X2611618Y606498D02*
Y621373D01*
X2612055Y622831D01*
X2612928Y623706D01*
X2614238Y623998D01*
X2615548Y623415D01*
X2616203Y621956D01*
G01X2613583Y616998D02*
X2609216D01*
G01X2630428Y605915D02*
X2629991Y606206D01*
Y606790D01*
X2630428Y607081D01*
X2630865Y606790D01*
Y606206D01*
X2630428Y605915D01*
G01X2661061Y606498D02*
Y623998D01*
X2666301D01*
X2668048Y623123D01*
X2669358Y621081D01*
X2669795Y618748D01*
X2669358Y616415D01*
X2668266Y614665D01*
X2666301Y613789D01*
X2661061D01*
G01X2682928Y606498D02*
Y623998D01*
G01X2704358Y606498D02*
Y618164D01*
G01Y616123D02*
X2703485Y617289D01*
X2702174Y617873D01*
X2700646Y618164D01*
X2699118Y617581D01*
X2697808Y616415D01*
X2696934Y614665D01*
X2696498Y612331D01*
X2696934Y609998D01*
X2697808Y608248D01*
X2699118Y607081D01*
X2700646Y606498D01*
X2702174Y606790D01*
X2703485Y607664D01*
X2704358Y608831D01*
G01X2714216Y606498D02*
Y618164D01*
G01Y615248D02*
X2715090Y616706D01*
X2716400Y617873D01*
X2718146Y618164D01*
X2719674Y617873D01*
X2720985Y616706D01*
X2721640Y614665D01*
Y606498D01*
G01X2732153Y614373D02*
X2739140D01*
X2738485Y616415D01*
X2737393Y617581D01*
X2735865Y618164D01*
X2734336Y617873D01*
X2733026Y616998D01*
X2732153Y614956D01*
X2731716Y613206D01*
Y611456D01*
X2732153Y609706D01*
X2733245Y607956D01*
X2734555Y606790D01*
X2736083Y606498D01*
X2737611Y607081D01*
X2739140Y608831D01*
G01X2617311Y554698D02*
Y537198D01*
X2626045D01*
G01X2641798D02*
Y554698D01*
X2633719Y542156D01*
X2644637D01*
G01X2652748Y536615D02*
X2660608Y554698D01*
G01X2669811D02*
Y537198D01*
X2678545D01*
G01X2687530Y544489D02*
X2689058Y546531D01*
X2690368Y547698D01*
X2692115Y548281D01*
X2693643Y547698D01*
X2694735Y546531D01*
X2695608Y544781D01*
X2695826Y542740D01*
X2695608Y540989D01*
X2694735Y539239D01*
X2693424Y537781D01*
X2691896Y537198D01*
X2690150Y537781D01*
X2688621Y539531D01*
X2687748Y542156D01*
X2687530Y545073D01*
X2687966Y548864D01*
X2688621Y550907D01*
X2689713Y552948D01*
X2691241Y554406D01*
X2692770Y554698D01*
X2694298Y554115D01*
X2695390Y552656D01*
G01X2617311Y589348D02*
Y571848D01*
X2626045D01*
G01X2641798D02*
Y589348D01*
X2633719Y576806D01*
X2644637D01*
G01X2652748Y571265D02*
X2660608Y589348D01*
G01X2669811D02*
Y571848D01*
X2678545D01*
G01X2687530Y579139D02*
X2689058Y581181D01*
X2690368Y582348D01*
X2692115Y582931D01*
X2693643Y582348D01*
X2694735Y581181D01*
X2695608Y579431D01*
X2695826Y577390D01*
X2695608Y575639D01*
X2694735Y573889D01*
X2693424Y572431D01*
X2691896Y571848D01*
X2690150Y572431D01*
X2688621Y574181D01*
X2687748Y576806D01*
X2687530Y579723D01*
X2687966Y583514D01*
X2688621Y585557D01*
X2689713Y587598D01*
X2691241Y589056D01*
X2692770Y589348D01*
X2694298Y588765D01*
X2695390Y587306D01*
G01X2853228Y548864D02*
Y537198D01*
G01Y553531D02*
X2852791Y553823D01*
Y554406D01*
X2853228Y554698D01*
X2853665Y554406D01*
Y553823D01*
X2853228Y553531D01*
G01X2867016Y537198D02*
Y548864D01*
G01Y545948D02*
X2867890Y547406D01*
X2869200Y548573D01*
X2870946Y548864D01*
X2872474Y548573D01*
X2873785Y547406D01*
X2874440Y545365D01*
Y537198D01*
G01X2884953Y539239D02*
X2886045Y538073D01*
X2887573Y537198D01*
X2888883D01*
X2890193Y537781D01*
X2891066Y538656D01*
X2891503Y539822D01*
X2891285Y541573D01*
X2890411Y542448D01*
X2886481Y544198D01*
X2885608Y546240D01*
X2886045Y547698D01*
X2886918Y548573D01*
X2888228Y548864D01*
X2889538Y548573D01*
X2890848Y547698D01*
G01X2905728Y548864D02*
Y537198D01*
G01Y553531D02*
X2905291Y553823D01*
Y554406D01*
X2905728Y554698D01*
X2906165Y554406D01*
Y553823D01*
X2905728Y553531D01*
G01X2927158Y554698D02*
Y537198D01*
G01Y539822D02*
X2926285Y538364D01*
X2924974Y537490D01*
X2923446Y537198D01*
X2921700Y537781D01*
X2920390Y539239D01*
X2919516Y540989D01*
X2919298Y543031D01*
X2919516Y545073D01*
X2920390Y546823D01*
X2921700Y548281D01*
X2923446Y548864D01*
X2924974Y548573D01*
X2926066Y547989D01*
X2927158Y546823D01*
G01X2937453Y545073D02*
X2944440D01*
X2943785Y547115D01*
X2942693Y548281D01*
X2941165Y548864D01*
X2939636Y548573D01*
X2938326Y547698D01*
X2937453Y545656D01*
X2937016Y543906D01*
Y542156D01*
X2937453Y540406D01*
X2938545Y538656D01*
X2939855Y537490D01*
X2941383Y537198D01*
X2942911Y537781D01*
X2944440Y539531D01*
G01X2971798Y537198D02*
Y554698D01*
G01Y545948D02*
X2972890Y547698D01*
X2974200Y548573D01*
X2975510Y548864D01*
X2977474Y548281D01*
X2978785Y547115D01*
X2979658Y545073D01*
Y542740D01*
X2979221Y540406D01*
X2978348Y538656D01*
X2976820Y537490D01*
X2975510Y537198D01*
X2974200Y537490D01*
X2972890Y538364D01*
X2971798Y539822D01*
G01X2993228Y537198D02*
X2991918Y537490D01*
X2990608Y538656D01*
X2989734Y540698D01*
X2989298Y543031D01*
X2989734Y545365D01*
X2990608Y547406D01*
X2991918Y548573D01*
X2993228Y548864D01*
X2994538Y548573D01*
X2995848Y547406D01*
X2996721Y545365D01*
X2996940Y543031D01*
X2996721Y540698D01*
X2995848Y538656D01*
X2994538Y537490D01*
X2993228Y537198D01*
G01X3014658D02*
Y548864D01*
G01Y546823D02*
X3013785Y547989D01*
X3012474Y548573D01*
X3010946Y548864D01*
X3009418Y548281D01*
X3008108Y547115D01*
X3007234Y545365D01*
X3006798Y543031D01*
X3007234Y540698D01*
X3008108Y538948D01*
X3009418Y537781D01*
X3010946Y537198D01*
X3012474Y537490D01*
X3013785Y538364D01*
X3014658Y539531D01*
G01X3025171Y537198D02*
Y548864D01*
G01Y546531D02*
X3026263Y547698D01*
X3027355Y548573D01*
X3028883Y548864D01*
X3029974Y548573D01*
X3031285Y547698D01*
G01X3049658Y554698D02*
Y537198D01*
G01Y539822D02*
X3048785Y538364D01*
X3047474Y537490D01*
X3045946Y537198D01*
X3044200Y537781D01*
X3042890Y539239D01*
X3042016Y540989D01*
X3041798Y543031D01*
X3042016Y545073D01*
X3042890Y546823D01*
X3044200Y548281D01*
X3045946Y548864D01*
X3047474Y548573D01*
X3048566Y547989D01*
X3049658Y546823D01*
G01X3080728Y537198D02*
X3079418Y537490D01*
X3078108Y538656D01*
X3077234Y540698D01*
X3076798Y543031D01*
X3077234Y545365D01*
X3078108Y547406D01*
X3079418Y548573D01*
X3080728Y548864D01*
X3082038Y548573D01*
X3083348Y547406D01*
X3084221Y545365D01*
X3084440Y543031D01*
X3084221Y540698D01*
X3083348Y538656D01*
X3082038Y537490D01*
X3080728Y537198D01*
G01X3094516Y548864D02*
Y540698D01*
X3095390Y538656D01*
X3096700Y537490D01*
X3098228Y537198D01*
X3099756Y537490D01*
X3101066Y538656D01*
X3101940Y540698D01*
G01Y537198D02*
Y548864D01*
G01X3115728Y554698D02*
Y537198D01*
G01X3112671Y548864D02*
X3118785D01*
G01X3133228Y537198D02*
Y554698D01*
G01X3150728Y548864D02*
Y537198D01*
G01Y553531D02*
X3150291Y553823D01*
Y554406D01*
X3150728Y554698D01*
X3151165Y554406D01*
Y553823D01*
X3150728Y553531D01*
G01X3164516Y537198D02*
Y548864D01*
G01Y545948D02*
X3165390Y547406D01*
X3166700Y548573D01*
X3168446Y548864D01*
X3169974Y548573D01*
X3171285Y547406D01*
X3171940Y545365D01*
Y537198D01*
G01X3182453Y545073D02*
X3189440D01*
X3188785Y547115D01*
X3187693Y548281D01*
X3186165Y548864D01*
X3184636Y548573D01*
X3183326Y547698D01*
X3182453Y545656D01*
X3182016Y543906D01*
Y542156D01*
X3182453Y540406D01*
X3183545Y538656D01*
X3184855Y537490D01*
X3186383Y537198D01*
X3187911Y537781D01*
X3189440Y539531D01*
G01X3203228Y536615D02*
X3202791Y536906D01*
Y537490D01*
X3203228Y537781D01*
X3203665Y537490D01*
Y536906D01*
X3203228Y536615D01*
G01X2853228Y583514D02*
Y571848D01*
G01Y588181D02*
X2852791Y588473D01*
Y589056D01*
X2853228Y589348D01*
X2853665Y589056D01*
Y588473D01*
X2853228Y588181D01*
G01X2867453Y573889D02*
X2868545Y572723D01*
X2870073Y571848D01*
X2871383D01*
X2872693Y572431D01*
X2873566Y573306D01*
X2874003Y574472D01*
X2873785Y576223D01*
X2872911Y577098D01*
X2868981Y578848D01*
X2868108Y580890D01*
X2868545Y582348D01*
X2869418Y583223D01*
X2870728Y583514D01*
X2872038Y583223D01*
X2873348Y582348D01*
G01X2900706Y571848D02*
Y589348D01*
X2910750Y571848D01*
Y589348D01*
G01X2923228Y571848D02*
X2921481Y572140D01*
X2919953Y573306D01*
X2918643Y575056D01*
X2917769Y577098D01*
X2917333Y579431D01*
Y581765D01*
X2917769Y584098D01*
X2918643Y586140D01*
X2919953Y587889D01*
X2921481Y589056D01*
X2923228Y589348D01*
X2924974Y589056D01*
X2926503Y587889D01*
X2927813Y586140D01*
X2928687Y584098D01*
X2929123Y581765D01*
Y579431D01*
X2928687Y577098D01*
X2927813Y575056D01*
X2926503Y573306D01*
X2924974Y572140D01*
X2923228Y571848D01*
G01X2940728Y589348D02*
Y571848D01*
G01X2935706Y589348D02*
X2945750D01*
G01X2972016Y583514D02*
Y575348D01*
X2972890Y573306D01*
X2974200Y572140D01*
X2975728Y571848D01*
X2977256Y572140D01*
X2978566Y573306D01*
X2979440Y575348D01*
G01Y571848D02*
Y583514D01*
G01X2989953Y573889D02*
X2991045Y572723D01*
X2992573Y571848D01*
X2993883D01*
X2995193Y572431D01*
X2996066Y573306D01*
X2996503Y574472D01*
X2996285Y576223D01*
X2995411Y577098D01*
X2991481Y578848D01*
X2990608Y580890D01*
X2991045Y582348D01*
X2991918Y583223D01*
X2993228Y583514D01*
X2994538Y583223D01*
X2995848Y582348D01*
G01X3007453Y579723D02*
X3014440D01*
X3013785Y581765D01*
X3012693Y582931D01*
X3011165Y583514D01*
X3009636Y583223D01*
X3008326Y582348D01*
X3007453Y580306D01*
X3007016Y578556D01*
Y576806D01*
X3007453Y575056D01*
X3008545Y573306D01*
X3009855Y572140D01*
X3011383Y571848D01*
X3012911Y572431D01*
X3014440Y574181D01*
G01X3032158Y589348D02*
Y571848D01*
G01Y574472D02*
X3031285Y573014D01*
X3029974Y572140D01*
X3028446Y571848D01*
X3026700Y572431D01*
X3025390Y573889D01*
X3024516Y575639D01*
X3024298Y577681D01*
X3024516Y579723D01*
X3025390Y581473D01*
X3026700Y582931D01*
X3028446Y583514D01*
X3029974Y583223D01*
X3031066Y582639D01*
X3032158Y581473D01*
G01X3063228Y583514D02*
Y571848D01*
G01Y588181D02*
X3062791Y588473D01*
Y589056D01*
X3063228Y589348D01*
X3063665Y589056D01*
Y588473D01*
X3063228Y588181D01*
G01X3077016Y571848D02*
Y583514D01*
G01Y580598D02*
X3077890Y582056D01*
X3079200Y583223D01*
X3080946Y583514D01*
X3082474Y583223D01*
X3083785Y582056D01*
X3084440Y580015D01*
Y571848D01*
G01X3115728Y589348D02*
Y571848D01*
G01X3112671Y583514D02*
X3118785D01*
G01X3129516Y571848D02*
Y589348D01*
G01Y580890D02*
X3130608Y582348D01*
X3131700Y583223D01*
X3133446Y583514D01*
X3134756Y583223D01*
X3136285Y582056D01*
X3136940Y580306D01*
Y571848D01*
G01X3150728Y583514D02*
Y571848D01*
G01Y588181D02*
X3150291Y588473D01*
Y589056D01*
X3150728Y589348D01*
X3151165Y589056D01*
Y588473D01*
X3150728Y588181D01*
G01X3164953Y573889D02*
X3166045Y572723D01*
X3167573Y571848D01*
X3168883D01*
X3170193Y572431D01*
X3171066Y573306D01*
X3171503Y574472D01*
X3171285Y576223D01*
X3170411Y577098D01*
X3166481Y578848D01*
X3165608Y580890D01*
X3166045Y582348D01*
X3166918Y583223D01*
X3168228Y583514D01*
X3169538Y583223D01*
X3170848Y582348D01*
G01X3203228Y571848D02*
Y589348D01*
G01X3224658Y571848D02*
Y583514D01*
G01Y581473D02*
X3223785Y582639D01*
X3222474Y583223D01*
X3220946Y583514D01*
X3219418Y582931D01*
X3218108Y581765D01*
X3217234Y580015D01*
X3216798Y577681D01*
X3217234Y575348D01*
X3218108Y573598D01*
X3219418Y572431D01*
X3220946Y571848D01*
X3222474Y572140D01*
X3223785Y573014D01*
X3224658Y574181D01*
G01X3233643Y566598D02*
X3234953Y566015D01*
X3236700Y566598D01*
X3237791Y567764D01*
X3238665Y569223D01*
X3239974Y573889D01*
X3242813Y583514D01*
G01X3235826D02*
X3239974Y573889D01*
G01X3252453Y579723D02*
X3259440D01*
X3258785Y581765D01*
X3257693Y582931D01*
X3256165Y583514D01*
X3254636Y583223D01*
X3253326Y582348D01*
X3252453Y580306D01*
X3252016Y578556D01*
Y576806D01*
X3252453Y575056D01*
X3253545Y573306D01*
X3254855Y572140D01*
X3256383Y571848D01*
X3257911Y572431D01*
X3259440Y574181D01*
G01X3270171Y571848D02*
Y583514D01*
G01Y581181D02*
X3271263Y582348D01*
X3272355Y583223D01*
X3273883Y583514D01*
X3274974Y583223D01*
X3276285Y582348D01*
G01X2778425Y605915D02*
X2788031Y618748D01*
G01X2783228Y621081D02*
Y603581D01*
G01X2788031Y605915D02*
X2778425Y618748D01*
G01X2776678Y612331D02*
X2789778D01*
G01X2815390D02*
X2821066D01*
G01X2848425Y606498D02*
Y623998D01*
X2852791D01*
X2854538Y623123D01*
X2855848Y621956D01*
X2856940Y620207D01*
X2857813Y618164D01*
X2858031Y615248D01*
X2857813Y612331D01*
X2856940Y610289D01*
X2855848Y608539D01*
X2854538Y607373D01*
X2852791Y606498D01*
X2848425D01*
G01X2867453Y614373D02*
X2874440D01*
X2873785Y616415D01*
X2872693Y617581D01*
X2871165Y618164D01*
X2869636Y617873D01*
X2868326Y616998D01*
X2867453Y614956D01*
X2867016Y613206D01*
Y611456D01*
X2867453Y609706D01*
X2868545Y607956D01*
X2869855Y606790D01*
X2871383Y606498D01*
X2872911Y607081D01*
X2874440Y608831D01*
G01X2884516Y606498D02*
Y618164D01*
G01Y615248D02*
X2885390Y616706D01*
X2886700Y617873D01*
X2888446Y618164D01*
X2889974Y617873D01*
X2891285Y616706D01*
X2891940Y614665D01*
Y606498D01*
G01X2905728D02*
X2904418Y606790D01*
X2903108Y607956D01*
X2902234Y609998D01*
X2901798Y612331D01*
X2902234Y614665D01*
X2903108Y616706D01*
X2904418Y617873D01*
X2905728Y618164D01*
X2907038Y617873D01*
X2908348Y616706D01*
X2909221Y614665D01*
X2909440Y612331D01*
X2909221Y609998D01*
X2908348Y607956D01*
X2907038Y606790D01*
X2905728Y606498D01*
G01X2923228Y623998D02*
Y606498D01*
G01X2920171Y618164D02*
X2926285D01*
G01X2937453Y614373D02*
X2944440D01*
X2943785Y616415D01*
X2942693Y617581D01*
X2941165Y618164D01*
X2939636Y617873D01*
X2938326Y616998D01*
X2937453Y614956D01*
X2937016Y613206D01*
Y611456D01*
X2937453Y609706D01*
X2938545Y607956D01*
X2939855Y606790D01*
X2941383Y606498D01*
X2942911Y607081D01*
X2944440Y608831D01*
G01X2954953Y608539D02*
X2956045Y607373D01*
X2957573Y606498D01*
X2958883D01*
X2960193Y607081D01*
X2961066Y607956D01*
X2961503Y609122D01*
X2961285Y610873D01*
X2960411Y611748D01*
X2956481Y613498D01*
X2955608Y615540D01*
X2956045Y616998D01*
X2956918Y617873D01*
X2958228Y618164D01*
X2959538Y617873D01*
X2960848Y616998D01*
G01X2993228Y623998D02*
Y606498D01*
G01X2990171Y618164D02*
X2996285D01*
G01X3007016Y606498D02*
Y623998D01*
G01Y615540D02*
X3008108Y616998D01*
X3009200Y617873D01*
X3010946Y618164D01*
X3012256Y617873D01*
X3013785Y616706D01*
X3014440Y614956D01*
Y606498D01*
G01X3032158D02*
Y618164D01*
G01Y616123D02*
X3031285Y617289D01*
X3029974Y617873D01*
X3028446Y618164D01*
X3026918Y617581D01*
X3025608Y616415D01*
X3024734Y614665D01*
X3024298Y612331D01*
X3024734Y609998D01*
X3025608Y608248D01*
X3026918Y607081D01*
X3028446Y606498D01*
X3029974Y606790D01*
X3031285Y607664D01*
X3032158Y608831D01*
G01X3045728Y623998D02*
Y606498D01*
G01X3042671Y618164D02*
X3048785D01*
G01X3074178Y623998D02*
X3077234Y606498D01*
X3080728Y623998D01*
X3084221Y606498D01*
X3087278Y623998D01*
G01X3095608D02*
X3100848D01*
G01X3098228D02*
Y606498D01*
G01X3095608D02*
X3100848D01*
G01X3110925D02*
Y623998D01*
X3115291D01*
X3117038Y623123D01*
X3118348Y621956D01*
X3119440Y620207D01*
X3120313Y618164D01*
X3120531Y615248D01*
X3120313Y612331D01*
X3119440Y610289D01*
X3118348Y608539D01*
X3117038Y607373D01*
X3115291Y606498D01*
X3110925D01*
G01X3133228Y623998D02*
Y606498D01*
G01X3128206Y623998D02*
X3138250D01*
G01X3146143Y606498D02*
Y623998D01*
G01X3155313D02*
Y606498D01*
G01Y615248D02*
X3146143D01*
G01X-7874Y-31496D02*
X-19685D01*
G01X-7874D02*
X-19685D01*
G01D02*
G03X-23622Y-35433I0J-3937D01*
G01D02*
Y-59055D01*
G01Y-35433D02*
Y-59055D01*
G01X-19685Y-31496D02*
G03X-23622Y-35433I0J-3937D01*
G01Y-59055D02*
G03X-19685Y-62992I3937J0D01*
G01D02*
X1972441D01*
G01X-19685D02*
X1972441D01*
G01X-23622Y-59055D02*
G03X-19685Y-62992I3937J0D01*
G01Y-23622D02*
X1972441D01*
G01X-19685D02*
X1972441D01*
G01X-19685D02*
X1972441D01*
G01X-19685D02*
X1972441D01*
G01X-23622Y622441D02*
Y-19685D01*
G01Y622441D02*
Y-19685D01*
G01Y622441D02*
Y-19685D01*
G01Y622441D02*
Y-19685D01*
G01D02*
G03X-19685Y-23622I3937J0D01*
G01X-23622Y-19685D02*
G03X-19685Y-23622I3937J0D01*
G01X-23622Y-19685D02*
G03X-19685Y-23622I3937J0D01*
G01X-23622Y-19685D02*
G03X-19685Y-23622I3937J0D01*
G01X1972441Y626378D02*
X-19685D01*
G01X1972441D02*
X-19685D01*
G01X1972441D02*
X-19685D01*
G01X1972441D02*
X-19685D01*
G01D02*
G03X-23622Y622441I0J-3937D01*
G01X-19685Y626378D02*
G03X-23622Y622441I0J-3937D01*
G01X-19685Y626378D02*
G03X-23622Y622441I0J-3937D01*
G01X-19685Y626378D02*
G03X-23622Y622441I0J-3937D01*
G01X-19685Y634252D02*
X-7874D01*
G01X-19685D02*
X-7874D01*
G01X-23622Y661811D02*
Y638189D01*
G01Y661811D02*
Y638189D01*
G01D02*
G03X-19685Y634252I3937J0D01*
G01X-23622Y638189D02*
G03X-19685Y634252I3937J0D01*
G01X1972441Y665748D02*
X-19685D01*
G01X1972441D02*
X-19685D01*
G01D02*
G03X-23622Y661811I0J-3937D01*
G01X-19685Y665748D02*
G03X-23622Y661811I0J-3937D01*
G01X-7874Y-31496D02*
G03Y-23622I0J3937D01*
G01Y-31496D02*
G03Y-23622I0J3937D01*
G01X22835D02*
G03Y-31496I0J-3937D01*
G01X137795D02*
X22835D01*
G01X137795D02*
X22835D01*
G01Y-23622D02*
G03Y-31496I0J-3937D01*
G01X0Y616535D02*
G03Y604724I0J-5905D01*
G01Y616535D02*
G03Y604724I0J-5905D01*
G01Y616535D02*
X2646D01*
G01X2644D02*
X0D01*
G01Y604724D02*
X2644D01*
G01X2646D02*
X0D01*
G01X2646D02*
X0D01*
G01D02*
X2644D01*
G01Y616535D02*
X0D01*
G01D02*
X2646D01*
G01X0D02*
G03Y604724I0J-5905D01*
G01Y616535D02*
G03Y604724I0J-5905D01*
G01X2646Y616535D02*
G03X7595Y618285I0J7874D01*
G01X2644Y616535D02*
G03X7593Y618285I0J7874D01*
G01X2644Y616535D02*
G03X7593Y618285I0J7874D01*
G01X7595Y602975D02*
G03X2646Y604724I-4948J-6125D01*
G01X7593Y602975D02*
G03X2644Y604724I-4948J-6125D01*
G01X7593Y602975D02*
G03X2644Y604724I-4948J-6125D01*
G01X7593Y602975D02*
G03X2644Y604724I-4948J-6125D01*
G01X7593Y602975D02*
G03X2644Y604724I-4948J-6125D01*
G01X7595Y602975D02*
G03X2646Y604724I-4948J-6125D01*
G01X2644Y616535D02*
G03X7593Y618285I0J7874D01*
G01X2644Y616535D02*
G03X7593Y618285I0J7874D01*
G01X2646Y616535D02*
G03X7595Y618285I0J7874D01*
G01Y602975D02*
G03Y618285I6186J7655D01*
G01X7593Y602975D02*
G03Y618285I6187J7655D01*
G01Y602975D02*
G03Y618285I6187J7655D01*
G01Y602975D02*
G03Y618285I6187J7655D01*
G01Y602975D02*
G03Y618285I6187J7655D01*
G01X7595Y602975D02*
G03Y618285I6186J7655D01*
G01X-7874Y626378D02*
G03Y634252I0J3937D01*
G01Y626378D02*
G03Y634252I0J3937D01*
G01X22835D02*
G03Y626378I0J-3937D01*
G01Y634252D02*
X137795D01*
G01X22835D02*
X137795D01*
G01X22835D02*
G03Y626378I0J-3937D01*
G01X168504Y-23622D02*
G03Y-31496I0J-3937D01*
G01X137795D02*
G03Y-23622I0J3937D01*
G01X341732Y-31496D02*
X168504D01*
G01X341732D02*
X168504D01*
G01X137795D02*
G03Y-23622I0J3937D01*
G01X168504D02*
G03Y-31496I0J-3937D01*
G01Y634252D02*
G03Y626378I0J-3937D01*
G01X137795D02*
G03Y634252I0J3937D01*
G01X168504D02*
X341732D01*
G01X168504D02*
X341732D01*
G01X137795Y626378D02*
G03Y634252I0J3937D01*
G01X168504D02*
G03Y626378I0J-3937D01*
G01X341732Y-31496D02*
G03Y-23622I0J3937D01*
G01Y-31496D02*
G03Y-23622I0J3937D01*
G01Y626378D02*
G03Y634252I0J3937D01*
G01Y626378D02*
G03Y634252I0J3937D01*
G01X372441Y-23622D02*
G03Y-31496I0J-3937D01*
G01X529921D02*
X372441D01*
G01X529921D02*
X372441D01*
G01Y-23622D02*
G03Y-31496I0J-3937D01*
G01Y634252D02*
G03Y626378I0J-3937D01*
G01Y634252D02*
X529921D01*
G01X372441D02*
X529921D01*
G01X372441D02*
G03Y626378I0J-3937D01*
G01X529921Y-31496D02*
G03Y-23622I0J3937D01*
G01Y-31496D02*
G03Y-23622I0J3937D01*
G01Y626378D02*
G03Y634252I0J3937D01*
G01Y626378D02*
G03Y634252I0J3937D01*
G01X560630Y-23622D02*
G03Y-31496I0J-3937D01*
G01X788976D02*
X560630D01*
G01X788976D02*
X560630D01*
G01Y-23622D02*
G03Y-31496I0J-3937D01*
G01Y634252D02*
G03Y626378I0J-3937D01*
G01Y634252D02*
X788976D01*
G01X560630D02*
X788976D01*
G01X560630D02*
G03Y626378I0J-3937D01*
G01X684760Y-15529D02*
G03Y-219I6187J7655D01*
G01X684759Y-15529D02*
G03X679809Y-13780I-4948J-6125D01*
G01X679811Y-1969D02*
G03X684760Y-219I0J7874D01*
G01X677165Y-1969D02*
X679811D01*
G01X677165D02*
G03Y-13780I0J-5906D01*
G01D02*
X679809D01*
G01X684760Y602975D02*
G03Y618285I6187J7655D01*
G01X684759Y602975D02*
G03Y618285I6186J7655D01*
G01Y602975D02*
G03Y618285I6186J7655D01*
G01Y602975D02*
G03Y618285I6186J7655D01*
G01Y602975D02*
G03Y618285I6186J7655D01*
G01X684760Y602975D02*
G03Y618285I6187J7655D01*
G01X679811Y616535D02*
G03X684760Y618285I0J7874D01*
G01X679809Y616535D02*
G03X684759Y618285I0J7874D01*
G01X679809Y616535D02*
G03X684759Y618285I0J7874D01*
G01X684760Y602975D02*
G03X679811Y604724I-4948J-6125D01*
G01X684759Y602975D02*
G03X679809Y604724I-4948J-6125D01*
G01X684759Y602975D02*
G03X679809Y604724I-4948J-6125D01*
G01X684759Y602975D02*
G03X679809Y604724I-4948J-6125D01*
G01X684759Y602975D02*
G03X679809Y604724I-4948J-6125D01*
G01X684760Y602975D02*
G03X679811Y604724I-4948J-6125D01*
G01X679809Y616535D02*
G03X684759Y618285I0J7874D01*
G01X679809Y616535D02*
G03X684759Y618285I0J7874D01*
G01X679811Y616535D02*
G03X684760Y618285I0J7874D01*
G01X677165Y616535D02*
X679811D01*
G01X677165D02*
G03Y604724I0J-5905D01*
G01D02*
X679809D01*
G01X788976Y-31496D02*
G03Y-23622I0J3937D01*
G01Y-31496D02*
G03Y-23622I0J3937D01*
G01X819685D02*
G03Y-31496I0J-3937D01*
G01X975591D02*
X819685D01*
G01X975591D02*
X819685D01*
G01Y-23622D02*
G03Y-31496I0J-3937D01*
G01X788976Y626378D02*
G03Y634252I0J3937D01*
G01Y626378D02*
G03Y634252I0J3937D01*
G01X819685D02*
G03Y626378I0J-3937D01*
G01Y634252D02*
X975591D01*
G01X819685D02*
X975591D01*
G01X819685D02*
G03Y626378I0J-3937D01*
G01X975591Y-31496D02*
G03Y-23622I0J3937D01*
G01Y-31496D02*
G03Y-23622I0J3937D01*
G01X1006299D02*
G03Y-31496I0J-3937D01*
G01X1162205D02*
X1006299D01*
G01X1162205D02*
X1006299D01*
G01Y-23622D02*
G03Y-31496I0J-3937D01*
G01Y634252D02*
X1162205D01*
G01X1006299D02*
X1162205D01*
G01X975591Y626378D02*
G03Y634252I0J3937D01*
G01Y626378D02*
G03Y634252I0J3937D01*
G01X1006299D02*
G03Y626378I0J-3937D01*
G01Y634252D02*
G03Y626378I0J-3937D01*
G01X1162205Y-31496D02*
G03Y-23622I0J3937D01*
G01Y-31496D02*
G03Y-23622I0J3937D01*
G01X1192913D02*
G03Y-31496I0J-3937D01*
G01X1398425D02*
X1192913D01*
G01X1398425D02*
X1192913D01*
G01Y-23622D02*
G03Y-31496I0J-3937D01*
G01Y634252D02*
X1394488D01*
G01X1192913D02*
X1394488D01*
G01X1162205Y626378D02*
G03Y634252I0J3937D01*
G01Y626378D02*
G03Y634252I0J3937D01*
G01X1192913D02*
G03Y626378I0J-3937D01*
G01Y634252D02*
G03Y626378I0J-3937D01*
G01X1398425Y-31496D02*
G03Y-23622I0J3937D01*
G01Y-31496D02*
G03Y-23622I0J3937D01*
G01X1405512Y-1968D02*
G03Y-13779I0J-5906D01*
G01Y-1968D02*
G03Y-13779I0J-5906D01*
G01Y-1968D02*
G03Y-13779I0J-5906D01*
G01Y-1968D02*
G03Y-13779I0J-5906D01*
G01X1394488Y626378D02*
G03Y634252I0J3937D01*
G01Y626378D02*
G03Y634252I0J3937D01*
G01X1405512Y616535D02*
G03Y604724I0J-5905D01*
G01Y616535D02*
G03Y604724I0J-5905D01*
G01Y616535D02*
G03Y604724I0J-5905D01*
G01Y616535D02*
G03Y604724I0J-5905D01*
G01X1429134Y-23622D02*
G03Y-31496I0J-3937D01*
G01X1851181D02*
X1429134D01*
G01X1851181D02*
X1429134D01*
G01Y-23622D02*
G03Y-31496I0J-3937D01*
G01X1413107Y-15529D02*
G03Y-218I6186J7655D01*
G01X1413105Y-15529D02*
G03Y-218I6186J7655D01*
G01Y-15529D02*
G03Y-218I6186J7655D01*
G01Y-15529D02*
G03Y-218I6186J7655D01*
G01Y-15529D02*
G03Y-218I6186J7655D01*
G01X1413107Y-15529D02*
G03Y-218I6186J7655D01*
G01X1408157Y-1968D02*
G03X1413107Y-218I1J7874D01*
G01X1408156Y-1968D02*
G03X1413105Y-218I0J7874D01*
G01X1408156Y-1968D02*
G03X1413105Y-218I0J7874D01*
G01X1408156Y-1968D02*
G03X1413105Y-218I0J7874D01*
G01X1408156Y-1968D02*
G03X1413105Y-218I0J7874D01*
G01X1408157Y-1968D02*
G03X1413107Y-218I1J7874D01*
G01Y-15529D02*
G03X1408157Y-13779I-4949J-6124D01*
G01X1413105Y-15529D02*
G03X1408156Y-13779I-4949J-6124D01*
G01X1413105Y-15529D02*
G03X1408156Y-13779I-4949J-6124D01*
G01X1413105Y-15529D02*
G03X1408156Y-13779I-4949J-6124D01*
G01X1413105Y-15529D02*
G03X1408156Y-13779I-4949J-6124D01*
G01X1413107Y-15529D02*
G03X1408157Y-13779I-4949J-6124D01*
G01X1405512D02*
X1408156D01*
G01X1408157D02*
X1405512D01*
G01X1408157D02*
X1405512D01*
G01D02*
X1408156D01*
G01X1405512Y-1968D02*
X1408157D01*
G01X1408156D02*
X1405512D01*
G01X1408156D02*
X1405512D01*
G01D02*
X1408157D01*
G01X1425197Y634252D02*
X1851181D01*
G01X1425197D02*
X1851181D01*
G01X1425197D02*
G03Y626378I0J-3937D01*
G01Y634252D02*
G03Y626378I0J-3937D01*
G01X1408157Y616535D02*
G03X1413107Y618285I1J7874D01*
G01X1408156Y616535D02*
G03X1413105Y618285I0J7874D01*
G01X1408156Y616535D02*
G03X1413105Y618285I0J7874D01*
G01X1413107Y602975D02*
G03Y618285I6186J7655D01*
G01X1413105Y602975D02*
G03Y618285I6187J7655D01*
G01Y602975D02*
G03Y618285I6187J7655D01*
G01X1413107Y602975D02*
G03X1408157Y604724I-4948J-6125D01*
G01X1413105Y602975D02*
G03X1408156Y604724I-4948J-6125D01*
G01X1413105Y602975D02*
G03X1408156Y604724I-4948J-6125D01*
G01X1413105Y602975D02*
G03X1408156Y604724I-4948J-6125D01*
G01X1413105Y602975D02*
G03X1408156Y604724I-4948J-6125D01*
G01X1413107Y602975D02*
G03X1408157Y604724I-4948J-6125D01*
G01X1413105Y602975D02*
G03Y618285I6187J7655D01*
G01Y602975D02*
G03Y618285I6187J7655D01*
G01X1413107Y602975D02*
G03Y618285I6186J7655D01*
G01X1408156Y616535D02*
G03X1413105Y618285I0J7874D01*
G01X1408156Y616535D02*
G03X1413105Y618285I0J7874D01*
G01X1408157Y616535D02*
G03X1413107Y618285I1J7874D01*
G01X1405512Y616535D02*
X1408157D01*
G01X1408156D02*
X1405512D01*
G01Y604724D02*
X1408156D01*
G01X1408157D02*
X1405512D01*
G01X1408157D02*
X1405512D01*
G01D02*
X1408156D01*
G01Y616535D02*
X1405512D01*
G01D02*
X1408157D01*
G01X1685866Y267244D02*
X1883780D01*
G01X1685866D02*
X1883780D01*
G01X1685866D02*
X1883780D01*
G01X1685866D02*
X1883780D01*
G01X1681929Y271181D02*
G03X1685866Y267244I3937J0D01*
G01X1681929Y271181D02*
G03X1685866Y267244I3937J0D01*
G01X1681929Y271181D02*
G03X1685866Y267244I3937J0D01*
G01X1681929Y271181D02*
G03X1685866Y267244I3937J0D01*
G01X1681929Y428661D02*
Y271181D01*
G01Y428661D02*
Y271181D01*
G01Y428661D02*
Y271181D01*
G01Y428661D02*
Y271181D01*
G01X1685866Y432598D02*
G03X1681929Y428661I0J-3937D01*
G01X1685866Y432598D02*
G03X1681929Y428661I0J-3937D01*
G01X1972441Y432598D02*
X1685866D01*
G01X1972441D02*
X1685866D01*
G01X1972441D02*
X1685866D01*
G01X1972441D02*
X1685866D01*
G01D02*
G03X1681929Y428661I0J-3937D01*
G01X1685866Y432598D02*
G03X1681929Y428661I0J-3937D01*
G01X1851181Y-31496D02*
G03Y-23622I0J3937D01*
G01Y-31496D02*
G03Y-23622I0J3937D01*
G01X1881890D02*
G03Y-31496I0J-3937D01*
G01X1972441D02*
X1881890D01*
G01X1972441D02*
X1881890D01*
G01Y-23622D02*
G03Y-31496I0J-3937D01*
G01X1861926Y-15529D02*
G03X1856976Y-13780I-4948J-6125D01*
G01X1861924Y-15529D02*
G03X1856975Y-13780I-4948J-6125D01*
G01X1861924Y-15529D02*
G03X1856975Y-13780I-4948J-6125D01*
G01X1861924Y-15529D02*
G03X1856975Y-13780I-4948J-6125D01*
G01X1861924Y-15529D02*
G03X1856975Y-13780I-4948J-6125D01*
G01X1861926Y-15529D02*
G03X1856976Y-13780I-4948J-6125D01*
G01Y-1969D02*
G03X1861926Y-219I0J7874D01*
G01X1856975Y-1969D02*
G03X1861924Y-219I0J7874D01*
G01X1856975Y-1969D02*
G03X1861924Y-219I0J7874D01*
G01X1861926Y-15529D02*
G03Y-219I6186J7655D01*
G01X1861924Y-15529D02*
G03Y-219I6186J7655D01*
G01Y-15529D02*
G03Y-219I6186J7655D01*
G01Y-15529D02*
G03Y-219I6186J7655D01*
G01Y-15529D02*
G03Y-219I6186J7655D01*
G01X1861926Y-15529D02*
G03Y-219I6186J7655D01*
G01X1856975Y-1969D02*
G03X1861924Y-219I0J7874D01*
G01X1856975Y-1969D02*
G03X1861924Y-219I0J7874D01*
G01X1856976Y-1969D02*
G03X1861926Y-219I0J7874D01*
G01X1854331Y-1969D02*
G03Y-13780I0J-5906D01*
G01Y-1969D02*
G03Y-13780I0J-5906D01*
G01D02*
X1856975D01*
G01X1856976D02*
X1854331D01*
G01X1856976D02*
X1854331D01*
G01D02*
X1856975D01*
G01X1854331Y-1969D02*
G03Y-13780I0J-5906D01*
G01Y-1969D02*
G03Y-13780I0J-5906D01*
G01Y-1969D02*
X1856976D01*
G01X1856975D02*
X1854331D01*
G01X1856975D02*
X1854331D01*
G01D02*
X1856976D01*
G01X1891654Y246772D02*
X1972441D01*
G01X1891654D02*
X1972441D01*
G01X1891654D02*
X1972441D01*
G01X1891654D02*
X1972441D01*
G01X1887717Y250709D02*
G03X1891654Y246772I3937J0D01*
G01X1887717Y250709D02*
G03X1891654Y246772I3937J0D01*
G01X1887717Y263307D02*
Y250709D01*
G01Y263307D02*
Y250709D01*
G01Y263307D02*
Y250709D01*
G01Y263307D02*
Y250709D01*
G01D02*
G03X1891654Y246772I3937J0D01*
G01X1887717Y250709D02*
G03X1891654Y246772I3937J0D01*
G01X1887717Y263307D02*
G03X1883780Y267244I-3937J0D01*
G01X1887717Y263307D02*
G03X1883780Y267244I-3937J0D01*
G01X1887717Y263307D02*
G03X1883780Y267244I-3937J0D01*
G01X1887717Y263307D02*
G03X1883780Y267244I-3937J0D01*
G01X1881890Y634252D02*
G03Y626378I0J-3937D01*
G01Y634252D02*
X1972441D01*
G01X1881890D02*
X1972441D01*
G01X1881890D02*
G03Y626378I0J-3937D01*
G01X1851181D02*
G03Y634252I0J3937D01*
G01Y626378D02*
G03Y634252I0J3937D01*
G01X1856976Y616535D02*
G03X1861926Y618285I0J7874D01*
G01X1856975Y616535D02*
G03X1861924Y618285I0J7874D01*
G01X1856975Y616535D02*
G03X1861924Y618285I0J7874D01*
G01X1861926Y602975D02*
G03Y618285I6186J7655D01*
G01X1861924Y602975D02*
G03Y618285I6186J7655D01*
G01Y602975D02*
G03Y618285I6186J7655D01*
G01Y602975D02*
G03Y618285I6186J7655D01*
G01Y602975D02*
G03Y618285I6186J7655D01*
G01X1861926Y602975D02*
G03Y618285I6186J7655D01*
G01X1856975Y616535D02*
G03X1861924Y618285I0J7874D01*
G01X1856975Y616535D02*
G03X1861924Y618285I0J7874D01*
G01X1856976Y616535D02*
G03X1861926Y618285I0J7874D01*
G01Y602975D02*
G03X1856976Y604724I-4948J-6125D01*
G01X1861924Y602975D02*
G03X1856975Y604724I-4948J-6125D01*
G01X1861924Y602975D02*
G03X1856975Y604724I-4948J-6125D01*
G01X1861924Y602975D02*
G03X1856975Y604724I-4948J-6125D01*
G01X1861924Y602975D02*
G03X1856975Y604724I-4948J-6125D01*
G01X1861926Y602975D02*
G03X1856976Y604724I-4948J-6125D01*
G01X1854331Y616535D02*
G03Y604724I0J-5905D01*
G01Y616535D02*
G03Y604724I0J-5905D01*
G01D02*
X1856975D01*
G01X1856976D02*
X1854331D01*
G01X1856976D02*
X1854331D01*
G01D02*
X1856975D01*
G01X1854331Y616535D02*
G03Y604724I0J-5905D01*
G01Y616535D02*
G03Y604724I0J-5905D01*
G01Y616535D02*
X1856976D01*
G01X1856975D02*
X1854331D01*
G01X1856975D02*
X1854331D01*
G01D02*
X1856976D01*
G01X1972441Y-11811D02*
X1906890D01*
G01X1904921Y-9843D02*
G03X1906890Y-11811I1969J1D01*
G01X1904921Y53150D02*
Y-9843D01*
G01X1972441Y-11811D02*
X1906890D01*
G01X1904921Y-9843D02*
G03X1906890Y-11811I1969J1D01*
G01X1904921Y53150D02*
Y-9843D01*
G01X1923071Y53150D02*
Y-9843D01*
G01X1940787Y-3937D02*
X1972441D01*
G01X1940787D02*
G03X1938819Y-5906I0J-1968D01*
G01Y-9843D02*
Y-5906D01*
G01Y-9843D02*
G03X1940787Y-11811I1968J0D01*
G01X1921102D02*
G03X1923071Y-9843I0J1969D01*
G01X1906890Y55118D02*
G03X1904921Y53150I0J-1969D01*
G01X1972441Y55118D02*
X1906890D01*
G01X1972441D02*
X1906890D01*
G01X1972441D02*
X1906890D01*
G01X1972441D02*
X1906890D01*
G01D02*
G03X1904921Y53150I0J-1969D01*
G01X1923071D02*
G03X1921102Y55118I-1969J-1D01*
G01X1940787D02*
G03X1938819Y53150I0J-1968D01*
G01Y49213D02*
Y53150D01*
G01Y49213D02*
G03X1940787Y47244I1968J-1D01*
G01X1972441D02*
X1940787D01*
G01X1976378Y-35433D02*
G03X1972441Y-31496I-3937J0D01*
G01X1976378Y-59055D02*
Y-35433D01*
G01Y-59055D02*
Y-35433D01*
G01D02*
G03X1972441Y-31496I-3937J0D01*
G01Y-62992D02*
G03X1976378Y-59055I0J3937D01*
G01X1972441Y-62992D02*
G03X1976378Y-59055I0J3937D01*
G01X1972441Y-23622D02*
G03X1976378Y-19685I0J3937D01*
G01X1972441Y-23622D02*
G03X1976378Y-19685I0J3937D01*
G01X1972441Y-23622D02*
G03X1976378Y-19685I0J3937D01*
G01X1972441Y-23622D02*
G03X1976378Y-19685I0J3937D01*
G01D02*
Y-15748D01*
G01Y-19685D02*
Y-15748D01*
G01Y-19685D02*
Y-15748D01*
G01Y-19685D02*
Y-15748D01*
G01D02*
G03X1972441Y-11811I-3937J0D01*
G01X1976378Y-15748D02*
G03X1972441Y-11811I-3937J0D01*
G01X1976378Y-15748D02*
G03X1972441Y-11811I-3937J0D01*
G01X1976378Y-15748D02*
G03X1972441Y-11811I-3937J0D01*
G01X1976378Y0D02*
Y43307D01*
G01X1972441Y-3937D02*
G03X1976378Y0I0J3937D01*
G01X1972441Y55118D02*
G03X1976378Y59055I0J3937D01*
G01X1972441Y55118D02*
G03X1976378Y59055I0J3937D01*
G01X1972441Y55118D02*
G03X1976378Y59055I0J3937D01*
G01X1972441Y55118D02*
G03X1976378Y59055I0J3937D01*
G01D02*
Y242835D01*
G01Y59055D02*
Y242835D01*
G01Y59055D02*
Y242835D01*
G01Y59055D02*
Y242835D01*
G01Y43307D02*
G03X1972441Y47244I-3937J0D01*
G01X1976378Y242835D02*
G03X1972441Y246772I-3937J0D01*
G01X1976378Y242835D02*
G03X1972441Y246772I-3937J0D01*
G01X1976378Y242835D02*
G03X1972441Y246772I-3937J0D01*
G01X1976378Y242835D02*
G03X1972441Y246772I-3937J0D01*
G01Y432598D02*
G03X1976378Y436535I0J3937D01*
G01X1972441Y432598D02*
G03X1976378Y436535I0J3937D01*
G01X1972441Y432598D02*
G03X1976378Y436535I0J3937D01*
G01X1972441Y432598D02*
G03X1976378Y436535I0J3937D01*
G01D02*
Y622441D01*
G01Y436535D02*
Y622441D01*
G01Y436535D02*
Y622441D01*
G01Y436535D02*
Y622441D01*
G01D02*
G03X1972441Y626378I-3937J0D01*
G01X1976378Y622441D02*
G03X1972441Y626378I-3937J0D01*
G01X1976378Y622441D02*
G03X1972441Y626378I-3937J0D01*
G01X1976378Y622441D02*
G03X1972441Y626378I-3937J0D01*
G01Y634252D02*
G03X1976378Y638189I0J3937D01*
G01X1972441Y634252D02*
G03X1976378Y638189I0J3937D01*
G01D02*
Y661811D01*
G01Y638189D02*
Y661811D01*
G01D02*
G03X1972441Y665748I-3937J0D01*
G01X1976378Y661811D02*
G03X1972441Y665748I-3937J0D01*
G54D12*
G01X285119Y183292D02*
X297258Y195431D01*
G01X285119Y182551D02*
Y183292D01*
G01X283460Y208060D02*
X284759Y211060D01*
G01X283394Y207946D02*
X283460Y208060D01*
G01X283394Y206372D02*
G02Y207946I1365J787D01*
G01X283800Y205909D02*
G02X283394Y206372I959J1250D01*
G01X285711Y204533D02*
X283800Y205909D01*
G01X285953Y204344D02*
X285711Y204533D01*
G01X286124Y204047D02*
X285953Y204344D01*
G01X286143Y204013D02*
X286124Y204047D01*
G01Y202472D02*
G03X286143Y204013I-1365J787D01*
G01X284840Y201686D02*
G03X286124Y202472I-81J1574D01*
G01X284689Y201686D02*
X284840D01*
G01X282744Y200523D02*
G02X284689Y201686I2015J-1162D01*
G01X281438Y199735D02*
G03X282744Y200523I-59J1574D01*
G01X281320Y199735D02*
X281438D01*
G01X280439Y200045D02*
G03X281320Y199735I940J1264D01*
G01X278348Y200935D02*
X280439Y200045D01*
G01X277940Y200935D02*
X278348D01*
G01X276634Y200147D02*
G02X277940Y200935I1365J-786D01*
G01X276032Y199110D02*
X276634Y200147D01*
G01X269924Y193003D02*
X276032Y199110D01*
G01X268330Y193003D02*
X269924D01*
G01X262544Y187217D02*
X268330Y193003D01*
G01X262544Y186099D02*
Y187217D01*
G01X256447Y191656D02*
X255292Y190501D01*
G01X257683Y191656D02*
X256447D01*
G01X263136Y197109D02*
X257683Y191656D01*
G01X267797Y197109D02*
X263136D01*
G01X271852Y201164D02*
X267797Y197109D01*
G01X272606Y202471D02*
X271852Y201164D01*
G01X272604Y202472D02*
X272606Y202471D01*
G01X274568Y203635D02*
G03X272604Y202472I51J-2326D01*
G01X274663Y203635D02*
X274568D01*
G01X275984Y204423D02*
G02X274663Y203635I-1365J787D01*
G01X277914Y205585D02*
G03X275984Y204423I85J-2325D01*
G01X278651Y205585D02*
X277914D01*
G01X279932Y205437D02*
X278651Y205585D01*
G01X281379Y205210D02*
X279932Y205437D01*
G01X292884Y207948D02*
X291519Y211060D01*
G01X293071Y206891D02*
G03X292884Y207948I-1552J270D01*
G01X286430Y188891D02*
X293248Y195709D01*
G01X283519Y188891D02*
X286430D01*
G01X281634Y187006D02*
X283519Y188891D01*
G01X281634Y186145D02*
Y187006D01*
G01X282533Y208444D02*
X281379Y209109D01*
G01X282627Y208092D02*
X282533Y208444D01*
G01X282719Y206039D02*
G02X282627Y208092I2039J1120D01*
G01X282744Y205997D02*
G02X282719Y206039I594J382D01*
G01X280427Y203955D02*
G03X282744Y205997I952J1255D01*
G01X279191Y204588D02*
X280427Y203955D01*
G01X278654Y204784D02*
X279191Y204588D01*
G01X278248Y204834D02*
X278654Y204784D01*
G01X277928Y204834D02*
X278248D01*
G01X276634Y204047D02*
G02X277928Y204834I1365J-787D01*
G01X274670Y202884D02*
G03X276634Y204047I-51J2326D01*
G01X274560Y202884D02*
X274670D01*
G01X273254Y202097D02*
G02X274560Y202884I1365J-788D01*
G01X272451Y200705D02*
X273254Y202097D01*
G01X268106Y196360D02*
X272451Y200705D01*
G01X263447Y196360D02*
X268106D01*
G01X259116Y192029D02*
X263447Y196360D01*
G01X258209Y191122D02*
X259116Y192029D01*
G01X258209Y188367D02*
Y191122D01*
G01X279844Y217444D02*
G03X280039Y219980I-1845J1417D01*
G01X279800Y217138D02*
X279844Y217444D01*
G01X279799Y216900D02*
X279800Y217138D01*
G01X279799Y215372D02*
Y216900D01*
G01X275887Y215490D02*
X275397Y215000D01*
G01X276078Y215951D02*
G02X275887Y215490I-652J0D01*
G01X276078Y216005D02*
Y215951D01*
G01X276279Y216525D02*
G03X276078Y216005I572J-520D01*
G01X277929Y217285D02*
G03X276279Y216525I71J-2325D01*
G01X278058Y217285D02*
X277929D01*
G01X279383Y219613D02*
G02X278058Y217285I-1384J-753D01*
G01X281525Y187958D02*
X279911D01*
G01X283208Y189641D02*
X281525Y187958D01*
G01X286119Y189641D02*
X283208D01*
G01X292498Y196020D02*
X286119Y189641D01*
G01X292498Y197904D02*
Y196020D01*
G01X292884Y198572D02*
X292498Y197904D01*
G01X292903Y200113D02*
G02X292884Y198572I-1384J-754D01*
G01Y200147D02*
X292903Y200113D01*
G01X292859Y200189D02*
X292884Y200147D01*
G01Y202472D02*
G03X292859Y200189I2015J-1164D01*
G01X292990Y202694D02*
G02X292884Y202472I-1445J554D01*
G01X292850Y203260D02*
X293078Y203032D01*
G01X291519Y203260D02*
X292850D01*
G01X273481Y218484D02*
X272608Y217611D01*
G01X262123Y187856D02*
X260786D01*
G01X268019Y193752D02*
X262123Y187856D01*
G01X269612Y193752D02*
X268019D01*
G01X269613Y193751D02*
X269612Y193752D01*
G01X269614Y193751D02*
X269613D01*
G01X275433Y199570D02*
X269614Y193751D01*
G01X275984Y200523D02*
X275433Y199570D01*
G01X277929Y201686D02*
G03X275984Y200523I70J-2325D01*
G01X278548Y201686D02*
X277929D01*
G01X280429Y202566D02*
G02X278548Y201686I-3004J3970D01*
G01X281320Y202884D02*
G03X280429Y202566I60J-1575D01*
G01X281515Y202884D02*
X281320D01*
G01X284759Y203260D02*
X281515Y202884D01*
G01X285159Y184392D02*
X283417D01*
G01X296508Y195741D02*
X285159Y184392D01*
G01X274765Y262134D02*
X277999Y261760D01*
G01X274534Y262134D02*
X274765D01*
G01X272604Y260972D02*
G02X274534Y262134I2015J-1163D01*
G01X271298Y260185D02*
G03X272604Y260972I-59J1575D01*
G01X271169Y260185D02*
X271298D01*
G01X269224Y259022D02*
G02X271169Y260185I2015J-1162D01*
G01X267903Y258234D02*
G03X269224Y259022I-44J1575D01*
G01X267059Y258234D02*
X267903D01*
G01X265687Y257061D02*
G02X267059Y258234I2172J-1152D01*
G01X264836Y256285D02*
G03X265687Y257061I-657J1575D01*
G01X261381Y256285D02*
X264836D01*
G01X254681Y249585D02*
X261381Y256285D01*
G01X253695Y249585D02*
X254681D01*
G01X284901Y248485D02*
X288139Y248109D01*
G01X284700Y248485D02*
X284901D01*
G01X283394Y249272D02*
G03X284700Y248485I1365J788D01*
G01X281464Y250434D02*
G02X283394Y249272I-85J-2325D01*
G01X281335Y250434D02*
X281464D01*
G01X280014Y251222D02*
G03X281335Y250434I1365J787D01*
G01X278069Y252385D02*
G02X280014Y251222I-70J-2325D01*
G01X277940Y252385D02*
X278069D01*
G01X277023Y252723D02*
G03X277940Y252385I977J1237D01*
G01X275873Y253297D02*
X277023Y252723D01*
G01X274998Y253584D02*
X275873Y253297D01*
G01X274560Y253584D02*
X274998D01*
G01X273254Y252797D02*
G02X274560Y253584I1365J-788D01*
G01X271324Y251635D02*
G03X273254Y252797I-85J2325D01*
G01X271195Y251635D02*
X271324D01*
G01X269874Y250847D02*
G02X271195Y251635I1365J-787D01*
G01X267929Y249684D02*
G03X269874Y250847I-70J2325D01*
G01X267800Y249684D02*
X267929D01*
G01X266494Y248897D02*
G02X267800Y249684I1365J-788D01*
G01X264564Y247735D02*
G03X266494Y248897I-85J2325D01*
G01X263242Y247735D02*
X264564D01*
G01X262518Y247011D02*
X263242Y247735D01*
G01X262518Y239861D02*
Y247011D01*
G01X261473Y238816D02*
X262518Y239861D01*
G01X261473Y237484D02*
Y238816D01*
G01X286190Y246831D02*
X288139Y244209D01*
G01X286124Y246947D02*
X286190Y246831D01*
G01X284803Y247735D02*
G02X286124Y246947I-44J-1575D01*
G01X284453Y247735D02*
X284803D01*
G01X283993Y247656D02*
G02X284453Y247735I461J-1304D01*
G01X282426Y246817D02*
X283993Y247656D01*
G01X281848Y246534D02*
X282426Y246817D01*
G01X281335Y246534D02*
X281848D01*
G01X280014Y247322D02*
G03X281335Y246534I1365J787D01*
G01X278069Y248485D02*
G02X280014Y247322I-70J-2325D01*
G01X277940Y248485D02*
X278069D01*
G01X276928Y248904D02*
G03X277940Y248485I1071J1156D01*
G01X276696Y249136D02*
X276928Y248904D01*
G01X275373Y249684D02*
G02X276696Y249136I0J-1871D01*
G01X274560Y249684D02*
X275373D01*
G01X273254Y248897D02*
G02X274560Y249684I1365J-788D01*
G01X271324Y247735D02*
G03X273254Y248897I-85J2325D01*
G01X271195Y247735D02*
X271324D01*
G01X269874Y246947D02*
G02X271195Y247735I1365J-787D01*
G01X267929Y245784D02*
G03X269874Y246947I-70J2325D01*
G01X267800Y245784D02*
X267929D01*
G01X266475Y243456D02*
G02X267800Y245784I1384J753D01*
G01X266494Y243422D02*
X266475Y243456D01*
G01X266519Y243380D02*
X266494Y243422D01*
G01Y241097D02*
G03X266519Y243380I-2015J1164D01*
G01X266475Y239556D02*
G02X266494Y241097I1384J754D01*
G01Y239522D02*
X266475Y239556D01*
G01X266519Y239480D02*
X266494Y239522D01*
G01Y237197D02*
G03X266519Y239480I-2015J1164D01*
G01X266492Y237198D02*
X266494Y237197D01*
G01X265881Y236139D02*
X266492Y237198D01*
G01X264964Y235222D02*
X265881Y236139D01*
G01X264964Y233875D02*
Y235222D01*
G01X283669Y271920D02*
X284759Y269560D01*
G01X281464Y273834D02*
G02X283669Y271920I-85J-2325D01*
G01X281335Y273834D02*
X281464D01*
G01X280014Y274622D02*
G03X281335Y273834I1365J787D01*
G01X278069Y275785D02*
G02X280014Y274622I-70J-2325D01*
G01X277940Y275785D02*
X278069D01*
G01X276634Y276572D02*
G03X277940Y275785I1365J788D01*
G01X272604Y276572D02*
G02X276634I2015J-1163D01*
G01X271298Y275785D02*
G03X272604Y276572I-59J1575D01*
G01X270303Y275785D02*
X271298D01*
G01X269075Y274724D02*
G02X270303Y275785I2164J-1264D01*
G01X268190Y273971D02*
G03X269075Y274724I-631J1638D01*
G01X267681Y273934D02*
X268190Y273971D01*
G01X267355Y273934D02*
X267681D01*
G01X266504Y273935D02*
X267355Y273934D01*
G01X266178Y274261D02*
X266504Y273935D01*
G01X280225Y237075D02*
X281379Y236409D01*
G01X279915Y236991D02*
X280225Y237075D01*
G01X279995Y235656D02*
G02X279915Y236991I1385J753D01*
G01X280014Y235622D02*
X279995Y235656D01*
G01X280039Y235580D02*
X280014Y235622D01*
G01Y233297D02*
G03X280039Y235580I-2015J1164D01*
G01X279995Y231756D02*
G02X280014Y233297I1384J754D01*
G01Y231722D02*
X279995Y231756D01*
G01X280039Y229439D02*
G03X280014Y231722I-2040J1119D01*
G01Y229397D02*
X280039Y229439D01*
G01X280014Y227823D02*
G02Y229397I1365J787D01*
G01Y225497D02*
G03Y227823I-2015J1163D01*
G01X279995Y223956D02*
G02X280014Y225497I1384J754D01*
G01Y223922D02*
X279995Y223956D01*
G01X280039Y223880D02*
X280014Y223922D01*
G01Y221597D02*
G03X280039Y223880I-2015J1164D01*
G01X279995Y220056D02*
G02X280014Y221597I1384J754D01*
G01Y220022D02*
X279995Y220056D01*
G01X280039Y219980D02*
X280014Y220022D01*
G01X279364Y219647D02*
X279383Y219613D01*
G01X279339Y219689D02*
X279364Y219647D01*
G01Y221972D02*
G03X279339Y219689I2015J-1164D01*
G01X279383Y223513D02*
G02X279364Y221972I-1384J-754D01*
G01Y223547D02*
X279383Y223513D01*
G01X279339Y223589D02*
X279364Y223547D01*
G01Y225872D02*
G03X279339Y223589I2015J-1164D01*
G01X279383Y227413D02*
G02X279364Y225872I-1384J-754D01*
G01Y227447D02*
X279383Y227413D01*
G01X279339Y229730D02*
G03X279364Y227447I2040J-1119D01*
G01Y229772D02*
X279339Y229730D01*
G01X279364Y231346D02*
G02Y229772I-1365J-787D01*
G01Y233672D02*
G03Y231346I2015J-1163D01*
G01X279383Y235213D02*
G02X279364Y233672I-1384J-754D01*
G01Y235247D02*
X279383Y235213D01*
G01X279339Y235289D02*
X279364Y235247D01*
G01X279247Y237342D02*
G03X279339Y235289I2131J-933D01*
G01X279153Y237694D02*
X279247Y237342D01*
G01X277999Y238360D02*
X279153Y237694D01*
G01X273485Y219234D02*
X272608Y220111D01*
G01X274663Y219234D02*
X273485D01*
G01X275856Y219834D02*
G02X274663Y219234I-1238J975D01*
G01X275984Y220022D02*
G02X275856Y219834I-1127J630D01*
G01X276003Y220056D02*
X275984Y220022D01*
G01X276111Y221315D02*
G02X276003Y220056I-1492J-506D01*
G01X275984Y221596D02*
G02X276111Y221315I-1373J-790D01*
G01X275984Y223922D02*
G03Y221596I2015J-1163D01*
G01Y225496D02*
G02Y223922I-1365J-787D01*
G01Y227822D02*
G03Y225496I2015J-1163D01*
G01Y229396D02*
G02Y227822I-1365J-787D01*
G01Y231722D02*
G03Y229396I2015J-1163D01*
G01Y233296D02*
G02Y231722I-1365J-787D01*
G01Y235622D02*
G03Y233296I2015J-1163D01*
G01Y237196D02*
G02Y235622I-1365J-787D01*
G01Y239522D02*
G03Y237196I2015J-1163D01*
G01X277999Y242259D02*
G03X275984Y239522I11254J-10395D01*
G01X277999Y242260D02*
Y242259D01*
G01X277947Y257926D02*
X277999Y257860D01*
G01X275282Y258234D02*
X277947Y257926D01*
G01X274534Y258234D02*
X275282D01*
G01X272604Y257072D02*
G02X274534Y258234I2015J-1163D01*
G01X271298Y256285D02*
G03X272604Y257072I-59J1575D01*
G01X271169Y256285D02*
X271298D01*
G01X269224Y255122D02*
G02X271169Y256285I2015J-1162D01*
G01X267903Y254334D02*
G03X269224Y255122I-44J1575D01*
G01X267059Y254334D02*
X267903D01*
G01X265687Y253161D02*
G02X267059Y254334I2172J-1152D01*
G01X264836Y252385D02*
G03X265687Y253161I-657J1575D01*
G01X261761Y252385D02*
X264836D01*
G01X258348Y248972D02*
X261761Y252385D01*
G01X258348Y245859D02*
Y248972D01*
G01X257528Y245039D02*
X258348Y245859D01*
G01X256241Y245039D02*
X257528D01*
G01X278141Y256285D02*
X281379Y255909D01*
G01X277940Y256285D02*
X278141D01*
G01X276905Y256726D02*
G03X277940Y256285I1095J1134D01*
G01X275075Y257484D02*
G02X276905Y256726I0J-2588D01*
G01X274560Y257484D02*
X275075D01*
G01X273254Y256697D02*
G02X274560Y257484I1365J-788D01*
G01X271324Y255535D02*
G03X273254Y256697I-85J2325D01*
G01X271195Y255535D02*
X271324D01*
G01X269874Y254747D02*
G02X271195Y255535I1365J-787D01*
G01X267929Y253584D02*
G03X269874Y254747I-70J2325D01*
G01X267202Y253584D02*
X267929D01*
G01X266351Y252808D02*
G02X267202Y253584I1508J-799D01*
G01X264979Y251635D02*
G03X266351Y252808I-800J2325D01*
G01X262072Y251635D02*
X264979D01*
G01X259098Y248661D02*
X262072Y251635D01*
G01X259098Y245551D02*
Y248661D01*
G01X258409Y244862D02*
X259098Y245551D01*
G01X258409Y243671D02*
Y244862D01*
G01X284903Y267986D02*
X288139Y267609D01*
G01X284715Y267986D02*
X284903D01*
G01X284149Y268108D02*
G03X284715Y267986I609J1453D01*
G01X282798Y268841D02*
G03X284149Y268108I1433J1030D01*
G01X282719Y270680D02*
G03X282798Y268841I1443J-859D01*
G01X282744Y270722D02*
X282719Y270680D01*
G01X282763Y270756D02*
X282744Y270722D01*
G01X281438Y273084D02*
G02X282763Y270756I-59J-1575D01*
G01X281309Y273084D02*
X281438D01*
G01X279364Y274247D02*
G03X281309Y273084I2015J1162D01*
G01X278043Y275035D02*
G02X279364Y274247I-44J-1575D01*
G01X277914Y275035D02*
X278043D01*
G01X275984Y276197D02*
G03X277914Y275035I2015J1163D01*
G01X274678Y276984D02*
G02X275984Y276197I-59J-1575D01*
G01X274560Y276984D02*
X274678D01*
G01X273254Y276197D02*
G02X274560Y276984I1365J-788D01*
G01X271324Y275035D02*
G03X273254Y276197I-85J2325D01*
G01X270464Y275035D02*
X271324D01*
G01X269723Y274345D02*
G02X270464Y275035I1516J-885D01*
G01X268343Y273229D02*
G03X269723Y274345I-784J2380D01*
G01X267737Y273184D02*
X268343Y273229D01*
G01X266945Y273184D02*
X267737D01*
G01X266290Y272529D02*
X266945Y273184D01*
G01X280523Y269891D02*
X281379Y267609D01*
G01X280082Y270605D02*
X280523Y269891D01*
G01X280014Y270722D02*
X280082Y270605D01*
G01X278069Y271885D02*
G02X280014Y270722I-70J-2325D01*
G01X277940Y271885D02*
X278069D01*
G01X276634Y272672D02*
G03X277940Y271885I1365J788D01*
G01X274704Y273834D02*
G02X276634Y272672I-85J-2325D01*
G01X274534Y273834D02*
X274704D01*
G01X272604Y272672D02*
G02X274534Y273834I2015J-1163D01*
G01X271298Y271885D02*
G03X272604Y272672I-59J1575D01*
G01X271169Y271885D02*
X271298D01*
G01X269224Y270722D02*
G02X271169Y271885I2015J-1162D01*
G01X267903Y269934D02*
G03X269224Y270722I-44J1575D01*
G01X267059Y269934D02*
X267903D01*
G01X265687Y268761D02*
G02X267059Y269934I2172J-1152D01*
G01X264836Y267985D02*
G03X265687Y268761I-657J1575D01*
G01X263234Y267985D02*
X264836D01*
G01X261898Y269321D02*
X263234Y267985D01*
G01X274689Y218484D02*
X273481D01*
G01X276493Y219430D02*
G02X274689Y218484I-1873J1379D01*
G01X276634Y219647D02*
G02X276493Y219430I-2830J1684D01*
G01X276659Y219689D02*
X276634Y219647D01*
G01Y221972D02*
G02X276659Y219689I-2015J-1164D01*
G01X276634Y223546D02*
G03Y221972I1365J-787D01*
G01Y225872D02*
G02Y223546I-2015J-1163D01*
G01Y227446D02*
G03Y225872I1365J-787D01*
G01Y229772D02*
G02Y227446I-2015J-1163D01*
G01Y231346D02*
G03Y229772I1365J-787D01*
G01Y233672D02*
G02Y231346I-2015J-1163D01*
G01Y235246D02*
G03Y233672I1365J-787D01*
G01Y237572D02*
G02Y235246I-2015J-1163D01*
G01X277955Y239934D02*
G03X276634Y237572I44J-1575D01*
G01X279301Y239934D02*
X277955D01*
G01X280876Y238359D02*
X279301Y239934D01*
G01X284759Y238359D02*
X280876D01*
G01X284759Y238360D02*
Y238359D01*
G01X286190Y266331D02*
X288139Y263709D01*
G01X286124Y266447D02*
X286190Y266331D01*
G01X283903Y266983D02*
G02X286124Y266447I856J-1323D01*
G01X281748Y266034D02*
X283903Y266983D01*
G01X281335Y266034D02*
X281748D01*
G01X279805Y267686D02*
G03X281335Y266034I1574J-77D01*
G01X279578Y269976D02*
X279805Y267686D01*
G01X279364Y270347D02*
X279578Y269976D01*
G01X278043Y271135D02*
G02X279364Y270347I-44J-1575D01*
G01X277914Y271135D02*
X278043D01*
G01X275984Y272297D02*
G03X277914Y271135I2015J1163D01*
G01X274678Y273084D02*
G02X275984Y272297I-59J-1575D01*
G01X274560Y273084D02*
X274678D01*
G01X273254Y272297D02*
G02X274560Y273084I1365J-788D01*
G01X271324Y271135D02*
G03X273254Y272297I-85J2325D01*
G01X271195Y271135D02*
X271324D01*
G01X269874Y270347D02*
G02X271195Y271135I1365J-787D01*
G01X267929Y269184D02*
G03X269874Y270347I-70J2325D01*
G01X267202Y269184D02*
X267929D01*
G01X266351Y268408D02*
G02X267202Y269184I1508J-799D01*
G01X264979Y267235D02*
G03X266351Y268408I-800J2325D01*
G01X262312Y267235D02*
X264979D01*
G01X261898Y266821D02*
X262312Y267235D01*
G01X279430Y250731D02*
X281379Y248109D01*
G01X279364Y250847D02*
X279430Y250731D01*
G01X276855Y251143D02*
G02X279364Y250847I1144J-1083D01*
G01X276798Y251087D02*
X276855Y251143D01*
G01X275223Y250434D02*
G03X276798Y251087I-1J2228D01*
G01X274534Y250434D02*
X275223D01*
G01X272604Y249272D02*
G02X274534Y250434I2015J-1163D01*
G01X271298Y248485D02*
G03X272604Y249272I-59J1575D01*
G01X271169Y248485D02*
X271298D01*
G01X269224Y247322D02*
G02X271169Y248485I2015J-1162D01*
G01X267903Y246534D02*
G03X269224Y247322I-44J1575D01*
G01X267774Y246534D02*
X267903D01*
G01X265819Y243089D02*
G02X267774Y246534I2040J1120D01*
G01X265844Y243047D02*
X265819Y243089D01*
G01X265863Y243013D02*
X265844Y243047D01*
G01Y241472D02*
G03X265863Y243013I-1365J787D01*
G01X265819Y239189D02*
G02X265844Y241472I2040J1119D01*
G01Y239147D02*
X265819Y239189D01*
G01X265863Y239113D02*
X265844Y239147D01*
G01Y237572D02*
G03X265863Y239113I-1365J787D01*
G01X265282Y236598D02*
X265844Y237572D01*
G01X265069Y236385D02*
X265282Y236598D01*
G01X263924Y236385D02*
X265069D01*
G01X283631Y251600D02*
X284759Y250060D01*
G01X282638Y252957D02*
X283631Y251600D01*
G01X282067Y253427D02*
G02X282638Y252957I-688J-1418D01*
G01X280265Y254307D02*
X282067Y253427D01*
G01X279138Y255049D02*
X280265Y254307D01*
G01X278043Y255535D02*
G02X279138Y255049I-44J-1575D01*
G01X277698Y255535D02*
X278043D01*
G01X276345Y254999D02*
X277698Y255535D01*
G01X275301Y254489D02*
X276345Y254999D01*
G01X274663Y254334D02*
G03X275301Y254489I-45J1575D01*
G01X274534Y254334D02*
X274663D01*
G01X272604Y253172D02*
G02X274534Y254334I2015J-1163D01*
G01X271298Y252385D02*
G03X272604Y253172I-59J1575D01*
G01X271169Y252385D02*
X271298D01*
G01X269224Y251222D02*
G02X271169Y252385I2015J-1162D01*
G01X267903Y250434D02*
G03X269224Y251222I-44J1575D01*
G01X267774Y250434D02*
X267903D01*
G01X265844Y249272D02*
G02X267774Y250434I2015J-1163D01*
G01X264538Y248485D02*
G03X265844Y249272I-59J1575D01*
G01X262931Y248485D02*
X264538D01*
G01X261768Y247322D02*
X262931Y248485D01*
G01X261768Y240222D02*
Y247322D01*
G01X261387Y239841D02*
X261768Y240222D01*
G01X260278Y239841D02*
X261387D01*
G01X281525Y258234D02*
X284759Y257860D01*
G01X281335Y258234D02*
X281525D01*
G01X280014Y259022D02*
G03X281335Y258234I1365J787D01*
G01X278069Y260185D02*
G02X280014Y259022I-70J-2325D01*
G01X276698Y260185D02*
X278069D01*
G01X275984Y260597D02*
G03X276698Y260185I714J413D01*
G01X274678Y261384D02*
G02X275984Y260597I-59J-1575D01*
G01X274560Y261384D02*
X274678D01*
G01X273254Y260597D02*
G02X274560Y261384I1365J-788D01*
G01X271324Y259435D02*
G03X273254Y260597I-85J2325D01*
G01X271195Y259435D02*
X271324D01*
G01X269874Y258647D02*
G02X271195Y259435I1365J-787D01*
G01X267929Y257484D02*
G03X269874Y258647I-70J2325D01*
G01X267202Y257484D02*
X267929D01*
G01X266351Y256708D02*
G02X267202Y257484I1508J-799D01*
G01X264979Y255535D02*
G03X266351Y256708I-800J2325D01*
G01X261689Y255535D02*
X264979D01*
G01X255673Y249519D02*
X261689Y255535D01*
G01X255673Y248007D02*
Y249519D01*
G01X260719Y322681D02*
X259818Y321780D01*
G01X265788Y322681D02*
X260719D01*
G01X266891Y323784D02*
X265788Y322681D01*
G01X267918Y323784D02*
X266891D01*
G01X269224Y322997D02*
G03X267918Y323784I-1365J-788D01*
G01X271154Y321835D02*
G02X269224Y322997I85J2325D01*
G01X271283Y321835D02*
X271154D01*
G01X272604Y321047D02*
G03X271283Y321835I-1365J-787D01*
G01X274549Y319884D02*
G02X272604Y321047I70J2325D01*
G01X274689Y319884D02*
X274549D01*
G01X276634Y321047D02*
G02X274689Y319884I-2015J1162D01*
G01X277955Y321835D02*
G03X276634Y321047I44J-1575D01*
G01X278084Y321835D02*
X277955D01*
G01X280014Y322997D02*
G02X278084Y321835I-2015J1163D01*
G01X281320Y323784D02*
G03X280014Y322997I59J-1575D01*
G01X281430Y323784D02*
X281320D01*
G01X283394Y324947D02*
G02X281430Y323784I-2015J1163D01*
G01X284715Y325735D02*
G03X283394Y324947I44J-1575D01*
G01X284844Y325735D02*
X284715D01*
G01X286774Y326897D02*
G02X284844Y325735I-2015J1163D01*
G01X286839Y327009D02*
X286774Y326897D01*
G01X288139Y330009D02*
X286839Y327009D01*
G01X291604Y314035D02*
G03X293534Y315197I-85J2325D01*
G01X291475Y314035D02*
X291604D01*
G01X290154Y313247D02*
G02X291475Y314035I1365J-787D01*
G01X288209Y312084D02*
G03X290154Y313247I-70J2325D01*
G01X288080Y312084D02*
X288209D01*
G01X286774Y311297D02*
G02X288080Y312084I1365J-788D01*
G01X284844Y310135D02*
G03X286774Y311297I-85J2325D01*
G01X284674Y310135D02*
X284844D01*
G01X282744Y311297D02*
G03X284674Y310135I2015J1163D01*
G01X281438Y312084D02*
G02X282744Y311297I-59J-1575D01*
G01X281320Y312084D02*
X281438D01*
G01X280014Y311297D02*
G02X281320Y312084I1365J-788D01*
G01X278084Y310135D02*
G03X280014Y311297I-85J2325D01*
G01X277955Y310135D02*
X278084D01*
G01X276634Y309347D02*
G02X277955Y310135I1365J-787D01*
G01X274689Y308184D02*
G03X276634Y309347I-70J2325D01*
G01X273909Y308184D02*
X274689D01*
G01X273088Y307410D02*
G02X273909Y308184I1531J-801D01*
G01X271752Y306235D02*
G03X273088Y307410I-860J2325D01*
G01X268305Y306235D02*
X271752D01*
G01X258152Y308956D02*
X268305Y306235D01*
G01X257877Y308796D02*
X258152Y308956D01*
G01X257793Y308818D02*
X257877Y308796D01*
G01X256248Y341741D02*
X255448Y340941D01*
G01X265844Y340547D02*
G03X264523Y341335I-1365J-787D01*
G01X267789Y339384D02*
G02X265844Y340547I70J2325D01*
G01X267918Y339384D02*
X267789D01*
G01X269224Y338597D02*
G03X267918Y339384I-1365J-788D01*
G01X271154Y337435D02*
G02X269224Y338597I85J2325D01*
G01X271283Y337435D02*
X271154D01*
G01X272604Y336647D02*
G03X271283Y337435I-1365J-787D01*
G01X274549Y335484D02*
G02X272604Y336647I70J2325D01*
G01X274678Y335484D02*
X274549D01*
G01X275984Y334697D02*
G03X274678Y335484I-1365J-788D01*
G01X276698Y334285D02*
G02X275984Y334697I0J825D01*
G01X278058Y334285D02*
X276698D01*
G01X279364Y335072D02*
G02X278058Y334285I-1365J788D01*
G01X281294Y336234D02*
G03X279364Y335072I85J-2325D01*
G01X281423Y336234D02*
X281294D01*
G01X282744Y337022D02*
G02X281423Y336234I-1365J787D01*
G01X282810Y337138D02*
X282744Y337022D01*
G01X284759Y339760D02*
X282810Y337138D01*
G01X279429Y327387D02*
X281379Y330009D01*
G01X279364Y327273D02*
X279429Y327387D01*
G01X278043Y326485D02*
G03X279364Y327273I-44J1575D01*
G01X277914Y326485D02*
X278043D01*
G01X275984Y325323D02*
G02X277914Y326485I2015J-1163D01*
G01X273254Y325323D02*
G03X275984I1365J787D01*
G01X271324Y326485D02*
G02X273254Y325323I-85J-2325D01*
G01X271195Y326485D02*
X271324D01*
G01X269874Y327273D02*
G03X271195Y326485I1365J787D01*
G01X267944Y328435D02*
G02X269874Y327273I-85J-2325D01*
G01X267061Y328435D02*
X267944D01*
G01X265687Y327261D02*
G02X267061Y328435I2172J-1151D01*
G01X265259Y326790D02*
X265687Y327261D01*
G01X264954Y326485D02*
X265259Y326790D01*
G01X263362Y326485D02*
X264954D01*
G01X260858Y328989D02*
X263362Y326485D01*
G01X260099Y328989D02*
X260858D01*
G01X259208Y329880D02*
X260099Y328989D01*
G01X286840Y330910D02*
X288139Y333909D01*
G01X286774Y330797D02*
X286840Y330910D01*
G01X284844Y329635D02*
G03X286774Y330797I-85J2325D01*
G01X284715Y329635D02*
X284844D01*
G01X283394Y328847D02*
G02X284715Y329635I1365J-787D01*
G01X281449Y327684D02*
G03X283394Y328847I-70J2325D01*
G01X281308Y327684D02*
X281449D01*
G01X280014Y326897D02*
G02X281308Y327684I1365J-787D01*
G01X278084Y325735D02*
G03X280014Y326897I-85J2325D01*
G01X277955Y325735D02*
X278084D01*
G01X276634Y324947D02*
G02X277955Y325735I1365J-787D01*
G01X272604Y324947D02*
G03X276634I2015J1163D01*
G01X271283Y325735D02*
G02X272604Y324947I-44J-1575D01*
G01X271154Y325735D02*
X271283D01*
G01X269224Y326897D02*
G03X271154Y325735I2015J1163D01*
G01X267930Y327684D02*
G02X269224Y326897I-71J-1574D01*
G01X267200Y327684D02*
X267930D01*
G01X266799Y327394D02*
G02X267200Y327684I821J-714D01*
G01X265922Y326385D02*
X266799Y327394D01*
G01X265274Y325737D02*
X265922Y326385D01*
G01X263052Y325737D02*
X265274D01*
G01X260548Y328241D02*
X263052Y325737D01*
G01X259949Y328241D02*
X260548D01*
G01X259088Y327380D02*
X259949Y328241D01*
G01X280080Y338710D02*
X281379Y341709D01*
G01X280014Y338597D02*
X280080Y338710D01*
G01X278084Y337435D02*
G03X280014Y338597I-85J2325D01*
G01X277914Y337435D02*
X278084D01*
G01X275984Y338597D02*
G03X277914Y337435I2015J1163D01*
G01X274678Y339384D02*
G02X275984Y338597I-59J-1575D01*
G01X274549Y339384D02*
X274678D01*
G01X272604Y340547D02*
G03X274549Y339384I2015J1162D01*
G01X271283Y341335D02*
G02X272604Y340547I-44J-1575D01*
G01X273254Y340922D02*
G03X271309Y342085I-2015J-1162D01*
G01X274575Y340134D02*
G02X273254Y340922I44J1575D01*
G01X274765Y340134D02*
X274575D01*
G01X277999Y339760D02*
X274765Y340134D01*
G01X292884Y315572D02*
G02X296914I2015J-1163D01*
G01X291578Y314785D02*
G03X292884Y315572I-59J1575D01*
G01X291449Y314785D02*
X291578D01*
G01X289504Y313622D02*
G02X291449Y314785I2015J-1162D01*
G01X288183Y312834D02*
G03X289504Y313622I-44J1575D01*
G01X288054Y312834D02*
X288183D01*
G01X286124Y311672D02*
G02X288054Y312834I2015J-1163D01*
G01X284818Y310885D02*
G03X286124Y311672I-59J1575D01*
G01X284700Y310885D02*
X284818D01*
G01X283394Y311672D02*
G03X284700Y310885I1365J788D01*
G01X281464Y312834D02*
G02X283394Y311672I-85J-2325D01*
G01X281294Y312834D02*
X281464D01*
G01X279364Y311672D02*
G02X281294Y312834I2015J-1163D01*
G01X278058Y310885D02*
G03X279364Y311672I-59J1575D01*
G01X277929Y310885D02*
X278058D01*
G01X275984Y309722D02*
G02X277929Y310885I2015J-1162D01*
G01X274663Y308934D02*
G03X275984Y309722I-44J1575D01*
G01X273759Y308934D02*
X274663D01*
G01X272423Y307759D02*
G02X273759Y308934I2196J-1150D01*
G01X271602Y306985D02*
G03X272423Y307759I-710J1575D01*
G01X268404Y306985D02*
X271602D01*
G01X258345Y309682D02*
X268404Y306985D01*
G01X258187Y309956D02*
X258345Y309682D01*
G01X258103Y309978D02*
X258187Y309956D01*
G01X274765Y336234D02*
X277999Y335860D01*
G01X274575Y336234D02*
X274765D01*
G01X273254Y337022D02*
G03X274575Y336234I1365J787D01*
G01X271309Y338185D02*
G02X273254Y337022I-70J-2325D01*
G01X271180Y338185D02*
X271309D01*
G01X269874Y338972D02*
G03X271180Y338185I1365J788D01*
G01X267944Y340134D02*
G02X269874Y338972I-85J-2325D01*
G01X267815Y340134D02*
X267944D01*
G01X266494Y340922D02*
G03X267815Y340134I1365J787D01*
G01X264549Y342085D02*
G02X266494Y340922I-70J-2325D01*
G01X260669Y323429D02*
X259818Y324280D01*
G01X265475Y323429D02*
X260669D01*
G01X266580Y324534D02*
X265475Y323429D01*
G01X267931Y324534D02*
X266580D01*
G01X269874Y323372D02*
G03X267931Y324534I-2015J-1163D01*
G01X271180Y322585D02*
G02X269874Y323372I59J1575D01*
G01X271309Y322585D02*
X271180D01*
G01X273254Y321422D02*
G03X271309Y322585I-2015J-1162D01*
G01X275984Y321422D02*
G02X273254I-1365J787D01*
G01X277929Y322585D02*
G03X275984Y321422I70J-2325D01*
G01X278058Y322585D02*
X277929D01*
G01X279364Y323372D02*
G02X278058Y322585I-1365J788D01*
G01X281328Y324535D02*
G03X279364Y323372I51J-2326D01*
G01X281423Y324535D02*
X281328D01*
G01X282744Y325323D02*
G02X281423Y324535I-1365J787D01*
G01X282809Y325436D02*
X282744Y325323D01*
G01X284759Y328060D02*
X282809Y325436D01*
G01X264218Y399034D02*
Y400312D01*
G01X266567Y396685D02*
X264218Y399034D01*
G01X271290Y396685D02*
X266567D01*
G01X273254Y395522D02*
G03X271290Y396685I-2015J-1163D01*
G01X274548Y394735D02*
G02X273254Y395522I71J1574D01*
G01X274689Y394735D02*
X274548D01*
G01X276634Y393572D02*
G03X274689Y394735I-2015J-1162D01*
G01X277928Y392785D02*
G02X276634Y393572I71J1574D01*
G01X278143Y392785D02*
X277928D01*
G01X281379Y392410D02*
X278143Y392785D01*
G01X273028Y399809D02*
X268748Y404089D01*
G01X273252Y399421D02*
X273028Y399809D01*
G01X274562Y398632D02*
G02X273252Y399421I57J1577D01*
G01X274575Y398632D02*
X274562D01*
G01X274577Y398634D02*
X274575Y398632D01*
G01X274704Y398634D02*
X274577D01*
G01X276634Y397472D02*
G03X274704Y398634I-2015J-1163D01*
G01X277940Y396685D02*
G02X276634Y397472I59J1575D01*
G01X278050Y396685D02*
X277940D01*
G01X280014Y395522D02*
G03X278050Y396685I-2015J-1163D01*
G01X281308Y394735D02*
G02X280014Y395522I71J1574D01*
G01X281521Y394735D02*
X281308D01*
G01X284759Y394359D02*
X281521Y394735D01*
G01X279430Y346888D02*
X281379Y349509D01*
G01X279364Y346772D02*
X279430Y346888D01*
G01X278058Y345985D02*
G03X279364Y346772I-59J1575D01*
G01X277940Y345985D02*
X278058D01*
G01X276634Y346772D02*
G03X277940Y345985I1365J788D01*
G01X274704Y347934D02*
G02X276634Y346772I-85J-2325D01*
G01X274575Y347934D02*
X274704D01*
G01X273254Y348722D02*
G03X274575Y347934I1365J787D01*
G01X271309Y349885D02*
G02X273254Y348722I-70J-2325D01*
G01X271180Y349885D02*
X271309D01*
G01X269874Y350672D02*
G03X271180Y349885I1365J788D01*
G01X267944Y351834D02*
G02X269874Y350672I-85J-2325D01*
G01X267204Y351834D02*
X267944D01*
G01X266351Y354208D02*
G03X267204Y351834I1508J-799D01*
G01X266834Y355119D02*
X266351Y354208D01*
G01X266834Y357313D02*
Y355119D01*
G01X265158Y358989D02*
X266834Y357313D01*
G01X262658Y358989D02*
X265158D01*
G01X260192Y361455D02*
X262658Y358989D01*
G01X260192Y362444D02*
Y361455D01*
G01X262748Y341741D02*
X256248D01*
G01X263154Y341335D02*
X262748Y341741D01*
G01X264523Y341335D02*
X263154D01*
G01X293303Y399831D02*
X289843Y403291D01*
G01X292778Y396021D02*
G03X293468Y396982I-4364J3861D01*
G01X291519Y394359D02*
G02X292778Y396021I11539J-7434D01*
G01X259048Y380299D02*
Y381468D01*
G01X266458Y372889D02*
X259048Y380299D01*
G01X268459Y372889D02*
X266458D01*
G01X272829Y368519D02*
X268459Y372889D01*
G01X272833Y368519D02*
X272829D01*
G01X273917Y367435D02*
X272833Y368519D01*
G01X274670Y367435D02*
X273917D01*
G01X276659Y363989D02*
G03X274670Y367435I-2040J1120D01*
G01X276634Y363947D02*
X276659Y363989D01*
G01X276615Y363913D02*
X276634Y363947D01*
G01Y362372D02*
G02X276615Y363913I1365J787D01*
G01X277135Y361504D02*
X276634Y362372D01*
G01X277999Y359260D02*
G03X277135Y361504I-7568J-1626D01*
G01X286190Y350788D02*
X288139Y353409D01*
G01X286124Y350672D02*
X286190Y350788D01*
G01X284818Y349885D02*
G03X286124Y350672I-59J1575D01*
G01X284689Y349885D02*
X284818D01*
G01X282744Y348722D02*
G02X284689Y349885I2015J-1162D01*
G01X282096Y347598D02*
X282744Y348722D01*
G01X281379Y347184D02*
G03X282096Y347598I0J828D01*
G01X281320Y347184D02*
X281379D01*
G01X280014Y346397D02*
G02X281320Y347184I1365J-788D01*
G01X278084Y345235D02*
G03X280014Y346397I-85J2325D01*
G01X277914Y345235D02*
X278084D01*
G01X275984Y346397D02*
G03X277914Y345235I2015J1163D01*
G01X274678Y347184D02*
G02X275984Y346397I-59J-1575D01*
G01X274549Y347184D02*
X274678D01*
G01X272604Y348347D02*
G03X274549Y347184I2015J1162D01*
G01X271283Y349135D02*
G02X272604Y348347I-44J-1575D01*
G01X271154Y349135D02*
X271283D01*
G01X269224Y350297D02*
G03X271154Y349135I2015J1163D01*
G01X267918Y351084D02*
G02X269224Y350297I-59J-1575D01*
G01X267061Y351084D02*
X267918D01*
G01X265687Y354561D02*
G03X267061Y351084I2172J-1152D01*
G01X266086Y355307D02*
X265687Y354561D01*
G01X266086Y357003D02*
Y355307D01*
G01X264848Y358241D02*
X266086Y357003D01*
G01X262348Y358241D02*
X264848D01*
G01X259948Y360641D02*
X262348Y358241D01*
G01X258459Y360641D02*
X259948D01*
G01X286774Y346397D02*
X288139Y349509D01*
G01X284844Y345235D02*
G03X286774Y346397I-85J2325D01*
G01X284715Y345235D02*
X284844D01*
G01X283394Y344447D02*
G02X284715Y345235I1365J-787D01*
G01X281449Y343284D02*
G03X283394Y344447I-70J2325D01*
G01X281320Y343284D02*
X281449D01*
G01X280014Y342497D02*
G02X281320Y343284I1365J-788D01*
G01X278084Y341335D02*
G03X280014Y342497I-85J2325D01*
G01X277914Y341335D02*
X278084D01*
G01X275984Y342497D02*
G03X277914Y341335I2015J1163D01*
G01X274678Y343284D02*
G02X275984Y342497I-59J-1575D01*
G01X274549Y343284D02*
X274678D01*
G01X272604Y344447D02*
G03X274549Y343284I2015J1162D01*
G01X271283Y345235D02*
G02X272604Y344447I-44J-1575D01*
G01X271154Y345235D02*
X271283D01*
G01X269224Y346397D02*
G03X271154Y345235I2015J1163D01*
G01X267918Y347184D02*
G02X269224Y346397I-59J-1575D01*
G01X267789Y347184D02*
X267918D01*
G01X265844Y348347D02*
G03X267789Y347184I2015J1162D01*
G01X264523Y349135D02*
G02X265844Y348347I-44J-1575D01*
G01X262893Y349135D02*
X264523D01*
G01X261248Y350780D02*
X262893Y349135D01*
G01X261248Y352141D02*
Y350780D01*
G01X256648Y356741D02*
X261248Y352141D01*
G01X255287Y356741D02*
X256648D01*
G01X292884Y391247D02*
G02X294829Y394735I2015J1163D01*
G01X292949Y391134D02*
X292884Y391247D01*
G01X294899Y388509D02*
X292949Y391134D01*
G01X263545Y398644D02*
X262350D01*
G01X266255Y395934D02*
X263545Y398644D01*
G01X271283Y395934D02*
X266255D01*
G01X272604Y395146D02*
G03X271283Y395934I-1365J-787D01*
G01X274534Y393984D02*
G02X272604Y395146I85J2325D01*
G01X274690Y393984D02*
X274534D01*
G01X275984Y393197D02*
G03X274690Y393984I-1365J-787D01*
G01X277929Y392034D02*
G02X275984Y393197I70J2325D01*
G01X278070Y392034D02*
X277929D01*
G01X279364Y391247D02*
G03X278070Y392034I-1365J-787D01*
G01X279429Y391134D02*
X279364Y391247D01*
G01X281379Y388509D02*
X279429Y391134D01*
G01X272429Y399350D02*
X268544Y403235D01*
G01X272604Y399047D02*
X272429Y399350D01*
G01X274549Y397884D02*
G02X272604Y399047I70J2325D01*
G01X274678Y397884D02*
X274549D01*
G01X275984Y397097D02*
G03X274678Y397884I-1365J-788D01*
G01X277948Y395934D02*
G02X275984Y397097I51J2326D01*
G01X278043Y395934D02*
X277948D01*
G01X279364Y395146D02*
G03X278043Y395934I-1365J-787D01*
G01X281294Y393984D02*
G02X279364Y395146I85J2325D01*
G01X281450Y393984D02*
X281294D01*
G01X282744Y391623D02*
G03X281450Y393984I-1365J787D01*
G01X282744Y389297D02*
G02Y391623I2015J1163D01*
G01X282810Y389181D02*
X282744Y389297D01*
G01X284759Y386560D02*
X282810Y389181D01*
G01X286546Y402543D02*
X282205Y406884D01*
G01X289532Y402543D02*
X286546D01*
G01X292701Y399374D02*
X289532Y402543D01*
G01X292903Y399013D02*
X292701Y399374D01*
G01X292884Y397472D02*
G03X292903Y399013I-1365J787D01*
G01X290943Y395826D02*
G03X292884Y397472I-1439J3664D01*
G01X290154Y393572D02*
G02X290943Y395826I1365J787D01*
G01X290179Y393530D02*
X290154Y393572D01*
G01Y391247D02*
G03X290179Y393530I-2015J1164D01*
G01X290135Y391213D02*
X290154Y391247D01*
G01Y389672D02*
G02X290135Y391213I1365J787D01*
G01X290220Y389559D02*
X290154Y389672D01*
G01X291519Y386560D02*
X290220Y389559D01*
G01X283228Y345411D02*
X284759Y347560D01*
G01X282744Y344822D02*
G02X283228Y345411I2015J-1162D01*
G01X281423Y344034D02*
G03X282744Y344822I-44J1575D01*
G01X281294Y344034D02*
X281423D01*
G01X279364Y342872D02*
G02X281294Y344034I2015J-1163D01*
G01X278058Y342085D02*
G03X279364Y342872I-59J1575D01*
G01X277940Y342085D02*
X278058D01*
G01X276634Y342872D02*
G03X277940Y342085I1365J788D01*
G01X274704Y344034D02*
G02X276634Y342872I-85J-2325D01*
G01X274575Y344034D02*
X274704D01*
G01X273254Y344822D02*
G03X274575Y344034I1365J787D01*
G01X271309Y345985D02*
G02X273254Y344822I-70J-2325D01*
G01X271180Y345985D02*
X271309D01*
G01X269874Y346772D02*
G03X271180Y345985I1365J788D01*
G01X267944Y347934D02*
G02X269874Y346772I-85J-2325D01*
G01X267815Y347934D02*
X267944D01*
G01X266494Y348722D02*
G03X267815Y347934I1365J787D01*
G01X264549Y349885D02*
G02X266494Y348722I-70J-2325D01*
G01X263201Y349885D02*
X264549D01*
G01X261996Y351090D02*
X263201Y349885D01*
G01X261996Y352451D02*
Y351090D01*
G01X256948Y357499D02*
X261996Y352451D01*
G01X256948Y358616D02*
Y357499D01*
G01X264958Y380989D02*
Y382652D01*
G01X270713Y375234D02*
X264958Y380989D01*
G01X274704Y375234D02*
X270713D01*
G01X276634Y374072D02*
G03X274704Y375234I-2015J-1163D01*
G01X277940Y373285D02*
G02X276634Y374072I59J1575D01*
G01X278050Y373285D02*
X277940D01*
G01X280039Y369839D02*
G03X278050Y373285I-2040J1120D01*
G01X280014Y369797D02*
X280039Y369839D01*
G01X280014Y368223D02*
G02Y369797I1365J787D01*
G01Y365897D02*
G03Y368223I-2015J1163D01*
G01X279995Y364356D02*
G02X280014Y365897I1384J754D01*
G01X280082Y364205D02*
X279995Y364356D01*
G01X281379Y361209D02*
X280082Y364205D01*
G01X271154Y341335D02*
X271283D01*
G01X269224Y342497D02*
G03X271154Y341335I2015J1163D01*
G01X267918Y343284D02*
G02X269224Y342497I-59J-1575D01*
G01X267789Y343284D02*
X267918D01*
G01X265844Y344447D02*
G03X267789Y343284I2015J1162D01*
G01X264523Y345235D02*
G02X265844Y344447I-44J-1575D01*
G01X262654Y345235D02*
X264523D01*
G01X260848Y347041D02*
X262654Y345235D01*
G01X254392Y347041D02*
X260848D01*
G01X253333Y348100D02*
X254392Y347041D01*
G01X252358Y348100D02*
X253333D01*
G01X264016Y380873D02*
X263179D01*
G01X270405Y374484D02*
X264016Y380873D01*
G01X274678Y374484D02*
X270405D01*
G01X275984Y373697D02*
G03X274678Y374484I-1365J-788D01*
G01X277948Y372534D02*
G02X275984Y373697I51J2326D01*
G01X278043Y372534D02*
X277948D01*
G01X279364Y370172D02*
G03X278043Y372534I-1365J787D01*
G01X279339Y370130D02*
X279364Y370172D01*
G01Y367847D02*
G02X279339Y370130I2015J1164D01*
G01X279383Y367813D02*
X279364Y367847D01*
G01Y366272D02*
G03X279383Y367813I-1365J787D01*
G01X279339Y363989D02*
G02X279364Y366272I2040J1119D01*
G01Y363947D02*
X279339Y363989D01*
G01X279383Y363913D02*
X279364Y363947D01*
G01Y362372D02*
G03X279383Y363913I-1365J787D01*
G01X279364Y361550D02*
G02Y362372I712J411D01*
G01X281525Y359634D02*
X284759Y359260D01*
G01X281335Y359634D02*
X281525D01*
G01X280014Y360422D02*
G03X281335Y359634I1365J787D01*
G01X279364Y361550D02*
X280014Y360422D01*
G01X253792Y349333D02*
X253108Y350017D01*
G01X253792Y348801D02*
Y349333D01*
G01X254804Y347789D02*
X253792Y348801D01*
G01X261158Y347789D02*
X254804D01*
G01X262962Y345985D02*
X261158Y347789D01*
G01X264533Y345985D02*
X262962D01*
G01X266494Y344822D02*
G03X264533Y345985I-2015J-1162D01*
G01X267815Y344034D02*
G02X266494Y344822I44J1575D01*
G01X267944Y344034D02*
X267815D01*
G01X269874Y342872D02*
G03X267944Y344034I-2015J-1163D01*
G01X271180Y342085D02*
G02X269874Y342872I59J1575D01*
G01X271309Y342085D02*
X271180D01*
G01X263465D02*
X264549D01*
G01X263061Y342489D02*
X263465Y342085D01*
G01X256400Y342489D02*
X263061D01*
G01X255448Y343441D02*
X256400Y342489D01*
G01X258648Y379641D02*
X257339D01*
G01X266148Y372141D02*
X258648Y379641D01*
G01X268149Y372141D02*
X266148D01*
G01X273606Y366684D02*
X268149Y372141D01*
G01X274678Y366684D02*
X273606D01*
G01X276003Y364356D02*
G03X274678Y366684I-1384J753D01*
G01X275984Y364322D02*
X276003Y364356D01*
G01X275959Y364280D02*
X275984Y364322D01*
G01Y361997D02*
G02X275959Y364280I2015J1164D01*
G01X276485Y361129D02*
X275984Y361997D01*
G01X276550Y359880D02*
G03X276485Y361129I-1305J558D01*
G01X276634Y358472D02*
G02X276550Y359880I1365J788D01*
G01X276700Y358359D02*
X276634Y358472D01*
G01X277999Y355360D02*
X276700Y358359D01*
G01X268748Y404089D02*
Y404948D01*
G01X282953Y407194D02*
Y409796D01*
G01X286856Y403291D02*
X282953Y407194D01*
G01X289843Y403291D02*
X286856D01*
G01X268544Y403235D02*
X266925D01*
G01X281958Y408201D02*
X280998D01*
G01X282205Y407954D02*
X281958Y408201D01*
G01X282205Y406884D02*
Y407954D01*
G01X354092Y204301D02*
X357892Y200501D01*
G01X354092Y208853D02*
Y204301D01*
G01X354372Y209897D02*
G03X354092Y208853I1808J-1044D01*
G01X354397Y212180D02*
G02X354372Y209897I-2040J-1119D01*
G01Y212222D02*
X354397Y212180D01*
G01X354353Y212256D02*
X354372Y212222D01*
G01Y213797D02*
G03X354353Y212256I1365J-787D01*
G01X354397Y216080D02*
G02X354372Y213797I-2040J-1119D01*
G01Y216122D02*
X354397Y216080D01*
G01X354353Y216156D02*
X354372Y216122D01*
G01X355678Y218484D02*
G03X354353Y216156I59J-1575D01*
G01X328948Y198091D02*
X328148Y197291D01*
G01X328948Y198341D02*
Y198091D01*
G01X326594Y200695D02*
X328948Y198341D01*
G01X326594Y206447D02*
Y200695D01*
G01X322918Y210123D02*
X326594Y206447D01*
G01X322918Y219361D02*
Y210123D01*
G01X294899Y207778D02*
Y209109D01*
G01X295155Y207522D02*
X294899Y207778D01*
G01X296914Y204047D02*
G03X295155Y207522I-2015J1163D01*
G01X296895Y204013D02*
X296914Y204047D01*
G01Y202472D02*
G02X296895Y204013I1365J787D01*
G01X296939Y200189D02*
G03X296914Y202472I-2040J1119D01*
G01Y200147D02*
X296939Y200189D01*
G01X296895Y200113D02*
X296914Y200147D01*
G01X296965Y198492D02*
G02X296895Y200113I1311J869D01*
G01X297258Y198050D02*
X296965Y198492D01*
G01X297258Y195431D02*
Y198050D01*
G01X352188Y200204D02*
Y199049D01*
G01X350598Y201794D02*
X352188Y200204D01*
G01X350598Y208094D02*
Y201794D01*
G01X350592Y208100D02*
X350598Y208094D01*
G01X350592Y208964D02*
Y208100D01*
G01X350342Y209896D02*
G02X350592Y208964I-1614J-932D01*
G01X350307Y212162D02*
G03X350342Y209896I2050J-1102D01*
G01Y212222D02*
X350307Y212162D01*
G01X350342Y213796D02*
G02Y212222I-1364J-787D01*
G01X350307Y216062D02*
G03X350342Y213796I2050J-1102D01*
G01Y216122D02*
X350307Y216062D01*
G01X350342Y217696D02*
G02Y216122I-1364J-787D01*
G01X350307Y219962D02*
G03X350342Y217696I2050J-1102D01*
G01X329698Y198241D02*
X330648Y197291D01*
G01X329698Y198693D02*
Y198241D01*
G01X327344Y201047D02*
X329698Y198693D01*
G01X327344Y206799D02*
Y201047D01*
G01X323669Y210474D02*
X327344Y206799D01*
G01X323669Y218978D02*
Y210474D01*
G01X293534Y204424D02*
G02X293071Y206891I3278J1892D01*
G01X293534Y204423D02*
Y204424D01*
G01Y202097D02*
G03Y204423I-2015J1163D01*
G01X293515Y200556D02*
G02X293534Y202097I1384J754D01*
G01Y200522D02*
X293515Y200556D01*
G01X293559Y200480D02*
X293534Y200522D01*
G01Y198197D02*
G03X293559Y200480I-2015J1164D01*
G01X293248Y197704D02*
X293534Y198197D01*
G01X293248Y195709D02*
Y197704D01*
G01X309318Y198211D02*
X308448Y197341D01*
G01X309318Y199311D02*
Y198211D01*
G01X310001Y199994D02*
X309318Y199311D01*
G01X310001Y202108D02*
Y199994D01*
G01X309830Y202279D02*
X310001Y202108D01*
G01X309830Y209815D02*
Y202279D01*
G01X309783Y209897D02*
X309830Y209815D01*
G01X309758Y212180D02*
G03X309783Y209897I2040J-1119D01*
G01Y212222D02*
X309758Y212180D01*
G01X309802Y212256D02*
X309783Y212222D01*
G01Y213797D02*
G02X309802Y212256I-1365J-787D01*
G01X309758Y216080D02*
G03X309783Y213797I2040J-1119D01*
G01Y216122D02*
X309758Y216080D01*
G01X309802Y216156D02*
X309783Y216122D01*
G01Y217697D02*
G02X309802Y216156I-1365J-787D01*
G01X309758Y219980D02*
G03X309783Y217697I2040J-1119D01*
G01X343486Y199951D02*
Y198703D01*
G01X341355Y202082D02*
X343486Y199951D01*
G01X341355Y202545D02*
Y202082D01*
G01X340853Y204422D02*
G02X341355Y202545I-3257J-1877D01*
G01X340826Y205948D02*
G03X340853Y204422I1392J-739D01*
G01Y205996D02*
X340826Y205948D01*
G01X340878Y206038D02*
X340853Y205996D01*
G01Y208321D02*
G02X340878Y206038I-2015J-1164D01*
G01X340834Y209862D02*
G03X340853Y208321I1384J-754D01*
G01X340921Y210013D02*
X340834Y209862D01*
G01X342218Y213009D02*
X340921Y210013D01*
G01X304326Y198219D02*
X303448Y197341D01*
G01X304326Y201213D02*
Y198219D01*
G01X306614Y203501D02*
X304326Y201213D01*
G01X306614Y211060D02*
Y203501D01*
G01X306403Y211847D02*
G02X306614Y211060I-1364J-787D01*
G01X306368Y211907D02*
X306403Y211847D01*
G01Y214173D02*
G03X306368Y211907I2015J-1164D01*
G01X306403Y215747D02*
G02Y214173I-1364J-787D01*
G01X306368Y215807D02*
X306403Y215747D01*
G01Y218073D02*
G03X306368Y215807I2015J-1164D01*
G01X307366Y211060D02*
X307365Y209837D01*
G01X307089Y212162D02*
G02X307366Y211060I-2050J-1101D01*
G01X307054Y212222D02*
X307089Y212162D01*
G01X307054Y213796D02*
G03Y212222I1364J-787D01*
G01X307089Y216062D02*
G02X307054Y213796I-2050J-1102D01*
G01Y216122D02*
X307089Y216062D01*
G01X307054Y217696D02*
G03Y216122I1364J-787D01*
G01X307089Y219962D02*
G02X307054Y217696I-2050J-1102D01*
G01X305076Y198213D02*
X305948Y197341D01*
G01X305076Y200901D02*
Y198213D01*
G01X307365Y203190D02*
X305076Y200901D01*
G01X307365Y209837D02*
Y203190D01*
G01X340101Y199391D02*
Y197885D01*
G01X337252Y202240D02*
X340101Y199391D01*
G01X337252Y214580D02*
Y202240D01*
G01X337263Y215001D02*
X337252Y214580D01*
G01X337473Y215747D02*
G03X337263Y215001I1365J-787D01*
G01X337498Y215789D02*
X337473Y215747D01*
G01Y218072D02*
G02X337498Y215789I-2015J-1164D01*
G01X323842Y197385D02*
X323148Y196691D01*
G01X323842Y198201D02*
Y197385D01*
G01X321836Y200207D02*
X323842Y198201D01*
G01X321836Y201888D02*
Y200207D01*
G01X322359Y202801D02*
X321836Y201888D01*
G01X322359Y206444D02*
Y202801D01*
G01X319898Y208905D02*
X322359Y206444D01*
G01X319898Y217424D02*
Y208905D01*
G01X320133Y217659D02*
X319898Y217424D01*
G01X320133Y218869D02*
Y217659D01*
G01X293078Y203032D02*
G02X292990Y202694I-1560J226D01*
G01X324658Y197641D02*
X325648Y196651D01*
G01X324658Y198479D02*
Y197641D01*
G01X322586Y200551D02*
X324658Y198479D01*
G01X322586Y201656D02*
Y200551D01*
G01X323109Y202569D02*
X322586Y201656D01*
G01X323109Y206784D02*
Y202569D01*
G01X320648Y209245D02*
X323109Y206784D01*
G01X320648Y217092D02*
Y209245D01*
G01X320883Y217327D02*
X320648Y217092D01*
G01X320883Y218870D02*
Y217327D01*
G01X341660Y200250D02*
Y197909D01*
G01X340501Y201409D02*
X341660Y200250D01*
G01X340501Y203002D02*
Y201409D01*
G01X340222Y204012D02*
G02X340501Y203002I-1802J-1041D01*
G01X340203Y204046D02*
X340222Y204012D01*
G01X340168Y206312D02*
G03X340203Y204046I2050J-1102D01*
G01X340230Y206420D02*
X340168Y206312D01*
G01X340203Y207946D02*
G02X340230Y206420I-1365J-787D01*
G01X340178Y210229D02*
G03X340203Y207946I2040J-1119D01*
G01Y210271D02*
X340178Y210229D01*
G01X340222Y210305D02*
X340203Y210271D01*
G01Y211846D02*
G02X340222Y210305I-1365J-787D01*
G01X338838Y214960D02*
X340203Y211846D01*
G01X310068Y198221D02*
X310948Y197341D01*
G01X310068Y198977D02*
Y198221D01*
G01X310751Y199660D02*
X310068Y198977D01*
G01X310751Y202416D02*
Y199660D01*
G01X310580Y202587D02*
X310751Y202416D01*
G01X310580Y210017D02*
Y202587D01*
G01X310433Y210272D02*
X310580Y210017D01*
G01X310414Y211813D02*
G03X310433Y210272I1384J-754D01*
G01Y211847D02*
X310414Y211813D01*
G01X310458Y211889D02*
X310433Y211847D01*
G01Y214172D02*
G02X310458Y211889I-2015J-1164D01*
G01X310414Y215713D02*
G03X310433Y214172I1384J-754D01*
G01Y215747D02*
X310414Y215713D01*
G01X310458Y215789D02*
X310433Y215747D01*
G01Y218072D02*
G02X310458Y215789I-2015J-1164D01*
G01X354188Y200104D02*
Y198734D01*
G01X351492Y202800D02*
X354188Y200104D01*
G01X351492Y208410D02*
Y202800D01*
G01X350993Y210273D02*
G02X351492Y208410I-3229J-1863D01*
G01X350993Y211847D02*
G03Y210273I1364J-787D01*
G01X351028Y211907D02*
X350993Y211847D01*
G01Y214173D02*
G02X351028Y211907I-2015J-1164D01*
G01X350993Y215747D02*
G03Y214173I1364J-787D01*
G01X351028Y215807D02*
X350993Y215747D01*
G01Y218073D02*
G02X351028Y215807I-2015J-1164D01*
G01X347613Y217698D02*
G03Y220024I-2015J1163D01*
G01X347158Y216254D02*
G02X347613Y217698I3483J-304D01*
G01X347167Y214812D02*
G03X347158Y216254I-7080J677D01*
G01X346963Y214174D02*
G03X347167Y214812I-1365J788D01*
G01X346963Y211848D02*
G02Y214174I2015J1163D01*
G01Y210274D02*
G03Y211848I-1364J787D01*
G01Y207948D02*
G02Y210274I2015J1163D01*
G01Y206374D02*
G03Y207948I-1364J787D01*
G01Y204048D02*
G02Y206374I2015J1163D01*
G01X347198Y203641D02*
X346963Y204048D01*
G01X347198Y201193D02*
Y203641D01*
G01X348188Y200203D02*
X347198Y201193D01*
G01X348188Y198224D02*
Y200203D01*
G01X350188Y200204D02*
Y198928D01*
G01X347992Y202400D02*
X350188Y200204D01*
G01X347992Y203948D02*
Y202400D01*
G01X347745Y204195D02*
X347992Y203948D01*
G01X347613Y204424D02*
X347745Y204195D01*
G01X347613Y205998D02*
G03Y204424I1365J-787D01*
G01Y208324D02*
G02Y205998I-2015J-1163D01*
G01Y209898D02*
G03Y208324I1365J-787D01*
G01Y212224D02*
G02Y209898I-2015J-1163D01*
G01Y213798D02*
G03Y212224I1365J-787D01*
G01X347846Y214361D02*
G02X347613Y213798I-2248J601D01*
G01X348978Y216909D02*
X347846Y214361D01*
G01X353697Y215789D02*
G02X353722Y218072I2040J1119D01*
G01Y215747D02*
X353697Y215789D01*
G01X353741Y215713D02*
X353722Y215747D01*
G01Y214172D02*
G03X353741Y215713I-1365J787D01*
G01X353697Y211889D02*
G02X353722Y214172I2040J1119D01*
G01Y211847D02*
X353697Y211889D01*
G01X353741Y211813D02*
X353722Y211847D01*
G01Y210272D02*
G03X353741Y211813I-1365J787D01*
G01X353292Y208665D02*
G02X353722Y210272I3217J0D01*
G01X353292Y203100D02*
Y208665D01*
G01X356188Y200204D02*
X353292Y203100D01*
G01X346576Y199816D02*
Y198054D01*
G01X343998Y202394D02*
X346576Y199816D01*
G01X343998Y203165D02*
Y202394D01*
G01X344234Y204048D02*
G03X343998Y203165I1535J-883D01*
G01X344465Y204607D02*
G02X344234Y204048I-2247J601D01*
G01X344258Y206330D02*
G02X344465Y204607I-2040J-1119D01*
G01X344233Y206372D02*
X344258Y206330D01*
G01X344233Y207946D02*
G03Y206372I1365J-787D01*
G01Y210272D02*
G02Y207946I-2015J-1163D01*
G01X344214Y211813D02*
G03X344233Y210272I1384J-754D01*
G01Y211847D02*
X344214Y211813D01*
G01X344258Y211889D02*
X344233Y211847D01*
G01Y214172D02*
G02X344258Y211889I-2015J-1164D01*
G01X344214Y215713D02*
G03X344233Y214172I1384J-754D01*
G01X344972Y216433D02*
G03X344214Y215713I736J-1534D01*
G01X345644Y216909D02*
G02X344972Y216433I-1731J1732D01*
G01X345691Y216956D02*
X345644Y216909D01*
G01X346281Y217441D02*
G03X345691Y216956I697J-1449D01*
G01X346234Y220303D02*
G02X346281Y217441I-636J-1442D01*
G01X296508Y197737D02*
Y195741D01*
G01X296264Y198197D02*
X296508Y197737D01*
G01X296239Y200480D02*
G03X296264Y198197I2040J-1119D01*
G01Y200522D02*
X296239Y200480D01*
G01X296283Y200556D02*
X296264Y200522D01*
G01Y202097D02*
G02X296283Y200556I-1365J-787D01*
G01X296264Y204423D02*
G03Y202097I2015J-1163D01*
G01X295127Y206769D02*
G02X296264Y204423I-228J-1559D01*
G01X294899Y206541D02*
X295127Y206769D01*
G01X294899Y205210D02*
Y206541D01*
G01X345037Y200293D02*
Y198346D01*
G01X343248Y202082D02*
X345037Y200293D01*
G01X343248Y203841D02*
Y202082D01*
G01X343583Y204423D02*
X343248Y203841D01*
G01X343583Y205997D02*
G02Y204423I-1365J-787D01*
G01X343558Y206039D02*
X343583Y205997D01*
G01Y208322D02*
G03X343558Y206039I2015J-1164D01*
G01X343602Y208356D02*
X343583Y208322D01*
G01Y209897D02*
G02X343602Y208356I-1365J-787D01*
G01X343558Y212180D02*
G03X343583Y209897I2040J-1119D01*
G01Y212222D02*
X343558Y212180D01*
G01X343602Y212256D02*
X343583Y212222D01*
G01Y213797D02*
G02X343602Y212256I-1365J-787D01*
G01X343558Y216080D02*
G03X343583Y213797I2040J-1119D01*
G01Y216122D02*
X343558Y216080D01*
G01X343902Y216682D02*
X343583Y216122D01*
G01X345451Y218713D02*
G03X343902Y216682I6772J-6771D01*
G01X323514Y219957D02*
X322918Y219361D01*
G01X323514Y220809D02*
Y219957D01*
G01X323303Y221597D02*
G02X323514Y220809I-1366J-788D01*
G01X323278Y223880D02*
G03X323303Y221597I2040J-1119D01*
G01Y223922D02*
X323278Y223880D01*
G01X323322Y223956D02*
X323303Y223922D01*
G01Y225497D02*
G02X323322Y223956I-1365J-787D01*
G01X323303Y227823D02*
G03Y225497I2015J-1163D01*
G01Y229397D02*
G02Y227823I-1365J-787D01*
G01X323278Y229439D02*
X323303Y229397D01*
G01Y231722D02*
G03X323278Y229439I2015J-1164D01*
G01X323322Y231756D02*
X323303Y231722D01*
G01Y233297D02*
G02X323322Y231756I-1365J-787D01*
G01X323278Y235580D02*
G03X323303Y233297I2040J-1119D01*
G01Y235622D02*
X323278Y235580D01*
G01X323322Y235656D02*
X323303Y235622D01*
G01Y237197D02*
G02X323322Y235656I-1365J-787D01*
G01X323278Y239480D02*
G03X323303Y237197I2040J-1119D01*
G01Y239522D02*
X323278Y239480D01*
G01X323322Y239556D02*
X323303Y239522D01*
G01Y241097D02*
G02X323322Y239556I-1365J-787D01*
G01X323278Y243380D02*
G03X323303Y241097I2040J-1119D01*
G01Y243422D02*
X323278Y243380D01*
G01X323322Y243456D02*
X323303Y243422D01*
G01Y244997D02*
G02X323322Y243456I-1365J-787D01*
G01X323278Y247280D02*
G03X323303Y244997I2040J-1119D01*
G01Y247322D02*
X323278Y247280D01*
G01X323322Y247356D02*
X323303Y247322D01*
G01Y248897D02*
G02X323322Y247356I-1365J-787D01*
G01X323278Y251180D02*
G03X323303Y248897I2040J-1119D01*
G01Y251222D02*
X323278Y251180D01*
G01X323322Y251256D02*
X323303Y251222D01*
G01Y252797D02*
G02X323322Y251256I-1365J-787D01*
G01X323278Y255080D02*
G03X323303Y252797I2040J-1119D01*
G01Y255122D02*
X323278Y255080D01*
G01X323322Y255156D02*
X323303Y255122D01*
G01Y256697D02*
G02X323322Y255156I-1365J-787D01*
G01X323278Y258980D02*
G03X323303Y256697I2040J-1119D01*
G01Y259022D02*
X323278Y258980D01*
G01X323322Y259056D02*
X323303Y259022D01*
G01Y260597D02*
G02X323322Y259056I-1365J-787D01*
G01X323278Y262880D02*
G03X323303Y260597I2040J-1119D01*
G01Y262922D02*
X323278Y262880D01*
G01X323322Y262956D02*
X323303Y262922D01*
G01Y264497D02*
G02X323322Y262956I-1365J-787D01*
G01X323237Y264610D02*
X323303Y264497D01*
G01X321938Y267609D02*
X323237Y264610D01*
G01X350342Y220022D02*
X350307Y219962D01*
G01X350342Y221596D02*
G02Y220022I-1364J-787D01*
G01X350307Y223862D02*
G03X350342Y221596I2050J-1102D01*
G01Y223922D02*
X350307Y223862D01*
G01X350342Y225496D02*
G02Y223922I-1364J-787D01*
G01X350279Y225603D02*
X350342Y225496D01*
G01X348978Y228610D02*
X350279Y225603D01*
G01X324265Y219574D02*
X323669Y218978D01*
G01X324265Y220809D02*
Y219574D01*
G01X323953Y221972D02*
G02X324265Y220809I-2015J-1164D01*
G01X323934Y223513D02*
G03X323953Y221972I1384J-754D01*
G01Y223547D02*
X323934Y223513D01*
G01X323978Y223589D02*
X323953Y223547D01*
G01Y225872D02*
G02X323978Y223589I-2015J-1164D01*
G01X323934Y227413D02*
G03X323953Y225872I1384J-754D01*
G01Y227447D02*
X323934Y227413D01*
G01X323978Y229730D02*
G02X323953Y227447I-2040J-1119D01*
G01Y229772D02*
X323978Y229730D01*
G01X323953Y231346D02*
G03Y229772I1365J-787D01*
G01Y233672D02*
G02Y231346I-2015J-1163D01*
G01X323934Y235213D02*
G03X323953Y233672I1384J-754D01*
G01Y235247D02*
X323934Y235213D01*
G01X323978Y235289D02*
X323953Y235247D01*
G01Y237572D02*
G02X323978Y235289I-2015J-1164D01*
G01X323934Y239113D02*
G03X323953Y237572I1384J-754D01*
G01Y239147D02*
X323934Y239113D01*
G01X323978Y239189D02*
X323953Y239147D01*
G01Y241472D02*
G02X323978Y239189I-2015J-1164D01*
G01X323934Y243013D02*
G03X323953Y241472I1384J-754D01*
G01Y243047D02*
X323934Y243013D01*
G01X323978Y243089D02*
X323953Y243047D01*
G01Y245372D02*
G02X323978Y243089I-2015J-1164D01*
G01X323934Y246913D02*
G03X323953Y245372I1384J-754D01*
G01Y246947D02*
X323934Y246913D01*
G01X323978Y246989D02*
X323953Y246947D01*
G01Y249272D02*
G02X323978Y246989I-2015J-1164D01*
G01X323934Y250813D02*
G03X323953Y249272I1384J-754D01*
G01Y250847D02*
X323934Y250813D01*
G01X323978Y250889D02*
X323953Y250847D01*
G01Y253172D02*
G02X323978Y250889I-2015J-1164D01*
G01X323934Y254713D02*
G03X323953Y253172I1384J-754D01*
G01Y254747D02*
X323934Y254713D01*
G01X323978Y254789D02*
X323953Y254747D01*
G01Y257072D02*
G02X323978Y254789I-2015J-1164D01*
G01X323934Y258613D02*
G03X323953Y257072I1384J-754D01*
G01Y258647D02*
X323934Y258613D01*
G01X323978Y258689D02*
X323953Y258647D01*
G01Y260972D02*
G02X323978Y258689I-2015J-1164D01*
G01X323934Y262513D02*
G03X323953Y260972I1384J-754D01*
G01Y262547D02*
X323934Y262513D01*
G01X323978Y262589D02*
X323953Y262547D01*
G01Y264872D02*
G02X323978Y262589I-2015J-1164D01*
G01X323744Y265638D02*
G03X323953Y264872I1586J21D01*
G01X323744Y268321D02*
Y265638D01*
G01X323203Y268862D02*
X323744Y268321D01*
G01X321938Y271509D02*
X323203Y268862D01*
G01X309783Y220022D02*
X309758Y219980D01*
G01X309802Y220056D02*
X309783Y220022D01*
G01Y221597D02*
G02X309802Y220056I-1365J-787D01*
G01X309758Y223880D02*
G03X309783Y221597I2040J-1119D01*
G01Y223922D02*
X309758Y223880D01*
G01X309802Y223956D02*
X309783Y223922D01*
G01Y225497D02*
G02X309802Y223956I-1365J-787D01*
G01X309783Y227823D02*
G03Y225497I2015J-1163D01*
G01Y229397D02*
G02Y227823I-1365J-787D01*
G01X309758Y229439D02*
X309783Y229397D01*
G01Y231722D02*
G03X309758Y229439I2015J-1164D01*
G01X309802Y231756D02*
X309783Y231722D01*
G01Y233297D02*
G02X309802Y231756I-1365J-787D01*
G01X309758Y235580D02*
G03X309783Y233297I2040J-1119D01*
G01Y235622D02*
X309758Y235580D01*
G01X309802Y235656D02*
X309783Y235622D01*
G01Y237197D02*
G02X309802Y235656I-1365J-787D01*
G01X309758Y239480D02*
G03X309783Y237197I2040J-1119D01*
G01Y239522D02*
X309758Y239480D01*
G01X309802Y239556D02*
X309783Y239522D01*
G01Y241097D02*
G02X309802Y239556I-1365J-787D01*
G01X309758Y243380D02*
G03X309783Y241097I2040J-1119D01*
G01Y243422D02*
X309758Y243380D01*
G01X309802Y243456D02*
X309783Y243422D01*
G01Y244997D02*
G02X309802Y243456I-1365J-787D01*
G01X309758Y247280D02*
G03X309783Y244997I2040J-1119D01*
G01Y247322D02*
X309758Y247280D01*
G01X309802Y247356D02*
X309783Y247322D01*
G01Y248897D02*
G02X309802Y247356I-1365J-787D01*
G01X309758Y251180D02*
G03X309783Y248897I2040J-1119D01*
G01Y251222D02*
X309758Y251180D01*
G01X309802Y251256D02*
X309783Y251222D01*
G01Y252797D02*
G02X309802Y251256I-1365J-787D01*
G01X309758Y255080D02*
G03X309783Y252797I2040J-1119D01*
G01Y255122D02*
X309758Y255080D01*
G01X309802Y255156D02*
X309783Y255122D01*
G01Y256697D02*
G02X309802Y255156I-1365J-787D01*
G01X309758Y258980D02*
G03X309783Y256697I2040J-1119D01*
G01Y259022D02*
X309758Y258980D01*
G01X309802Y259056D02*
X309783Y259022D01*
G01Y260596D02*
G02X309802Y259056I-1363J-787D01*
G01X309783Y262922D02*
G03Y260596I2015J-1163D01*
G01X309799Y262950D02*
X309783Y262922D01*
G01X310890Y264585D02*
G03X309799Y262950I12078J-9241D01*
G01X311798Y265660D02*
G03X310890Y264585I10671J-9934D01*
G01X306403Y219647D02*
G02Y218073I-1364J-787D01*
G01X306368Y219707D02*
X306403Y219647D01*
G01Y221973D02*
G03X306368Y219707I2015J-1164D01*
G01X306403Y223547D02*
G02Y221973I-1364J-787D01*
G01X306368Y223607D02*
X306403Y223547D01*
G01Y225873D02*
G03X306368Y223607I2015J-1164D01*
G01X306403Y227447D02*
G02Y225873I-1364J-787D01*
G01X306378Y229730D02*
G03X306403Y227447I2040J-1119D01*
G01Y229772D02*
X306378Y229730D01*
G01X306403Y231346D02*
G02Y229772I-1364J-787D01*
G01X306378Y231388D02*
X306403Y231346D01*
G01Y233673D02*
G03X306378Y231388I2015J-1165D01*
G01X306403Y235247D02*
G02Y233673I-1364J-787D01*
G01X306368Y235307D02*
X306403Y235247D01*
G01Y237573D02*
G03X306368Y235307I2015J-1164D01*
G01X306403Y239147D02*
G02Y237573I-1364J-787D01*
G01X306368Y239207D02*
X306403Y239147D01*
G01Y241473D02*
G03X306368Y239207I2015J-1164D01*
G01X306403Y243047D02*
G02Y241473I-1364J-787D01*
G01X306368Y243107D02*
X306403Y243047D01*
G01Y245373D02*
G03X306368Y243107I2015J-1164D01*
G01X306403Y246947D02*
G02Y245373I-1364J-787D01*
G01X306368Y247007D02*
X306403Y246947D01*
G01Y249273D02*
G03X306368Y247007I2015J-1164D01*
G01X306403Y250847D02*
G02Y249273I-1364J-787D01*
G01X306368Y250907D02*
X306403Y250847D01*
G01Y253173D02*
G03X306368Y250907I2015J-1164D01*
G01X306403Y254747D02*
G02Y253173I-1364J-787D01*
G01X306368Y254807D02*
X306403Y254747D01*
G01Y257073D02*
G03X306368Y254807I2015J-1164D01*
G01X306403Y258647D02*
G02Y257073I-1364J-787D01*
G01X306368Y258707D02*
X306403Y258647D01*
G01Y260972D02*
G03X306368Y258707I2017J-1164D01*
G01X306403Y262546D02*
G02Y260972I-1364J-787D01*
G01Y264872D02*
G03Y262546I2015J-1163D01*
G01X306419Y264900D02*
X306403Y264872D01*
G01X308187Y267360D02*
G03X306419Y264900I11400J-10059D01*
G01X308418Y267609D02*
X308187Y267360D01*
G01X307054Y220022D02*
X307089Y219962D01*
G01X307054Y221596D02*
G03Y220022I1364J-787D01*
G01X307089Y223862D02*
G02X307054Y221596I-2050J-1102D01*
G01Y223922D02*
X307089Y223862D01*
G01X307054Y225496D02*
G03Y223922I1364J-787D01*
G01X307079Y227781D02*
G02X307054Y225496I-2040J-1120D01*
G01Y227823D02*
X307079Y227781D01*
G01X307054Y229397D02*
G03Y227823I1364J-787D01*
G01X307079Y229439D02*
X307054Y229397D01*
G01Y231722D02*
G02X307079Y229439I-2015J-1164D01*
G01X307054Y233296D02*
G03Y231722I1364J-787D01*
G01X307089Y235562D02*
G02X307054Y233296I-2050J-1102D01*
G01Y235622D02*
X307089Y235562D01*
G01X307054Y237196D02*
G03Y235622I1364J-787D01*
G01X307089Y239462D02*
G02X307054Y237196I-2050J-1102D01*
G01Y239522D02*
X307089Y239462D01*
G01X307054Y241096D02*
G03Y239522I1364J-787D01*
G01X307089Y243362D02*
G02X307054Y241096I-2050J-1102D01*
G01Y243422D02*
X307089Y243362D01*
G01X307054Y244996D02*
G03Y243422I1364J-787D01*
G01X307089Y247262D02*
G02X307054Y244996I-2050J-1102D01*
G01Y247322D02*
X307089Y247262D01*
G01X307054Y248896D02*
G03Y247322I1364J-787D01*
G01X307089Y251162D02*
G02X307054Y248896I-2050J-1102D01*
G01Y251222D02*
X307089Y251162D01*
G01X307054Y252796D02*
G03Y251222I1364J-787D01*
G01X307089Y255062D02*
G02X307054Y252796I-2050J-1102D01*
G01Y255122D02*
X307089Y255062D01*
G01X307054Y256696D02*
G03Y255122I1364J-787D01*
G01X307089Y258962D02*
G02X307054Y256696I-2050J-1102D01*
G01Y259022D02*
X307089Y258962D01*
G01X307054Y260596D02*
G03Y259022I1364J-787D01*
G01Y262922D02*
G02Y260596I-2015J-1163D01*
G01Y264496D02*
G03Y262922I1364J-787D01*
G01X309017Y266135D02*
G03X307054Y264496I1191J-3422D01*
G01X309026Y266138D02*
X309017Y266135D01*
G01X309498Y268756D02*
G02X309026Y266138I-1088J-1155D01*
G01X308418Y271509D02*
X309498Y268756D01*
G01X337454Y219613D02*
G03X337473Y218072I1384J-754D01*
G01X337541Y219764D02*
X337454Y219613D01*
G01X338838Y222760D02*
X337541Y219764D01*
G01X320035Y219410D02*
G02X320133Y218869I-1444J-541D01*
G01X319898Y219689D02*
G02X320035Y219410I-1351J-836D01*
G01X319923Y221972D02*
G03X319898Y219689I2015J-1164D01*
G01X319942Y223513D02*
G02X319923Y221972I-1384J-754D01*
G01Y223547D02*
X319942Y223513D01*
G01X319898Y223589D02*
X319923Y223547D01*
G01Y225872D02*
G03X319898Y223589I2015J-1164D01*
G01X319942Y227413D02*
G02X319923Y225872I-1384J-754D01*
G01Y227447D02*
X319942Y227413D01*
G01X319898Y229730D02*
G03X319923Y227447I2040J-1119D01*
G01Y229772D02*
X319898Y229730D01*
G01X319923Y231346D02*
G02Y229772I-1365J-787D01*
G01Y233672D02*
G03Y231346I2015J-1163D01*
G01X319942Y235213D02*
G02X319923Y233672I-1384J-754D01*
G01Y235247D02*
X319942Y235213D01*
G01X319898Y235289D02*
X319923Y235247D01*
G01Y237572D02*
G03X319898Y235289I2015J-1164D01*
G01X319942Y239113D02*
G02X319923Y237572I-1384J-754D01*
G01Y239147D02*
X319942Y239113D01*
G01X319898Y239189D02*
X319923Y239147D01*
G01Y241472D02*
G03X319898Y239189I2015J-1164D01*
G01X319942Y243013D02*
G02X319923Y241472I-1384J-754D01*
G01Y243047D02*
X319942Y243013D01*
G01X319898Y243089D02*
X319923Y243047D01*
G01Y245372D02*
G03X319898Y243089I2015J-1164D01*
G01X319942Y246913D02*
G02X319923Y245372I-1384J-754D01*
G01Y246947D02*
X319942Y246913D01*
G01X319898Y246989D02*
X319923Y246947D01*
G01Y249272D02*
G03X319898Y246989I2015J-1164D01*
G01X319942Y250813D02*
G02X319923Y249272I-1384J-754D01*
G01Y250847D02*
X319942Y250813D01*
G01X319898Y250889D02*
X319923Y250847D01*
G01Y253172D02*
G03X319898Y250889I2015J-1164D01*
G01X319942Y254713D02*
G02X319923Y253172I-1384J-754D01*
G01Y254747D02*
X319942Y254713D01*
G01X319898Y254789D02*
X319923Y254747D01*
G01Y257072D02*
G03X319898Y254789I2015J-1164D01*
G01X319942Y258613D02*
G02X319923Y257072I-1384J-754D01*
G01Y258647D02*
X319942Y258613D01*
G01X319898Y258689D02*
X319923Y258647D01*
G01Y260972D02*
G03X319898Y258689I2018J-1164D01*
G01X319923Y262546D02*
G02Y260972I-1365J-787D01*
G01X319898Y262589D02*
G03X319923Y262546I896J492D01*
G01X319806Y264642D02*
G03X319898Y262589I2131J-933D01*
G01X319712Y264994D02*
X319806Y264642D01*
G01X318558Y265660D02*
X319712Y264994D01*
G01X320744Y219658D02*
G02X320883Y218870I-2162J-788D01*
G01X320554Y220052D02*
G02X320744Y219658I-1868J-1144D01*
G01X320572Y221598D02*
G03X320554Y220052I1366J-789D01*
G01X320573Y221597D02*
X320572Y221598D01*
G01X320598Y223880D02*
G02X320573Y221597I-2040J-1119D01*
G01Y223922D02*
X320598Y223880D01*
G01X320554Y223956D02*
X320573Y223922D01*
G01Y225497D02*
G03X320554Y223956I1365J-787D01*
G01X320573Y227823D02*
G02Y225497I-2015J-1163D01*
G01Y229397D02*
G03Y227823I1365J-787D01*
G01X320598Y229439D02*
X320573Y229397D01*
G01Y231722D02*
G02X320598Y229439I-2015J-1164D01*
G01X320554Y231756D02*
X320573Y231722D01*
G01Y233297D02*
G03X320554Y231756I1365J-787D01*
G01X320598Y235580D02*
G02X320573Y233297I-2040J-1119D01*
G01Y235622D02*
X320598Y235580D01*
G01X320554Y235656D02*
X320573Y235622D01*
G01Y237197D02*
G03X320554Y235656I1365J-787D01*
G01X320598Y239480D02*
G02X320573Y237197I-2040J-1119D01*
G01Y239522D02*
X320598Y239480D01*
G01X320554Y239556D02*
X320573Y239522D01*
G01Y241097D02*
G03X320554Y239556I1365J-787D01*
G01X320598Y243380D02*
G02X320573Y241097I-2040J-1119D01*
G01Y243422D02*
X320598Y243380D01*
G01X320554Y243456D02*
X320573Y243422D01*
G01Y244997D02*
G03X320554Y243456I1365J-787D01*
G01X320598Y247280D02*
G02X320573Y244997I-2040J-1119D01*
G01Y247322D02*
X320598Y247280D01*
G01X320554Y247356D02*
X320573Y247322D01*
G01Y248897D02*
G03X320554Y247356I1365J-787D01*
G01X320598Y251180D02*
G02X320573Y248897I-2040J-1119D01*
G01Y251222D02*
X320598Y251180D01*
G01X320554Y251256D02*
X320573Y251222D01*
G01Y252797D02*
G03X320554Y251256I1365J-787D01*
G01X320598Y255080D02*
G02X320573Y252797I-2040J-1119D01*
G01Y255122D02*
X320598Y255080D01*
G01X320554Y255156D02*
X320573Y255122D01*
G01Y256697D02*
G03X320554Y255156I1365J-787D01*
G01X320598Y258980D02*
G02X320573Y256697I-2040J-1119D01*
G01Y259022D02*
X320598Y258980D01*
G01X320554Y259056D02*
X320573Y259022D01*
G01Y260596D02*
G03X320554Y259056I1363J-787D01*
G01X320573Y262922D02*
G02Y260596I-2015J-1163D01*
G01Y264496D02*
G03Y262922I1365J-787D01*
G01Y266822D02*
G02Y264496I-2015J-1163D01*
G01X320110Y269289D02*
G03X320573Y266822I3741J-575D01*
G01X319923Y270346D02*
G02X320110Y269289I-1365J-787D01*
G01X319737Y270754D02*
G03X319923Y270346I2200J757D01*
G01X318558Y273460D02*
X319737Y270754D01*
G01X310414Y219613D02*
G03X310433Y218072I1384J-754D01*
G01Y219647D02*
X310414Y219613D01*
G01X310458Y219689D02*
X310433Y219647D01*
G01Y221972D02*
G02X310458Y219689I-2015J-1164D01*
G01X310414Y223513D02*
G03X310433Y221972I1384J-754D01*
G01Y223547D02*
X310414Y223513D01*
G01X310458Y223589D02*
X310433Y223547D01*
G01Y225872D02*
G02X310458Y223589I-2015J-1164D01*
G01X310414Y227413D02*
G03X310433Y225872I1384J-754D01*
G01Y227447D02*
X310414Y227413D01*
G01X310458Y229730D02*
G02X310433Y227447I-2040J-1119D01*
G01Y229772D02*
X310458Y229730D01*
G01X310433Y231346D02*
G03Y229772I1365J-787D01*
G01Y233672D02*
G02Y231346I-2015J-1163D01*
G01X310414Y235213D02*
G03X310433Y233672I1384J-754D01*
G01Y235247D02*
X310414Y235213D01*
G01X310458Y235289D02*
X310433Y235247D01*
G01Y237572D02*
G02X310458Y235289I-2015J-1164D01*
G01X310414Y239113D02*
G03X310433Y237572I1384J-754D01*
G01Y239147D02*
X310414Y239113D01*
G01X310458Y239189D02*
X310433Y239147D01*
G01Y241472D02*
G02X310458Y239189I-2015J-1164D01*
G01X310414Y243013D02*
G03X310433Y241472I1384J-754D01*
G01Y243047D02*
X310414Y243013D01*
G01X310458Y243089D02*
X310433Y243047D01*
G01Y245372D02*
G02X310458Y243089I-2015J-1164D01*
G01X310414Y246913D02*
G03X310433Y245372I1384J-754D01*
G01Y246947D02*
X310414Y246913D01*
G01X310458Y246989D02*
X310433Y246947D01*
G01Y249272D02*
G02X310458Y246989I-2015J-1164D01*
G01X310414Y250813D02*
G03X310433Y249272I1384J-754D01*
G01Y250847D02*
X310414Y250813D01*
G01X310458Y250889D02*
X310433Y250847D01*
G01Y253172D02*
G02X310458Y250889I-2015J-1164D01*
G01X310414Y254713D02*
G03X310433Y253172I1384J-754D01*
G01Y254747D02*
X310414Y254713D01*
G01X310458Y254789D02*
X310433Y254747D01*
G01Y257072D02*
G02X310458Y254789I-2015J-1164D01*
G01X310414Y258613D02*
G03X310433Y257072I1384J-754D01*
G01Y258647D02*
X310414Y258613D01*
G01X310458Y258689D02*
X310433Y258647D01*
G01Y260972D02*
G02X310458Y258689I-2018J-1164D01*
G01X310433Y262546D02*
G03Y260972I1365J-787D01*
G01X312372Y264192D02*
G03X310433Y262546I1328J-3530D01*
G01X313048Y266618D02*
G02X312372Y264192I-1250J-959D01*
G01X311194Y268104D02*
G02X313048Y266618I-1636J-3940D01*
G01X310433Y270346D02*
G03X311194Y268104I1365J-787D01*
G01X311798Y273460D02*
X310433Y270346D01*
G01X350993Y219647D02*
G03Y218073I1364J-787D01*
G01X351028Y219707D02*
X350993Y219647D01*
G01Y221973D02*
G02X351028Y219707I-2015J-1164D01*
G01X350993Y223547D02*
G03Y221973I1364J-787D01*
G01X351028Y223607D02*
X350993Y223547D01*
G01Y225873D02*
G02X351028Y223607I-2015J-1164D01*
G01X350993Y227447D02*
G03Y225873I1364J-787D01*
G01X351983Y229163D02*
X350993Y227447D01*
G01X352357Y230559D02*
G02X351983Y229163I-2793J0D01*
G01X347548Y227937D02*
X345598Y230559D01*
G01X347613Y227824D02*
X347548Y227937D01*
G01X347613Y225498D02*
G03Y227824I-2015J1163D01*
G01Y223924D02*
G02Y225498I1365J787D01*
G01Y221598D02*
G03Y223924I-2015J1163D01*
G01Y220024D02*
G02Y221598I1365J787D01*
G01X353983Y222423D02*
G02X355737Y224709I9566J-5524D01*
G01X353722Y221972D02*
X353983Y222423D01*
G01X353697Y219689D02*
G02X353722Y221972I2040J1119D01*
G01Y219647D02*
X353697Y219689D01*
G01X353741Y219613D02*
X353722Y219647D01*
G01Y218072D02*
G03X353741Y219613I-1365J787D01*
G01X344361Y221255D02*
X346234Y220303D01*
G01X342218Y224709D02*
X344361Y221255D01*
G01X345598Y218860D02*
X345451Y218713D01*
G01X327314Y340956D02*
G02X327333Y342497I1384J754D01*
G01Y340922D02*
X327314Y340956D01*
G01X327358Y340880D02*
X327333Y340922D01*
G01Y338597D02*
G03X327358Y340880I-2015J1164D01*
G01X327314Y337056D02*
G02X327333Y338597I1384J754D01*
G01Y337022D02*
X327314Y337056D01*
G01X327358Y336980D02*
X327333Y337022D01*
G01Y334697D02*
G03X327358Y336980I-2015J1164D01*
G01X326959Y334040D02*
X327333Y334697D01*
G01X325424Y331976D02*
X326959Y334040D01*
G01X325318Y331960D02*
X325424Y331976D01*
G01X313138Y340589D02*
G02X313163Y342872I2040J1119D01*
G01Y340547D02*
X313138Y340589D01*
G01X313182Y340513D02*
X313163Y340547D01*
G01Y338972D02*
G03X313182Y340513I-1365J787D01*
G01X313138Y336689D02*
G02X313163Y338972I2040J1119D01*
G01Y336647D02*
X313138Y336689D01*
G01X313182Y336613D02*
X313163Y336647D01*
G01Y335072D02*
G03X313182Y336613I-1365J787D01*
G01X313138Y332789D02*
G02X313163Y335072I2040J1119D01*
G01Y332747D02*
X313138Y332789D01*
G01X313182Y332713D02*
X313163Y332747D01*
G01Y331172D02*
G03X313182Y332713I-1365J787D01*
G01X313138Y328889D02*
G02X313163Y331172I2040J1119D01*
G01Y328847D02*
X313138Y328889D01*
G01X313229Y328731D02*
X313163Y328847D01*
G01X315178Y326110D02*
X313229Y328731D01*
G01X351006Y340570D02*
G02X352357Y341335I1351J-810D01*
G01X350993Y340547D02*
X351006Y340570D01*
G01X349048Y339384D02*
G03X350993Y340547I-70J2325D01*
G01X348919Y339384D02*
X349048D01*
G01X347613Y338597D02*
G02X348919Y339384I1365J-788D01*
G01X345683Y337435D02*
G03X347613Y338597I-85J2325D01*
G01X345554Y337435D02*
X345683D01*
G01X344233Y336647D02*
G02X345554Y337435I1365J-787D01*
G01X342288Y335484D02*
G03X344233Y336647I-70J2325D01*
G01X342159Y335484D02*
X342288D01*
G01X340853Y334697D02*
G02X342159Y335484I1365J-788D01*
G01X338923Y333535D02*
G03X340853Y334697I-85J2325D01*
G01X338794Y333535D02*
X338923D01*
G01X337473Y332747D02*
G02X338794Y333535I1365J-787D01*
G01X335528Y331584D02*
G03X337473Y332747I-70J2325D01*
G01X335399Y331584D02*
X335528D01*
G01X334093Y330797D02*
G02X335399Y331584I1365J-788D01*
G01X332163Y329635D02*
G03X334093Y330797I-85J2325D01*
G01X332034Y329635D02*
X332163D01*
G01X330713Y327273D02*
G02X332034Y329635I1365J787D01*
G01X328749Y323784D02*
G03X330713Y327273I-51J2326D01*
G01X328639Y323784D02*
X328749D01*
G01X327333Y322997D02*
G02X328639Y323784I1365J-788D01*
G01X325403Y321835D02*
G03X327333Y322997I-85J2325D01*
G01X325274Y321835D02*
X325403D01*
G01X323953Y321047D02*
G02X325274Y321835I1365J-787D01*
G01X322008Y319884D02*
G03X323953Y321047I-70J2325D01*
G01X321879Y319884D02*
X322008D01*
G01X320573Y319097D02*
G02X321879Y319884I1365J-788D01*
G01X318643Y317935D02*
G03X320573Y319097I-85J2325D01*
G01X318473Y317935D02*
X318643D01*
G01X316543Y319097D02*
G03X318473Y317935I2015J1163D01*
G01X313813Y319097D02*
G02X316543I1365J-788D01*
G01X309783D02*
G03X313813I2015J1163D01*
G01X307067Y319119D02*
G02X309783Y319097I1352J-810D01*
G01X307054Y319096D02*
X307067Y319119D01*
G01X305137Y317935D02*
G03X307054Y319096I-98J2325D01*
G01X304995Y317935D02*
X305137D01*
G01X303674Y317147D02*
G02X304995Y317935I1365J-787D01*
G01X301729Y315984D02*
G03X303674Y317147I-70J2325D01*
G01X301600Y315984D02*
X301729D01*
G01X300294Y315197D02*
G02X301600Y315984I1365J-788D01*
G01X296264Y315197D02*
G03X300294I2015J1163D01*
G01X293534D02*
G02X296264I1365J-788D01*
G01X309802Y340956D02*
G03X309783Y342497I-1384J754D01*
G01Y340922D02*
X309802Y340956D01*
G01X309758Y340880D02*
X309783Y340922D01*
G01Y338597D02*
G02X309758Y340880I2015J1164D01*
G01X309802Y337056D02*
G03X309783Y338597I-1384J754D01*
G01Y337022D02*
X309802Y337056D01*
G01X309758Y336980D02*
X309783Y337022D01*
G01Y334697D02*
G02X309758Y336980I2015J1164D01*
G01X309802Y333156D02*
G03X309783Y334697I-1384J754D01*
G01Y333122D02*
X309802Y333156D01*
G01X309758Y333080D02*
X309783Y333122D01*
G01Y330797D02*
G02X309758Y333080I2015J1164D01*
G01X309849Y330681D02*
X309783Y330797D01*
G01X311798Y328060D02*
X309849Y330681D01*
G01X320554Y333156D02*
G02X321296Y335348I1384J753D01*
G01X320573Y333122D02*
X320554Y333156D01*
G01X320598Y333080D02*
X320573Y333122D01*
G01Y330797D02*
G03X320598Y333080I-2015J1164D01*
G01X320554Y329256D02*
G02X320573Y330797I1384J754D01*
G01Y329222D02*
X320554Y329256D01*
G01X320640Y329107D02*
X320573Y329222D01*
G01X321938Y326110D02*
X320640Y329107D01*
G01X323322Y340956D02*
G03X323303Y342497I-1384J754D01*
G01Y340922D02*
X323322Y340956D01*
G01X323278Y340880D02*
X323303Y340922D01*
G01Y338597D02*
G02X323278Y340880I2015J1164D01*
G01X323322Y337056D02*
G03X323303Y338597I-1384J754D01*
G01X323101Y336672D02*
X323322Y337056D01*
G01X321928Y335693D02*
X323101Y336672D01*
G01X321296Y335348D02*
X321928Y335693D01*
G01X311798Y331960D02*
X310499Y334959D01*
G01X310458Y340589D02*
G03X310433Y342872I-2040J1119D01*
G01Y340547D02*
X310458Y340589D01*
G01X310414Y340513D02*
X310433Y340547D01*
G01Y338972D02*
G02X310414Y340513I1365J787D01*
G01X310458Y336689D02*
G03X310433Y338972I-2040J1119D01*
G01Y336647D02*
X310458Y336689D01*
G01X310414Y336613D02*
X310433Y336647D01*
G01Y335072D02*
G02X310414Y336613I1365J787D01*
G01X310499Y334959D02*
X310433Y335072D01*
G01X350342Y340922D02*
G02X352287Y342085I2015J-1162D01*
G01X350329Y340899D02*
X350342Y340922D01*
G01X348978Y340134D02*
G03X350329Y340899I0J1575D01*
G01X348893Y340134D02*
X348978D01*
G01X346963Y338972D02*
G02X348893Y340134I2015J-1163D01*
G01X345657Y338185D02*
G03X346963Y338972I-59J1575D01*
G01X345528Y338185D02*
X345657D01*
G01X343583Y337022D02*
G02X345528Y338185I2015J-1162D01*
G01X342262Y336234D02*
G03X343583Y337022I-44J1575D01*
G01X342133Y336234D02*
X342262D01*
G01X340203Y335072D02*
G02X342133Y336234I2015J-1163D01*
G01X338897Y334285D02*
G03X340203Y335072I-59J1575D01*
G01X338768Y334285D02*
X338897D01*
G01X336823Y333122D02*
G02X338768Y334285I2015J-1162D01*
G01X335502Y332334D02*
G03X336823Y333122I-44J1575D01*
G01X335373Y332334D02*
X335502D01*
G01X333443Y331172D02*
G02X335373Y332334I2015J-1163D01*
G01X332137Y330385D02*
G03X333443Y331172I-59J1575D01*
G01X332008Y330385D02*
X332137D01*
G01X330063Y326897D02*
G02X332008Y330385I2015J1163D01*
G01X328742Y324535D02*
G03X330063Y326897I-44J1575D01*
G01X328647Y324535D02*
X328742D01*
G01X326683Y323372D02*
G02X328647Y324535I2015J-1163D01*
G01X325377Y322585D02*
G03X326683Y323372I-59J1575D01*
G01X325248Y322585D02*
X325377D01*
G01X323303Y321422D02*
G02X325248Y322585I2015J-1162D01*
G01X321982Y320634D02*
G03X323303Y321422I-44J1575D01*
G01X321853Y320634D02*
X321982D01*
G01X319923Y319472D02*
G02X321853Y320634I2015J-1163D01*
G01X318617Y318685D02*
G03X319923Y319472I-59J1575D01*
G01X318499Y318685D02*
X318617D01*
G01X317193Y319472D02*
G03X318499Y318685I1365J788D01*
G01X313163Y319472D02*
G02X317193I2015J-1163D01*
G01X310433D02*
G03X313163I1365J788D01*
G01X308503Y320634D02*
G02X310433Y319472I-85J-2325D01*
G01X308320Y320634D02*
X308503D01*
G01X306403Y319473D02*
G02X308320Y320634I2015J-1164D01*
G01X306390Y319450D02*
X306403Y319473D01*
G01X305039Y318685D02*
G03X306390Y319450I0J1575D01*
G01X304969Y318685D02*
X305039D01*
G01X303024Y317522D02*
G02X304969Y318685I2015J-1162D01*
G01X301703Y316734D02*
G03X303024Y317522I-44J1575D01*
G01X301574Y316734D02*
X301703D01*
G01X299644Y315572D02*
G02X301574Y316734I2015J-1163D01*
G01X296914Y315572D02*
G03X299644I1365J788D01*
G01X324019Y331059D02*
X325318Y328060D01*
G01X323953Y331172D02*
X324019Y331059D01*
G01X324936Y333489D02*
G03X323953Y331172I382J-1529D01*
G01X325956Y334173D02*
X324936Y333489D01*
G01X326183Y334377D02*
X325956Y334173D01*
G01X326518Y334787D02*
X326183Y334377D01*
G01X326683Y335072D02*
X326518Y334787D01*
G01X326702Y336613D02*
G02X326683Y335072I-1384J-754D01*
G01Y336647D02*
X326702Y336613D01*
G01X326658Y336689D02*
X326683Y336647D01*
G01Y338972D02*
G03X326658Y336689I2015J-1164D01*
G01X326702Y340513D02*
G02X326683Y338972I-1384J-754D01*
G01Y340547D02*
X326702Y340513D01*
G01X326658Y340589D02*
X326683Y340547D01*
G01Y342872D02*
G03X326658Y340589I2015J-1164D01*
G01X313794Y340956D02*
G02X313813Y342497I1384J754D01*
G01Y340922D02*
X313794Y340956D01*
G01X313838Y340880D02*
X313813Y340922D01*
G01Y338597D02*
G03X313838Y340880I-2015J1164D01*
G01X313794Y337056D02*
G02X313813Y338597I1384J754D01*
G01X313881Y336905D02*
X313794Y337056D01*
G01X315178Y333909D02*
X313881Y336905D01*
G01X323608Y336041D02*
G02X321938Y333909I-8038J4576D01*
G01X323953Y336647D02*
X323608Y336041D01*
G01X323978Y336689D02*
X323953Y336647D01*
G01Y338972D02*
G02X323978Y336689I-2015J-1164D01*
G01X323934Y340513D02*
G03X323953Y338972I1384J-754D01*
G01Y340547D02*
X323934Y340513D01*
G01X323978Y340589D02*
X323953Y340547D01*
G01Y342872D02*
G02X323978Y340589I-2015J-1164D01*
G01X329996Y382209D02*
Y405013D01*
G01X327332Y377599D02*
X329996Y382209D01*
G01X327333Y377597D02*
X327332Y377599D01*
G01X327314Y376056D02*
G02X327333Y377597I1384J754D01*
G01Y376022D02*
X327314Y376056D01*
G01X327358Y375980D02*
X327333Y376022D01*
G01Y373697D02*
G03X327358Y375980I-2015J1164D01*
G01X327314Y372156D02*
G02X327333Y373697I1384J754D01*
G01Y372122D02*
X327314Y372156D01*
G01X327358Y369839D02*
G03X327333Y372122I-2040J1119D01*
G01Y369797D02*
X327358Y369839D01*
G01X327333Y368223D02*
G02Y369797I1365J787D01*
G01Y365897D02*
G03Y368223I-2015J1163D01*
G01X327314Y364356D02*
G02X327333Y365897I1384J754D01*
G01Y364322D02*
X327314Y364356D01*
G01X327358Y364280D02*
X327333Y364322D01*
G01Y361997D02*
G03X327358Y364280I-2015J1164D01*
G01X327314Y360456D02*
G02X327333Y361997I1384J754D01*
G01Y360422D02*
X327314Y360456D01*
G01X327358Y360380D02*
X327333Y360422D01*
G01Y358097D02*
G03X327358Y360380I-2015J1164D01*
G01X327314Y356556D02*
G02X327333Y358097I1384J754D01*
G01Y356522D02*
X327314Y356556D01*
G01X327358Y356480D02*
X327333Y356522D01*
G01Y354197D02*
G03X327358Y356480I-2015J1164D01*
G01X327314Y352656D02*
G02X327333Y354197I1384J754D01*
G01Y352622D02*
X327314Y352656D01*
G01X327358Y352580D02*
X327333Y352622D01*
G01Y350297D02*
G03X327358Y352580I-2015J1164D01*
G01X327314Y348756D02*
G02X327333Y350297I1384J754D01*
G01Y348722D02*
X327314Y348756D01*
G01X327358Y348680D02*
X327333Y348722D01*
G01Y346397D02*
G03X327358Y348680I-2015J1164D01*
G01X327314Y344856D02*
G02X327333Y346397I1384J754D01*
G01Y344822D02*
X327314Y344856D01*
G01X327358Y344780D02*
X327333Y344822D01*
G01Y342497D02*
G03X327358Y344780I-2015J1164D01*
G01X348790Y395998D02*
Y397365D01*
G01X346492Y393700D02*
X348790Y395998D01*
G01X346492Y392064D02*
Y393700D01*
G01X346963Y391247D02*
X346492Y392064D01*
G01X346963Y389673D02*
G03Y391247I-1365J787D01*
G01Y387347D02*
G02Y389673I2015J1163D01*
G01X346982Y387313D02*
X346963Y387347D01*
G01Y385772D02*
G03X346982Y387313I-1365J787D01*
G01X346938Y383489D02*
G02X346963Y385772I2040J1119D01*
G01Y383447D02*
X346938Y383489D01*
G01X346982Y383413D02*
X346963Y383447D01*
G01X347172Y382592D02*
G03X346982Y383413I-1574J68D01*
G01X347172Y370953D02*
Y382592D01*
G01X346963Y370172D02*
G03X347172Y370953I-1354J781D01*
G01X346896Y370057D02*
X346963Y370172D01*
G01X345598Y367060D02*
X346896Y370057D01*
G01X310748Y399541D02*
X309825Y400464D01*
G01X310748Y395641D02*
Y399541D01*
G01X312416Y393973D02*
X310748Y395641D01*
G01X312416Y388684D02*
Y393973D01*
G01X313182Y387313D02*
X312416Y388684D01*
G01X313163Y385772D02*
G03X313182Y387313I-1365J787D01*
G01X313138Y383489D02*
G02X313163Y385772I2040J1119D01*
G01Y383447D02*
X313138Y383489D01*
G01X313182Y383413D02*
X313163Y383447D01*
G01Y381872D02*
G03X313182Y383413I-1365J787D01*
G01X313138Y379589D02*
G02X313163Y381872I2040J1119D01*
G01Y379547D02*
X313138Y379589D01*
G01X313182Y379513D02*
X313163Y379547D01*
G01Y377972D02*
G03X313182Y379513I-1365J787D01*
G01X313138Y375689D02*
G02X313163Y377972I2040J1119D01*
G01Y375647D02*
X313138Y375689D01*
G01X313182Y375613D02*
X313163Y375647D01*
G01Y374072D02*
G03X313182Y375613I-1365J787D01*
G01X313163Y371746D02*
G02Y374072I2015J1163D01*
G01Y370172D02*
G03Y371746I-1365J787D01*
G01X313138Y370130D02*
X313163Y370172D01*
G01Y367847D02*
G02X313138Y370130I2015J1164D01*
G01X313182Y367813D02*
X313163Y367847D01*
G01Y366272D02*
G03X313182Y367813I-1365J787D01*
G01X313138Y363989D02*
G02X313163Y366272I2040J1119D01*
G01Y363947D02*
X313138Y363989D01*
G01X313182Y363913D02*
X313163Y363947D01*
G01Y362372D02*
G03X313182Y363913I-1365J787D01*
G01X313138Y360089D02*
G02X313163Y362372I2040J1119D01*
G01Y360047D02*
X313138Y360089D01*
G01X313182Y360013D02*
X313163Y360047D01*
G01Y358472D02*
G03X313182Y360013I-1365J787D01*
G01X313138Y356189D02*
G02X313163Y358472I2040J1119D01*
G01Y356147D02*
X313138Y356189D01*
G01X313182Y356113D02*
X313163Y356147D01*
G01Y354572D02*
G03X313182Y356113I-1365J787D01*
G01X313138Y352289D02*
G02X313163Y354572I2040J1119D01*
G01Y352247D02*
X313138Y352289D01*
G01X313182Y352213D02*
X313163Y352247D01*
G01Y350672D02*
G03X313182Y352213I-1365J787D01*
G01X313138Y348389D02*
G02X313163Y350672I2040J1119D01*
G01Y348347D02*
X313138Y348389D01*
G01X313182Y348313D02*
X313163Y348347D01*
G01Y346772D02*
G03X313182Y348313I-1365J787D01*
G01X313138Y344489D02*
G02X313163Y346772I2040J1119D01*
G01Y344447D02*
X313138Y344489D01*
G01X313182Y344413D02*
X313163Y344447D01*
G01Y342872D02*
G03X313182Y344413I-1365J787D01*
G01X351892Y395000D02*
X354790Y397898D01*
G01X351892Y389200D02*
Y395000D01*
G01X351392Y388000D02*
G03X351892Y389200I-3068J1983D01*
G01X350993Y387347D02*
G02X351392Y388000I13170J-7599D01*
G01X350993Y385773D02*
G02Y387347I1364J787D01*
G01X351028Y383507D02*
G03X350993Y385773I-2050J1102D01*
G01Y383447D02*
X351028Y383507D01*
G01X350993Y381873D02*
G02Y383447I1364J787D01*
G01X351028Y379607D02*
G03X350993Y381873I-2050J1102D01*
G01Y379547D02*
X351028Y379607D01*
G01X350993Y377973D02*
G02Y379547I1364J787D01*
G01X351028Y375707D02*
G03X350993Y377973I-2050J1102D01*
G01Y375647D02*
X351028Y375707D01*
G01X350993Y374073D02*
G02Y375647I1364J787D01*
G01X351018Y371788D02*
G03X350993Y374073I-2040J1120D01*
G01Y371746D02*
X351018Y371788D01*
G01X350993Y370172D02*
G02Y371746I1364J787D01*
G01X351058Y370060D02*
X350993Y370172D01*
G01X352357Y367060D02*
X351058Y370060D01*
G01X352494Y341335D02*
X355736Y341710D01*
G01X352357Y341335D02*
X352494D01*
G01X352968Y394576D02*
X355663Y397271D01*
G01X352968Y388695D02*
Y394576D01*
G01X353741Y387313D02*
X352968Y388695D01*
G01X353722Y385772D02*
G03X353741Y387313I-1365J787D01*
G01X353697Y383489D02*
G02X353722Y385772I2040J1119D01*
G01Y383447D02*
X353697Y383489D01*
G01X353741Y383413D02*
X353722Y383447D01*
G01Y381872D02*
G03X353741Y383413I-1365J787D01*
G01X355667Y378384D02*
G02X353722Y381872I70J2325D01*
G01X352892Y398814D02*
Y404000D01*
G01X347388Y393310D02*
X352892Y398814D01*
G01X347388Y392013D02*
Y393310D01*
G01X347613Y391623D02*
X347388Y392013D01*
G01X347613Y389297D02*
G03Y391623I-2015J1163D01*
G01Y387723D02*
G02Y389297I1365J787D01*
G01Y385397D02*
G03Y387723I-2015J1163D01*
G01X347594Y383856D02*
G02X347613Y385397I1384J754D01*
G01X347681Y383705D02*
X347594Y383856D01*
G01X348978Y380709D02*
X347681Y383705D01*
G01X293492Y399493D02*
X293303Y399831D01*
G01X293559Y399380D02*
X293492Y399493D01*
G01X293534Y397097D02*
G03X293559Y399380I-2015J1164D01*
G01X293468Y396982D02*
X293534Y397097D01*
G01X305348Y399339D02*
X304525Y400162D01*
G01X305348Y396641D02*
Y399339D01*
G01X306747Y395242D02*
X305348Y396641D01*
G01X306747Y392670D02*
Y395242D01*
G01X309993Y389424D02*
X306747Y392670D01*
G01X309993Y388075D02*
Y389424D01*
G01X309758Y387680D02*
X309993Y388075D01*
G01X309783Y385397D02*
G02X309758Y387680I2015J1164D01*
G01X309802Y383856D02*
G03X309783Y385397I-1384J754D01*
G01Y383822D02*
X309802Y383856D01*
G01X309758Y383780D02*
X309783Y383822D01*
G01Y381497D02*
G02X309758Y383780I2015J1164D01*
G01X309802Y379956D02*
G03X309783Y381497I-1384J754D01*
G01Y379922D02*
X309802Y379956D01*
G01X309758Y379880D02*
X309783Y379922D01*
G01Y377597D02*
G02X309758Y379880I2015J1164D01*
G01X309802Y376056D02*
G03X309783Y377597I-1384J754D01*
G01Y376022D02*
X309802Y376056D01*
G01X309758Y375980D02*
X309783Y376022D01*
G01Y373697D02*
G02X309758Y375980I2015J1164D01*
G01X309802Y372156D02*
G03X309783Y373697I-1384J754D01*
G01Y372122D02*
X309802Y372156D01*
G01X309758Y369839D02*
G02X309783Y372122I2040J1119D01*
G01Y369797D02*
X309758Y369839D01*
G01X309783Y368223D02*
G03Y369797I-1365J787D01*
G01Y365897D02*
G02Y368223I2015J1163D01*
G01X309802Y364356D02*
G03X309783Y365897I-1384J754D01*
G01Y364322D02*
X309802Y364356D01*
G01X309758Y364280D02*
X309783Y364322D01*
G01Y361997D02*
G02X309758Y364280I2015J1164D01*
G01X309802Y360456D02*
G03X309783Y361997I-1384J754D01*
G01Y360422D02*
X309802Y360456D01*
G01X309758Y360380D02*
X309783Y360422D01*
G01Y358097D02*
G02X309758Y360380I2015J1164D01*
G01X309802Y356556D02*
G03X309783Y358097I-1384J754D01*
G01Y356522D02*
X309802Y356556D01*
G01X309758Y356480D02*
X309783Y356522D01*
G01Y354197D02*
G02X309758Y356480I2015J1164D01*
G01X309802Y352656D02*
G03X309783Y354197I-1384J754D01*
G01Y352622D02*
X309802Y352656D01*
G01X309758Y352580D02*
X309783Y352622D01*
G01Y350297D02*
G02X309758Y352580I2015J1164D01*
G01X309802Y348756D02*
G03X309783Y350297I-1384J754D01*
G01Y348722D02*
X309802Y348756D01*
G01X309758Y348680D02*
X309783Y348722D01*
G01Y346397D02*
G02X309758Y348680I2015J1164D01*
G01X309802Y344856D02*
G03X309783Y346397I-1384J754D01*
G01Y344822D02*
X309802Y344856D01*
G01X309758Y344780D02*
X309783Y344822D01*
G01Y342497D02*
G02X309758Y344780I2015J1164D01*
G01X346790Y395698D02*
Y397118D01*
G01X344968Y393876D02*
X346790Y395698D01*
G01X344968Y392522D02*
Y393876D01*
G01X344966Y392520D02*
X344968Y392522D01*
G01X344232Y391249D02*
X344966Y392520D01*
G01X344233Y391247D02*
G02X344232Y391249I1406J704D01*
G01Y391248D02*
X344233Y391247D01*
G01X344214Y391213D02*
X344232Y391248D01*
G01X344233Y389672D02*
G02X344214Y391213I1365J787D01*
G01X344258Y387389D02*
G03X344233Y389672I-2040J1119D01*
G01Y387347D02*
X344258Y387389D01*
G01X344214Y387313D02*
X344233Y387347D01*
G01Y385772D02*
G02X344214Y387313I1365J787D01*
G01X344258Y383489D02*
G03X344233Y385772I-2040J1119D01*
G01Y383447D02*
X344258Y383489D01*
G01X344214Y383413D02*
X344233Y383447D01*
G01Y381872D02*
G02X344214Y383413I1365J787D01*
G01X344299Y381759D02*
X344233Y381872D01*
G01X345598Y378760D02*
X344299Y381759D01*
G01X296796Y400370D02*
Y403393D01*
G01X296305Y399492D02*
X296796Y400370D01*
G01X296239Y399380D02*
X296305Y399492D01*
G01X296264Y397097D02*
G02X296239Y399380I2015J1164D01*
G01X294970Y394735D02*
G03X296264Y397097I-71J1574D01*
G01X294829Y394735D02*
X294970D01*
G01X297544Y400175D02*
Y403703D01*
G01X296895Y399013D02*
X297544Y400175D01*
G01X296914Y397472D02*
G02X296895Y399013I1365J787D01*
G01X296914Y395146D02*
G03Y397472I-2015J1163D01*
G01X296849Y395032D02*
X296914Y395146D01*
G01X294899Y392410D02*
X296849Y395032D01*
G01X340787Y373582D02*
X338838Y370959D01*
G01X340853Y373697D02*
X340787Y373582D01*
G01X340878Y375980D02*
G02X340853Y373697I-2040J-1119D01*
G01Y376022D02*
X340878Y375980D01*
G01X340834Y376056D02*
X340853Y376022D01*
G01Y377597D02*
G03X340834Y376056I1365J-787D01*
G01X340878Y379880D02*
G02X340853Y377597I-2040J-1119D01*
G01Y379922D02*
X340878Y379880D01*
G01X340834Y379956D02*
X340853Y379922D01*
G01Y381497D02*
G03X340834Y379956I1365J-787D01*
G01X340878Y383780D02*
G02X340853Y381497I-2040J-1119D01*
G01Y383822D02*
X340878Y383780D01*
G01X340834Y383856D02*
X340853Y383822D01*
G01Y385397D02*
G03X340834Y383856I1365J-787D01*
G01X340878Y387680D02*
G02X340853Y385397I-2040J-1119D01*
G01Y387722D02*
X340878Y387680D01*
G01X340834Y387756D02*
X340853Y387722D01*
G01X340653Y388320D02*
G03X340834Y387756I1565J191D01*
G01X340292Y389321D02*
X340653Y388320D01*
G01X340292Y397400D02*
Y389321D01*
G01X342746Y399854D02*
X340292Y397400D01*
G01X342746Y400788D02*
Y399854D01*
G01X323932Y402825D02*
Y403096D01*
G01X321948Y400841D02*
X323932Y402825D01*
G01X321948Y397041D02*
Y400841D01*
G01X322948Y396041D02*
X321948Y397041D01*
G01X322948Y385441D02*
Y396041D01*
G01X323693Y384696D02*
X322948Y385441D01*
G01X323693Y380617D02*
Y384696D01*
G01X323278Y379880D02*
X323693Y380617D01*
G01X323303Y377597D02*
G02X323278Y379880I2015J1164D01*
G01X323322Y376056D02*
G03X323303Y377597I-1384J754D01*
G01Y376022D02*
X323322Y376056D01*
G01X323278Y375980D02*
X323303Y376022D01*
G01Y373697D02*
G02X323278Y375980I2015J1164D01*
G01X323322Y372156D02*
G03X323303Y373697I-1384J754D01*
G01Y372122D02*
X323322Y372156D01*
G01X323278Y369839D02*
G02X323303Y372122I2040J1119D01*
G01Y369797D02*
X323278Y369839D01*
G01X323303Y368223D02*
G03Y369797I-1365J787D01*
G01Y365897D02*
G02Y368223I2015J1163D01*
G01X323322Y364356D02*
G03X323303Y365897I-1384J754D01*
G01Y364322D02*
X323322Y364356D01*
G01X323278Y364280D02*
X323303Y364322D01*
G01Y361997D02*
G02X323278Y364280I2015J1164D01*
G01X323322Y360456D02*
G03X323303Y361997I-1384J754D01*
G01Y360422D02*
X323322Y360456D01*
G01X323278Y360380D02*
X323303Y360422D01*
G01Y358097D02*
G02X323278Y360380I2015J1164D01*
G01X323322Y356556D02*
G03X323303Y358097I-1384J754D01*
G01Y356522D02*
X323322Y356556D01*
G01X323278Y356480D02*
X323303Y356522D01*
G01Y354197D02*
G02X323278Y356480I2015J1164D01*
G01X323322Y352656D02*
G03X323303Y354197I-1384J754D01*
G01Y352622D02*
X323322Y352656D01*
G01X323278Y352580D02*
X323303Y352622D01*
G01Y350297D02*
G02X323278Y352580I2015J1164D01*
G01X323322Y348756D02*
G03X323303Y350297I-1384J754D01*
G01Y348722D02*
X323322Y348756D01*
G01X323278Y348680D02*
X323303Y348722D01*
G01Y346397D02*
G02X323278Y348680I2015J1164D01*
G01X323322Y344856D02*
G03X323303Y346397I-1384J754D01*
G01Y344822D02*
X323322Y344856D01*
G01X323278Y344780D02*
X323303Y344822D01*
G01Y342497D02*
G02X323278Y344780I2015J1164D01*
G01X353892Y398500D02*
Y405250D01*
G01X350764Y395372D02*
X353892Y398500D01*
G01X350764Y388570D02*
Y395372D01*
G01X350342Y387722D02*
G03X350764Y388570I-6161J3595D01*
G01X350307Y387662D02*
X350342Y387722D01*
G01Y385396D02*
G02X350307Y387662I2015J1164D01*
G01X350342Y383822D02*
G03Y385396I-1364J787D01*
G01X350307Y383762D02*
X350342Y383822D01*
G01Y381496D02*
G02X350307Y383762I2015J1164D01*
G01X350342Y379922D02*
G03Y381496I-1364J787D01*
G01X350307Y379862D02*
X350342Y379922D01*
G01Y377596D02*
G02X350307Y379862I2015J1164D01*
G01X350342Y376022D02*
G03Y377596I-1364J787D01*
G01X350307Y375962D02*
X350342Y376022D01*
G01Y373696D02*
G02X350307Y375962I2015J1164D01*
G01X350342Y372122D02*
G03Y373696I-1364J787D01*
G01X350118Y371593D02*
G02X350342Y372122I2238J-636D01*
G01X348978Y369010D02*
G02X350118Y371593I3496J0D01*
G01X306096Y399383D02*
X307025Y400312D01*
G01X306096Y396951D02*
Y399383D01*
G01X307495Y395552D02*
X306096Y396951D01*
G01X307495Y392980D02*
Y395552D01*
G01X310741Y389734D02*
X307495Y392980D01*
G01X310741Y387868D02*
Y389734D01*
G01X310458Y387392D02*
X310741Y387868D01*
G01X310414Y387313D02*
X310458Y387392D01*
G01X310433Y385772D02*
G02X310414Y387313I1365J787D01*
G01X310458Y383489D02*
G03X310433Y385772I-2040J1119D01*
G01Y383447D02*
X310458Y383489D01*
G01X310414Y383413D02*
X310433Y383447D01*
G01Y381872D02*
G02X310414Y383413I1365J787D01*
G01X310458Y379589D02*
G03X310433Y381872I-2040J1119D01*
G01Y379547D02*
X310458Y379589D01*
G01X310414Y379513D02*
X310433Y379547D01*
G01Y377972D02*
G02X310414Y379513I1365J787D01*
G01X310458Y375689D02*
G03X310433Y377972I-2040J1119D01*
G01Y375647D02*
X310458Y375689D01*
G01X310414Y375613D02*
X310433Y375647D01*
G01Y374072D02*
G02X310414Y375613I1365J787D01*
G01X310433Y371746D02*
G03Y374072I-2015J1163D01*
G01Y370172D02*
G02Y371746I1365J787D01*
G01X310458Y370130D02*
X310433Y370172D01*
G01Y367847D02*
G03X310458Y370130I-2015J1164D01*
G01X310414Y367813D02*
X310433Y367847D01*
G01Y366272D02*
G02X310414Y367813I1365J787D01*
G01X310458Y363989D02*
G03X310433Y366272I-2040J1119D01*
G01Y363947D02*
X310458Y363989D01*
G01X310414Y363913D02*
X310433Y363947D01*
G01Y362372D02*
G02X310414Y363913I1365J787D01*
G01X310458Y360089D02*
G03X310433Y362372I-2040J1119D01*
G01Y360047D02*
X310458Y360089D01*
G01X310414Y360013D02*
X310433Y360047D01*
G01Y358472D02*
G02X310414Y360013I1365J787D01*
G01X310458Y356189D02*
G03X310433Y358472I-2040J1119D01*
G01Y356147D02*
X310458Y356189D01*
G01X310414Y356113D02*
X310433Y356147D01*
G01Y354572D02*
G02X310414Y356113I1365J787D01*
G01X310458Y352289D02*
G03X310433Y354572I-2040J1119D01*
G01Y352247D02*
X310458Y352289D01*
G01X310414Y352213D02*
X310433Y352247D01*
G01Y350672D02*
G02X310414Y352213I1365J787D01*
G01X310458Y348389D02*
G03X310433Y350672I-2040J1119D01*
G01Y348347D02*
X310458Y348389D01*
G01X310414Y348313D02*
X310433Y348347D01*
G01Y346772D02*
G02X310414Y348313I1365J787D01*
G01X310458Y344489D02*
G03X310433Y346772I-2040J1119D01*
G01Y344447D02*
X310458Y344489D01*
G01X310414Y344413D02*
X310433Y344447D01*
G01Y342872D02*
G02X310414Y344413I1365J787D01*
G01X353722Y342872D02*
G02X355509Y343904I1787J-1032D01*
G01X352416Y342085D02*
G03X353722Y342872I-59J1575D01*
G01X352287Y342085D02*
X352416D01*
G01X343515Y375905D02*
X342218Y372909D01*
G01X343602Y376056D02*
X343515Y375905D01*
G01X343583Y377597D02*
G02X343602Y376056I-1365J-787D01*
G01X343558Y379880D02*
G03X343583Y377597I2040J-1119D01*
G01Y379922D02*
X343558Y379880D01*
G01X343602Y379956D02*
X343583Y379922D01*
G01Y381497D02*
G02X343602Y379956I-1365J-787D01*
G01X343558Y383780D02*
G03X343583Y381497I2040J-1119D01*
G01Y383822D02*
X343558Y383780D01*
G01X343602Y383856D02*
X343583Y383822D01*
G01Y385397D02*
G02X343602Y383856I-1365J-787D01*
G01X343558Y387680D02*
G03X343583Y385397I2040J-1119D01*
G01Y387722D02*
X343558Y387680D01*
G01X343602Y387756D02*
X343583Y387722D01*
G01Y389297D02*
G02X343602Y387756I-1365J-787D01*
G01X343418Y391271D02*
G03X343583Y389297I2180J-812D01*
G01X343404Y391317D02*
G03X343418Y391271I2233J655D01*
G01X343850Y392089D02*
X343404Y391317D01*
G01X343850Y394644D02*
Y392089D01*
G01X344790Y395584D02*
X343850Y394644D01*
G01X344790Y396937D02*
Y395584D01*
G01X326702Y344413D02*
G02X326683Y342872I-1384J-754D01*
G01Y344447D02*
X326702Y344413D01*
G01X326658Y344489D02*
X326683Y344447D01*
G01Y346772D02*
G03X326658Y344489I2015J-1164D01*
G01X326702Y348313D02*
G02X326683Y346772I-1384J-754D01*
G01Y348347D02*
X326702Y348313D01*
G01X326658Y348389D02*
X326683Y348347D01*
G01Y350672D02*
G03X326658Y348389I2015J-1164D01*
G01X326702Y352213D02*
G02X326683Y350672I-1384J-754D01*
G01Y352247D02*
X326702Y352213D01*
G01X326658Y352289D02*
X326683Y352247D01*
G01Y354572D02*
G03X326658Y352289I2015J-1164D01*
G01X326702Y356113D02*
G02X326683Y354572I-1384J-754D01*
G01Y356147D02*
X326702Y356113D01*
G01X326658Y356189D02*
X326683Y356147D01*
G01Y358472D02*
G03X326658Y356189I2015J-1164D01*
G01X326702Y360013D02*
G02X326683Y358472I-1384J-754D01*
G01Y360047D02*
X326702Y360013D01*
G01X326658Y360089D02*
X326683Y360047D01*
G01Y362372D02*
G03X326658Y360089I2015J-1164D01*
G01X326702Y363913D02*
G02X326683Y362372I-1384J-754D01*
G01Y363947D02*
X326702Y363913D01*
G01X326658Y363989D02*
X326683Y363947D01*
G01Y366272D02*
G03X326658Y363989I2015J-1164D01*
G01X326702Y367813D02*
G02X326683Y366272I-1384J-754D01*
G01Y367847D02*
X326702Y367813D01*
G01X326658Y370130D02*
G03X326683Y367847I2040J-1119D01*
G01Y370172D02*
X326658Y370130D01*
G01X326683Y371746D02*
G02Y370172I-1365J-787D01*
G01Y374072D02*
G03Y371746I2015J-1163D01*
G01X326702Y375613D02*
G02X326683Y374072I-1384J-754D01*
G01Y375647D02*
X326702Y375613D01*
G01X326658Y375689D02*
X326683Y375647D01*
G01Y377972D02*
G03X326658Y375689I2015J-1164D01*
G01X329248Y382412D02*
X326683Y377972D01*
G01X329248Y405077D02*
Y382412D01*
G01X340746Y399790D02*
Y401003D01*
G01X339542Y398586D02*
X340746Y399790D01*
G01X339542Y388250D02*
Y398586D01*
G01X339652Y388140D02*
X339542Y388250D01*
G01X340031Y387714D02*
X339652Y388140D01*
G01X340178Y387389D02*
G02X340031Y387714I2040J1119D01*
G01X340203Y387347D02*
X340178Y387389D01*
G01X340222Y387313D02*
X340203Y387347D01*
G01Y385772D02*
G03X340222Y387313I-1365J787D01*
G01X340178Y383489D02*
G02X340203Y385772I2040J1119D01*
G01Y383447D02*
X340178Y383489D01*
G01X340222Y383413D02*
X340203Y383447D01*
G01Y381872D02*
G03X340222Y383413I-1365J787D01*
G01X340178Y379589D02*
G02X340203Y381872I2040J1119D01*
G01Y379547D02*
X340178Y379589D01*
G01X340222Y379513D02*
X340203Y379547D01*
G01Y377972D02*
G03X340222Y379513I-1365J787D01*
G01X340137Y377859D02*
X340203Y377972D01*
G01X338838Y374860D02*
X340137Y377859D01*
G01X337539Y381759D02*
X338838Y378760D01*
G01X337473Y381872D02*
X337539Y381759D01*
G01X337454Y383413D02*
G03X337473Y381872I1384J-754D01*
G01Y383447D02*
X337454Y383413D01*
G01X337498Y383489D02*
X337473Y383447D01*
G01X337571Y385583D02*
G02X337498Y383489I-2113J-975D01*
G01X337537Y385617D02*
X337571Y385583D01*
G01X337264Y386276D02*
G03X337537Y385617I932J0D01*
G01X337264Y387212D02*
Y386276D01*
G01X338746Y388694D02*
X337264Y387212D01*
G01X338746Y400454D02*
Y388694D01*
G01X311496Y399483D02*
X312325Y400312D01*
G01X311496Y395951D02*
Y399483D01*
G01X313164Y394283D02*
X311496Y395951D01*
G01X313164Y388879D02*
Y394283D01*
G01X313838Y387680D02*
X313164Y388879D01*
G01X313813Y385397D02*
G03X313838Y387680I-2015J1164D01*
G01X313794Y383856D02*
G02X313813Y385397I1384J754D01*
G01Y383822D02*
X313794Y383856D01*
G01X313838Y383780D02*
X313813Y383822D01*
G01Y381497D02*
G03X313838Y383780I-2015J1164D01*
G01X313794Y379956D02*
G02X313813Y381497I1384J754D01*
G01Y379922D02*
X313794Y379956D01*
G01X313838Y379880D02*
X313813Y379922D01*
G01Y377597D02*
G03X313838Y379880I-2015J1164D01*
G01X313794Y376056D02*
G02X313813Y377597I1384J754D01*
G01Y376022D02*
X313794Y376056D01*
G01X313838Y375980D02*
X313813Y376022D01*
G01Y373697D02*
G03X313838Y375980I-2015J1164D01*
G01X313794Y372156D02*
G02X313813Y373697I1384J754D01*
G01Y372122D02*
X313794Y372156D01*
G01X313838Y369839D02*
G03X313813Y372122I-2040J1119D01*
G01Y369797D02*
X313838Y369839D01*
G01X313813Y368223D02*
G02Y369797I1365J787D01*
G01Y365897D02*
G03Y368223I-2015J1163D01*
G01X313794Y364356D02*
G02X313813Y365897I1384J754D01*
G01Y364322D02*
X313794Y364356D01*
G01X313838Y364280D02*
X313813Y364322D01*
G01Y361997D02*
G03X313838Y364280I-2015J1164D01*
G01X313794Y360456D02*
G02X313813Y361997I1384J754D01*
G01Y360422D02*
X313794Y360456D01*
G01X313838Y360380D02*
X313813Y360422D01*
G01Y358097D02*
G03X313838Y360380I-2015J1164D01*
G01X313794Y356556D02*
G02X313813Y358097I1384J754D01*
G01Y356522D02*
X313794Y356556D01*
G01X313838Y356480D02*
X313813Y356522D01*
G01Y354197D02*
G03X313838Y356480I-2015J1164D01*
G01X313794Y352656D02*
G02X313813Y354197I1384J754D01*
G01Y352622D02*
X313794Y352656D01*
G01X313838Y352580D02*
X313813Y352622D01*
G01Y350297D02*
G03X313838Y352580I-2015J1164D01*
G01X313794Y348756D02*
G02X313813Y350297I1384J754D01*
G01Y348722D02*
X313794Y348756D01*
G01X313838Y348680D02*
X313813Y348722D01*
G01Y346397D02*
G03X313838Y348680I-2015J1164D01*
G01X313794Y344856D02*
G02X313813Y346397I1384J754D01*
G01Y344822D02*
X313794Y344856D01*
G01X313838Y344780D02*
X313813Y344822D01*
G01Y342497D02*
G03X313838Y344780I-2015J1164D01*
G01X323934Y344413D02*
G03X323953Y342872I1384J-754D01*
G01Y344447D02*
X323934Y344413D01*
G01X323978Y344489D02*
X323953Y344447D01*
G01Y346772D02*
G02X323978Y344489I-2015J-1164D01*
G01X323934Y348313D02*
G03X323953Y346772I1384J-754D01*
G01Y348347D02*
X323934Y348313D01*
G01X323978Y348389D02*
X323953Y348347D01*
G01Y350672D02*
G02X323978Y348389I-2015J-1164D01*
G01X323934Y352213D02*
G03X323953Y350672I1384J-754D01*
G01Y352247D02*
X323934Y352213D01*
G01X323978Y352289D02*
X323953Y352247D01*
G01Y354572D02*
G02X323978Y352289I-2015J-1164D01*
G01X323934Y356113D02*
G03X323953Y354572I1384J-754D01*
G01Y356147D02*
X323934Y356113D01*
G01X323978Y356189D02*
X323953Y356147D01*
G01Y358472D02*
G02X323978Y356189I-2015J-1164D01*
G01X323934Y360013D02*
G03X323953Y358472I1384J-754D01*
G01Y360047D02*
X323934Y360013D01*
G01X323978Y360089D02*
X323953Y360047D01*
G01Y362372D02*
G02X323978Y360089I-2015J-1164D01*
G01X323934Y363913D02*
G03X323953Y362372I1384J-754D01*
G01Y363947D02*
X323934Y363913D01*
G01X323978Y363989D02*
X323953Y363947D01*
G01Y366272D02*
G02X323978Y363989I-2015J-1164D01*
G01X323934Y367813D02*
G03X323953Y366272I1384J-754D01*
G01Y367847D02*
X323934Y367813D01*
G01X323978Y370130D02*
G02X323953Y367847I-2040J-1119D01*
G01Y370172D02*
X323978Y370130D01*
G01X323953Y371746D02*
G03Y370172I1365J-787D01*
G01Y374072D02*
G02Y371746I-2015J-1163D01*
G01X323934Y375613D02*
G03X323953Y374072I1384J-754D01*
G01Y375647D02*
X323934Y375613D01*
G01X323978Y375689D02*
X323953Y375647D01*
G01Y377972D02*
G02X323978Y375689I-2015J-1164D01*
G01X323934Y379513D02*
G03X323953Y377972I1384J-754D01*
G01X324441Y380420D02*
X323934Y379513D01*
G01X324441Y385006D02*
Y380420D01*
G01X323696Y385751D02*
X324441Y385006D01*
G01X323696Y396351D02*
Y385751D01*
G01X322696Y397351D02*
X323696Y396351D01*
G01X322696Y400531D02*
Y397351D01*
G01X324680Y402515D02*
X322696Y400531D01*
G01X324680Y402938D02*
Y402515D01*
G01X325604Y403862D02*
X324680Y402938D01*
G01X354163Y394271D02*
X356413Y396521D01*
G01X354163Y388096D02*
Y394271D01*
G01X354372Y387722D02*
X354163Y388096D01*
G01X354397Y387680D02*
X354372Y387722D01*
G01Y385397D02*
G03X354397Y387680I-2015J1164D01*
G01X354353Y383856D02*
G02X354372Y385397I1384J754D01*
G01Y383822D02*
X354353Y383856D01*
G01X354397Y383780D02*
X354372Y383822D01*
G01Y381497D02*
G03X354397Y383780I-2015J1164D01*
G01X355693Y379134D02*
G02X354372Y381497I44J1575D01*
G01X329996Y405013D02*
X330904Y405921D01*
G01X350790Y406102D02*
Y407015D01*
G01X352892Y404000D02*
X350790Y406102D01*
G01X294807Y405382D02*
X293707D01*
G01X296796Y403393D02*
X294807Y405382D01*
G01X295173Y406074D02*
Y407266D01*
G01X297544Y403703D02*
X295173Y406074D01*
G01X323932Y403096D02*
X323104Y403924D01*
G01X352790Y406352D02*
Y407700D01*
G01X353892Y405250D02*
X352790Y406352D01*
G01X328608Y405717D02*
X329248Y405077D01*
G01X384136Y197536D02*
Y195798D01*
G01X379397Y202275D02*
X384136Y197536D01*
G01X379397Y207159D02*
Y202275D01*
G01X393948Y193802D02*
Y192984D01*
G01X394608Y194462D02*
X393948Y193802D01*
G01X394608Y195629D02*
Y194462D01*
G01X393929Y196308D02*
X394608Y195629D01*
G01X393929Y199341D02*
Y196308D01*
G01X394608Y200020D02*
X393929Y199341D01*
G01X394608Y203984D02*
Y200020D01*
G01X391111Y207481D02*
X394608Y203984D01*
G01X391111Y209191D02*
Y207481D01*
G01X390933Y209840D02*
G02X391111Y209191I-1396J-732D01*
G01X390901Y209896D02*
X390933Y209840D01*
G01X390866Y212162D02*
G03X390901Y209896I2050J-1102D01*
G01Y212222D02*
X390866Y212162D01*
G01X389537Y214584D02*
G02X390901Y212222I0J-1575D01*
G01X389467Y214584D02*
X389537D01*
G01X387522Y215747D02*
G03X389467Y214584I2015J1162D01*
G01X387454Y215864D02*
X387522Y215747D01*
G01X386157Y218860D02*
X387454Y215864D01*
G01X360092Y194000D02*
Y192853D01*
G01X357892Y196200D02*
X360092Y194000D01*
G01X357892Y200501D02*
Y196200D01*
G01X385719Y202173D02*
Y200166D01*
G01X382442Y205450D02*
X385719Y202173D01*
G01X381485Y206696D02*
G03X382442Y205450I5226J3024D01*
G01X380762Y207946D02*
X381485Y206696D01*
G01X380439Y208340D02*
G02X380762Y207946I-1041J-1183D01*
G01X379480Y209954D02*
X380439Y208340D01*
G01X378892Y211177D02*
X379480Y209954D01*
G01X377382Y213797D02*
X378892Y211177D01*
G01X377357Y216080D02*
G03X377382Y213797I2040J-1119D01*
G01Y216122D02*
X377357Y216080D01*
G01X377401Y216156D02*
X377382Y216122D01*
G01Y217697D02*
G02X377401Y216156I-1365J-787D01*
G01X377357Y219980D02*
G03X377382Y217697I2040J-1119D01*
G01X411948Y205753D02*
Y223143D01*
G01X411946Y205751D02*
X411948Y205753D01*
G01X414939Y202758D02*
X411946Y205751D01*
G01X414939Y199558D02*
Y202758D01*
G01X414944Y199552D02*
X414939Y199558D01*
G01X417925Y196572D02*
X414944Y199552D01*
G01X361132Y209898D02*
X362497Y213009D01*
G01X360921Y209099D02*
G02X361132Y209898I1576J11D01*
G01X360921Y204500D02*
Y209099D01*
G01X361892Y203529D02*
X360921Y204500D01*
G01X361892Y200000D02*
Y203529D01*
G01X368092Y193800D02*
X361892Y200000D01*
G01X368092Y192974D02*
Y193800D01*
G01X390516Y193177D02*
Y192316D01*
G01X390192Y193501D02*
X390516Y193177D01*
G01X390192Y202001D02*
Y193501D01*
G01X387738Y204455D02*
X390192Y202001D01*
G01X387738Y207573D02*
Y204455D01*
G01X387456Y208060D02*
X387738Y207573D01*
G01X386157Y211060D02*
X387456Y208060D01*
G01X395749Y195628D02*
Y192972D01*
G01X394694Y196683D02*
X395749Y195628D01*
G01X394694Y198820D02*
Y196683D01*
G01X395692Y199818D02*
X394694Y198820D01*
G01X395692Y204401D02*
Y199818D01*
G01X393942Y206151D02*
X395692Y204401D01*
G01X393941Y206151D02*
X393942D01*
G01X392092Y208000D02*
X393941Y206151D01*
G01X392092Y209284D02*
Y208000D01*
G01X391552Y210273D02*
X392092Y209284D01*
G01X391552Y211847D02*
G03Y210273I1364J-787D01*
G01X391587Y211907D02*
X391552Y211847D01*
G01Y214173D02*
G02X391587Y211907I-2015J-1164D01*
G01X391237Y214730D02*
X391552Y214173D01*
G01X390432Y215813D02*
X391237Y214730D01*
G01X389537Y216909D02*
X390432Y215813D01*
G01X416198Y214621D02*
G02X416756Y214409I-564J-2324D01*
G01X415634Y214621D02*
X416198D01*
G01X414331Y215311D02*
G03X415634Y214621I1303J885D01*
G01X414255Y215444D02*
X414331Y215311D01*
G01X414274Y216983D02*
G03X414255Y215444I1360J-786D01*
G01X414328Y217076D02*
X414274Y216983D01*
G01X415407Y217754D02*
G03X414328Y217076I227J-1559D01*
G01X415634Y217527D02*
X415407Y217754D01*
G01X415634Y216196D02*
Y217527D01*
G01X382514Y196948D02*
Y195289D01*
G01X377598Y201864D02*
X382514Y196948D01*
G01X377598Y211441D02*
Y201864D01*
G01X376030Y213009D02*
X377598Y211441D01*
G01X376017Y213009D02*
X376030D01*
G01X409155Y195737D02*
Y194050D01*
G01X407892Y197000D02*
X409155Y195737D01*
G01X407892Y202000D02*
Y197000D01*
G01X405892Y204000D02*
X407892Y202000D01*
G01X405892Y209500D02*
Y204000D01*
G01X409392Y216500D02*
X405892Y209500D01*
G01X409392Y217526D02*
Y216500D01*
G01X408418Y218500D02*
X409392Y217526D01*
G01X416094Y213871D02*
G02X417070Y213090I-460J-1575D01*
G01X415634Y213871D02*
X416094D01*
G01X413682Y214934D02*
G03X415634Y213871I1952J1261D01*
G01X413624Y215033D02*
X413682Y214934D01*
G01X413599Y215075D02*
X413624Y215033D01*
G01Y217360D02*
G03X413599Y215075I2010J-1165D01*
G01X413676Y217450D02*
X413624Y217360D01*
G01X415376Y218507D02*
G03X413676Y217450I258J-2311D01*
G01X398336Y215789D02*
G03X398311Y218072I-2040J1119D01*
G01Y215747D02*
X398336Y215789D01*
G01X398292Y215713D02*
X398311Y215747D01*
G01X399617Y213385D02*
G02X398292Y215713I59J1575D01*
G01X400707Y213385D02*
X399617D01*
G01X402000Y212092D02*
X400707Y213385D01*
G01X402000Y197483D02*
Y212092D01*
G01X402806Y196677D02*
X402000Y197483D01*
G01X402806Y195555D02*
Y196677D01*
G01X397661Y217697D02*
X397013Y218820D01*
G01X397680Y216156D02*
G03X397661Y217697I-1384J754D01*
G01Y216122D02*
X397680Y216156D01*
G01X397636Y216080D02*
X397661Y216122D01*
G01X399591Y212635D02*
G02X397636Y216080I85J2325D01*
G01X400346Y212635D02*
X399591D01*
G01X401250Y211731D02*
X400346Y212635D01*
G01X401250Y195652D02*
Y211731D01*
G01X387496Y201496D02*
Y199996D01*
G01X383492Y205500D02*
X387496Y201496D01*
G01X381677Y207864D02*
G03X383492Y205500I9909J5729D01*
G01X381303Y208511D02*
X381677Y207864D01*
G01X380846Y209300D02*
X381303Y208511D01*
G01X379945Y210853D02*
X380846Y209300D01*
G01X378032Y214172D02*
X379945Y210853D01*
G01X378013Y215713D02*
G03X378032Y214172I1384J-754D01*
G01Y215747D02*
X378013Y215713D01*
G01X378057Y215789D02*
X378032Y215747D01*
G01Y218072D02*
G02X378057Y215789I-2015J-1164D01*
G01X357036Y213910D02*
X355737Y216909D01*
G01X357102Y213797D02*
X357036Y213910D01*
G01X357121Y212256D02*
G03X357102Y213797I-1384J754D01*
G01Y212222D02*
X357121Y212256D01*
G01X357077Y212180D02*
X357102Y212222D01*
G01Y209897D02*
G02X357077Y212180I2015J1164D01*
G01X357563Y208177D02*
G03X357102Y209897I-3438J0D01*
G01X357563Y203294D02*
Y208177D01*
G01X358892Y201965D02*
X357563Y203294D01*
G01X358892Y197100D02*
Y201965D01*
G01X362092Y193900D02*
X358892Y197100D01*
G01X362092Y192853D02*
Y193900D01*
G01X392026Y193504D02*
Y192547D01*
G01X391284Y194246D02*
X392026Y193504D01*
G01X391284Y197108D02*
Y194246D01*
G01X392182Y198006D02*
X391284Y197108D01*
G01X392182Y201510D02*
Y198006D01*
G01X388692Y205000D02*
X392182Y201510D01*
G01X388692Y207502D02*
Y205000D01*
G01X388172Y208322D02*
X388692Y207502D01*
G01X388153Y208356D02*
X388172Y208322D01*
G01Y209897D02*
G03X388153Y208356I1365J-787D01*
G01X386380Y213000D02*
G02X388172Y209897I0J-2069D01*
G01X382786Y213000D02*
X386380D01*
G01X382777Y213009D02*
X382786Y213000D01*
G01X405992Y200401D02*
Y194366D01*
G01X403500Y202893D02*
X405992Y200401D01*
G01X403500Y217492D02*
Y202893D01*
G01X399807Y221185D02*
X403500Y217492D01*
G01X389006Y201986D02*
Y191891D01*
G01X384498Y206494D02*
X389006Y201986D01*
G01X384498Y209794D02*
Y206494D01*
G01X383742Y210550D02*
X384498Y209794D01*
G01X382092Y211400D02*
X383742Y210550D01*
G01X381092Y212400D02*
X382092Y211400D01*
G01X381092Y220900D02*
Y212400D01*
G01X399537Y199541D02*
Y195507D01*
G01X397592Y201486D02*
X399537Y199541D01*
G01X397592Y205200D02*
Y201486D01*
G01X394889Y207902D02*
X397592Y205200D01*
G01X394642Y208500D02*
G03X394889Y207902I845J-1D01*
G01X394642Y208818D02*
Y208500D01*
G01X394931Y209897D02*
G03X394642Y208818I1871J-1079D01*
G01X394956Y212180D02*
G02X394931Y209897I-2040J-1119D01*
G01Y212222D02*
X394956Y212180D01*
G01X394912Y212256D02*
X394931Y212222D01*
G01Y213797D02*
G03X394912Y212256I1365J-787D01*
G01X392986Y217285D02*
G02X394931Y213797I-70J-2325D01*
G01X392916Y217285D02*
X392986D01*
G01X391552Y219647D02*
G03X392916Y217285I1364J-787D01*
G01X414191Y199202D02*
X417178Y196215D01*
G01X414191Y202448D02*
Y199202D01*
G01X411198Y205441D02*
X414191Y202448D01*
G01X411198Y223460D02*
Y205441D01*
G01X357820Y215864D02*
X359117Y218860D01*
G01X357733Y215713D02*
X357820Y215864D01*
G01X357752Y214172D02*
G02X357733Y215713I1365J787D01*
G01X357777Y211889D02*
G03X357752Y214172I-2040J1119D01*
G01Y211847D02*
X357777Y211889D01*
G01X357733Y211813D02*
X357752Y211847D01*
G01Y210272D02*
G02X357733Y211813I1365J787D01*
G01X358255Y209400D02*
X357752Y210272D01*
G01X358790Y207400D02*
G03X358255Y209400I-4004J0D01*
G01X358790Y203500D02*
Y207400D01*
G01X359892Y202398D02*
X358790Y203500D01*
G01X359892Y198000D02*
Y202398D01*
G01X364092Y193800D02*
X359892Y198000D01*
G01X364092Y192561D02*
Y193800D01*
G01X404353Y196755D02*
Y195531D01*
G01X402750Y198358D02*
X404353Y196755D01*
G01X402750Y215786D02*
Y198358D01*
G01X399676Y218860D02*
X402750Y215786D01*
G01X366092Y193800D02*
Y192683D01*
G01X360878Y199014D02*
X366092Y193800D01*
G01X360878Y203014D02*
Y199014D01*
G01X359892Y204000D02*
X360878Y203014D01*
G01X359892Y209062D02*
Y204000D01*
G01X359117Y211060D02*
X359892Y209062D01*
G01X407617Y195275D02*
Y194172D01*
G01X406892Y196000D02*
X407617Y195275D01*
G01X406892Y201500D02*
Y196000D01*
G01X404892Y203500D02*
X406892Y201500D01*
G01X404892Y216499D02*
Y203500D01*
G01X405302Y216909D02*
X404892Y216499D01*
G01X407706Y216909D02*
X405302D01*
G01X356188Y198807D02*
Y200204D01*
G01X397914Y200102D02*
Y195410D01*
G01X396692Y201324D02*
X397914Y200102D01*
G01X396692Y204599D02*
Y201324D01*
G01X394246Y207044D02*
X396692Y204599D01*
G01X393892Y207900D02*
G03X394246Y207044I1210J-1D01*
G01X393892Y208819D02*
Y207900D01*
G01X394281Y210272D02*
G03X393892Y208819I2521J-1453D01*
G01X394300Y211813D02*
G02X394281Y210272I-1384J-754D01*
G01Y211847D02*
X394300Y211813D01*
G01X394256Y211889D02*
X394281Y211847D01*
G01Y214172D02*
G03X394256Y211889I2015J-1164D01*
G01X392960Y216535D02*
G02X394281Y214172I-44J-1575D01*
G01X392818Y216535D02*
X392960D01*
G01X390901Y217696D02*
G03X392818Y216535I2015J1164D01*
G01X390888Y217719D02*
X390901Y217696D01*
G01X389537Y218484D02*
G02X390888Y217719I0J-1575D01*
G01X355807Y218484D02*
X355678D01*
G01X357752Y219647D02*
G02X355807Y218484I-2015J1162D01*
G01X357820Y219764D02*
X357752Y219647D01*
G01X359117Y222760D02*
X357820Y219764D01*
G01X377382Y220022D02*
X377357Y219980D01*
G01X377401Y220056D02*
X377382Y220022D01*
G01Y221597D02*
G02X377401Y220056I-1365J-787D01*
G01X377316Y221710D02*
X377382Y221597D01*
G01X376017Y224709D02*
X377316Y221710D01*
G01X417149Y228684D02*
G02X415634Y231797I21416J12348D01*
G01X415700Y225661D02*
X417149Y227110D01*
G01X414466Y225661D02*
X415700D01*
G01X411948Y223143D02*
X414466Y225661D01*
G01X399676Y222760D02*
X408418Y218500D01*
G01X415634Y218765D02*
X415376Y218507D01*
G01X415634Y220096D02*
Y218765D01*
G01X397595Y221710D02*
X396296Y224709D01*
G01X397661Y221597D02*
X397595Y221710D01*
G01X397680Y220056D02*
G03X397661Y221597I-1384J754D01*
G01Y220022D02*
X397680Y220056D01*
G01X397661Y219198D02*
G02Y220022I714J412D01*
G01X398311Y218072D02*
X397661Y219198D01*
G01X394865Y220138D02*
X392916Y222760D01*
G01X394931Y220022D02*
X394865Y220138D01*
G01X396252Y219234D02*
G02X394931Y220022I44J1575D01*
G01X396296Y219234D02*
X396252D01*
G01X397013Y218820D02*
G03X396296Y219234I-717J-414D01*
G01X378013Y219613D02*
G03X378032Y218072I1384J-754D01*
G01Y219647D02*
X378013Y219613D01*
G01X378057Y219689D02*
X378032Y219647D01*
G01X378492Y221385D02*
G02X378057Y219689I-3524J0D01*
G01X378492Y221855D02*
Y221385D01*
G01X379397Y222760D02*
X378492Y221855D01*
G01X399617Y221185D02*
X399807D01*
G01X398292Y223513D02*
G03X399617Y221185I1384J-753D01*
G01X398311Y223547D02*
X398292Y223513D01*
G01X398336Y223589D02*
X398311Y223547D01*
G01Y225872D02*
G02X398336Y223589I-2015J-1164D01*
G01X398245Y225987D02*
X398311Y225872D01*
G01X396296Y228610D02*
X398245Y225987D01*
G01X382777Y224709D02*
X381092Y220900D01*
G01X391587Y219707D02*
X391552Y219647D01*
G01Y221973D02*
G02X391587Y219707I-2015J-1164D01*
G01X391491Y222081D02*
X391552Y221973D01*
G01X389537Y224709D02*
X391491Y222081D01*
G01X415634Y227896D02*
X411198Y223460D01*
G01X389467Y218484D02*
X389537D01*
G01X387522Y219647D02*
G03X389467Y218484I2015J1162D01*
G01X387454Y219764D02*
X387522Y219647D01*
G01X386157Y222760D02*
X387454Y219764D01*
G01X377992Y399864D02*
X382192Y404064D01*
G01X377992Y393900D02*
Y399864D01*
G01X377382Y391623D02*
G03X377992Y393900I-3945J2277D01*
G01X377382Y389297D02*
G02Y391623I2015J1163D01*
G01X377401Y387756D02*
G03X377382Y389297I-1384J754D01*
G01X377314Y387605D02*
X377401Y387756D01*
G01X376017Y384609D02*
X377314Y387605D01*
G01X393492Y401900D02*
Y405000D01*
G01X388742Y397150D02*
X393492Y401900D01*
G01X388742Y390050D02*
Y397150D01*
G01X387732Y389040D02*
X388742Y390050D01*
G01X387732Y386596D02*
Y389040D01*
G01X386216Y384985D02*
G03X387732Y386596I-59J1575D01*
G01X386087Y384985D02*
X386216D01*
G01X384142Y381497D02*
G02X386087Y384985I2015J1163D01*
G01X384161Y379956D02*
G03X384142Y381497I-1384J754D01*
G01Y379922D02*
X384161Y379956D01*
G01X384117Y379880D02*
X384142Y379922D01*
G01Y377597D02*
G02X384117Y379880I2015J1164D01*
G01X384161Y376056D02*
G03X384142Y377597I-1384J754D01*
G01X384074Y375905D02*
X384161Y376056D01*
G01X382777Y372909D02*
X384074Y375905D01*
G01X354790Y397898D02*
Y407727D01*
G01X400192Y402300D02*
Y404700D01*
G01X398092Y400200D02*
X400192Y402300D01*
G01X398092Y394100D02*
Y400200D01*
G01X395892Y391900D02*
X398092Y394100D01*
G01X395892Y390466D02*
Y391900D01*
G01X395861Y390435D02*
X395892Y390466D01*
G01X394931Y389297D02*
G02X395861Y390435I3936J-2268D01*
G01X394912Y387756D02*
G02X394931Y389297I1384J754D01*
G01Y387722D02*
X394912Y387756D01*
G01X394956Y387680D02*
X394931Y387722D01*
G01Y385397D02*
G03X394956Y387680I-2015J1164D01*
G01X394912Y383856D02*
G02X394931Y385397I1384J754D01*
G01Y383822D02*
X394912Y383856D01*
G01X394956Y383780D02*
X394931Y383822D01*
G01Y381497D02*
G03X394956Y383780I-2015J1164D01*
G01X394912Y379956D02*
G02X394931Y381497I1384J754D01*
G01Y379922D02*
X394912Y379956D01*
G01X394956Y379880D02*
X394931Y379922D01*
G01X393001Y376435D02*
G03X394956Y379880I-85J2325D01*
G01X392916Y376435D02*
X393001D01*
G01X391565Y375670D02*
G02X392916Y376435I1351J-810D01*
G01X391488Y375534D02*
X391565Y375670D01*
G01X389537Y372909D02*
X391488Y375534D01*
G01X355736Y341710D02*
X355737Y341709D01*
G01X360818Y398526D02*
Y405327D01*
G01X358592Y396300D02*
X360818Y398526D01*
G01X358592Y388600D02*
Y396300D01*
G01X358058Y387727D02*
G03X358592Y388600I-1223J1348D01*
G01X357752Y385772D02*
G02X358058Y387727I1365J788D01*
G01X357777Y383489D02*
G03X357752Y385772I-2040J1119D01*
G01Y383447D02*
X357777Y383489D01*
G01X357733Y383413D02*
X357752Y383447D01*
G01Y381872D02*
G02X357733Y383413I1365J787D01*
G01X357818Y381759D02*
X357752Y381872D01*
G01X359117Y378760D02*
X357818Y381759D01*
G01X401392Y401800D02*
Y403600D01*
G01X399492Y399900D02*
X401392Y401800D01*
G01X399492Y393300D02*
Y399900D01*
G01X397872Y391680D02*
X399492Y393300D01*
G01X397872Y384589D02*
Y391680D01*
G01X397661Y383822D02*
G03X397872Y384589I-1289J767D01*
G01X397636Y383780D02*
X397661Y383822D01*
G01Y381497D02*
G02X397636Y383780I2015J1164D01*
G01X397680Y379956D02*
G03X397661Y381497I-1384J754D01*
G01Y379922D02*
X397680Y379956D01*
G01X397636Y379880D02*
X397661Y379922D01*
G01Y377597D02*
G02X397636Y379880I2015J1164D01*
G01X396340Y375234D02*
G03X397661Y377597I-44J1575D01*
G01X396150Y375234D02*
X396340D01*
G01X392916Y374860D02*
X396150Y375234D01*
G01X355663Y397271D02*
Y406071D01*
G01X355796Y378384D02*
X355667D01*
G01X357121Y376056D02*
G03X355796Y378384I-1384J753D01*
G01X357102Y376022D02*
X357121Y376056D01*
G01X357077Y375980D02*
X357102Y376022D01*
G01X356925Y375642D02*
G02X357077Y375980I2191J-782D01*
G01X355737Y372909D02*
X356925Y375642D01*
G01X400892Y379976D02*
X399676Y378760D01*
G01X400892Y381100D02*
Y379976D01*
G01X405992Y386200D02*
X400892Y381100D01*
G01X405992Y399100D02*
Y386200D01*
G01X408692Y401800D02*
X405992Y399100D01*
G01X408692Y403716D02*
Y401800D01*
G01X398245Y375531D02*
X396296Y372909D01*
G01X398311Y375647D02*
X398245Y375531D01*
G01X398336Y375689D02*
X398311Y375647D01*
G01Y377972D02*
G02X398336Y375689I-2015J-1164D01*
G01X398292Y379513D02*
G03X398311Y377972I1384J-754D01*
G01Y379547D02*
X398292Y379513D01*
G01X398336Y379589D02*
X398311Y379547D01*
G01Y381872D02*
G02X398336Y379589I-2015J-1164D01*
G01X399632Y384235D02*
G03X398311Y381872I44J-1575D01*
G01X400327Y384235D02*
X399632D01*
G01X400792Y384700D02*
X400327Y384235D01*
G01X401792Y384700D02*
X400792D01*
G01X405092Y388000D02*
X401792Y384700D01*
G01X405092Y401200D02*
Y388000D01*
G01X404692Y401600D02*
X405092Y401200D01*
G01X404692Y403300D02*
Y401600D01*
G01X378344Y388500D02*
G03X379397Y386560I2314J0D01*
G01X378327Y388792D02*
G02X378344Y388500I-2310J-281D01*
G01X378275Y389071D02*
G02X378327Y388792I-2257J-565D01*
G01X378032Y389672D02*
G02X378275Y389071I-2015J-1164D01*
G01X378013Y391213D02*
G03X378032Y389672I1384J-754D01*
G01Y391247D02*
X378013Y391213D01*
G01X378892Y392900D02*
G02X378032Y391247I-28098J13568D01*
G01X379192Y394211D02*
G02X378892Y392900I-3015J0D01*
G01X379192Y399304D02*
Y394211D01*
G01X384192Y404304D02*
X379192Y399304D01*
G01X413592Y400300D02*
Y405292D01*
G01X409492Y396200D02*
X413592Y400300D01*
G01X409492Y383388D02*
Y396200D01*
G01X407892Y381788D02*
X409492Y383388D01*
G01X407892Y374200D02*
Y381788D01*
G01X404692Y371000D02*
X407892Y374200D01*
G01X402392Y371000D02*
X404692D01*
G01X400402Y369010D02*
X402392Y371000D01*
G01X396296Y369010D02*
X400402D01*
G01X359618Y399426D02*
Y406326D01*
G01X357592Y397400D02*
X359618Y399426D01*
G01X357592Y388700D02*
Y397400D01*
G01X357431Y388163D02*
G03X357592Y388700I-450J427D01*
G01X357102Y385397D02*
G02X357431Y388163I2015J1163D01*
G01X357121Y383856D02*
G03X357102Y385397I-1384J754D01*
G01X357034Y383705D02*
X357121Y383856D01*
G01X355737Y380709D02*
X357034Y383705D01*
G01X394592Y396000D02*
Y404614D01*
G01X390392Y391800D02*
X394592Y396000D01*
G01X390392Y389924D02*
Y391800D01*
G01X390553Y389763D02*
X390392Y389924D01*
G01X390901Y389296D02*
G03X390553Y389763I-2180J-1261D01*
G01X390901Y387722D02*
G03Y389296I-1364J787D01*
G01X390866Y387662D02*
X390901Y387722D01*
G01Y385396D02*
G02X390866Y387662I2015J1164D01*
G01X389537Y383034D02*
G03X390901Y385396I0J1575D01*
G01X389452Y383034D02*
X389537D01*
G01X387522Y381872D02*
G02X389452Y383034I2015J-1163D01*
G01X386157Y378760D02*
X387522Y381872D01*
G01X377314Y375905D02*
X376017Y372909D01*
G01X377382Y376022D02*
X377314Y375905D01*
G01X379327Y377185D02*
G03X377382Y376022I70J-2325D01*
G01X379456Y377185D02*
X379327D01*
G01X380781Y379513D02*
G02X379456Y377185I-1384J-753D01*
G01X380762Y379547D02*
X380781Y379513D01*
G01X380737Y379589D02*
X380762Y379547D01*
G01Y381872D02*
G03X380737Y379589I2015J-1164D01*
G01X380781Y383413D02*
G02X380762Y381872I-1384J-754D01*
G01Y383447D02*
X380781Y383413D01*
G01X380737Y383489D02*
X380762Y383447D01*
G01Y385772D02*
G03X380737Y383489I2015J-1164D01*
G01X380781Y387313D02*
G02X380762Y385772I-1384J-754D01*
G01Y387347D02*
X380781Y387313D01*
G01X380737Y387389D02*
X380762Y387347D01*
G01Y389672D02*
G03X380737Y387389I2015J-1164D01*
G01X381092Y391000D02*
G02X380762Y389672I-2472J-91D01*
G01X381092Y399404D02*
Y391000D01*
G01X385792Y404104D02*
X381092Y399404D01*
G01X384492Y386324D02*
X382777Y384609D01*
G01X384492Y389900D02*
Y386324D01*
G01X386092Y391500D02*
X384492Y389900D01*
G01X386092Y400600D02*
Y391500D01*
G01X388992Y403500D02*
X386092Y400600D01*
G01X362018Y397926D02*
Y404625D01*
G01X359718Y395626D02*
X362018Y397926D01*
G01X359718Y388481D02*
Y395626D01*
G01X359117Y387880D02*
X359718Y388481D01*
G01X359117Y386560D02*
Y387880D01*
G01X410692Y401700D02*
Y404365D01*
G01X407392Y398400D02*
X410692Y401700D01*
G01X407392Y385045D02*
Y398400D01*
G01X403056Y380709D02*
X407392Y385045D01*
G01X412192Y401100D02*
Y406100D01*
G01X408492Y397400D02*
X412192Y401100D01*
G01X408492Y384460D02*
Y397400D01*
G01X405492Y381460D02*
X408492Y384460D01*
G01X405492Y376980D02*
Y381460D01*
G01X403372Y374860D02*
X405492Y376980D01*
G01X399676Y374860D02*
X403372D01*
G01X396892Y394900D02*
Y403500D01*
G01X394492Y392500D02*
X396892Y394900D01*
G01X394492Y390459D02*
Y392500D01*
G01X394281Y389672D02*
G03X394492Y390459I-1363J787D01*
G01X394256Y387389D02*
G02X394281Y389672I2040J1119D01*
G01Y387347D02*
X394256Y387389D01*
G01X394300Y387313D02*
X394281Y387347D01*
G01Y385772D02*
G03X394300Y387313I-1365J787D01*
G01X394256Y383489D02*
G02X394281Y385772I2040J1119D01*
G01Y383447D02*
X394256Y383489D01*
G01X394300Y383413D02*
X394281Y383447D01*
G01X392975Y381085D02*
G03X394300Y383413I-59J1575D01*
G01X392846Y381085D02*
X392975D01*
G01X390901Y379922D02*
G02X392846Y381085I2015J-1162D01*
G01X390888Y379899D02*
X390901Y379922D01*
G01X389537Y379134D02*
G03X390888Y379899I0J1575D01*
G01X389452Y379134D02*
X389537D01*
G01X387522Y377972D02*
G02X389452Y379134I2015J-1163D01*
G01X387456Y377859D02*
X387522Y377972D01*
G01X386157Y374860D02*
X387456Y377859D01*
G01X357168Y344938D02*
X359117Y347560D01*
G01X357102Y344822D02*
X357168Y344938D01*
G01X356882Y344535D02*
G03X357102Y344822I-976J976D01*
G01X356251Y343904D02*
X356882Y344535D01*
G01X355509Y343904D02*
X356251D01*
G01X386157Y389265D02*
Y386560D01*
G01X387642Y390750D02*
X386157Y389265D01*
G01X387642Y399950D02*
Y390750D01*
G01X390092Y402400D02*
X387642Y399950D01*
G01X390092Y403700D02*
Y402400D01*
G01X395692Y395800D02*
Y403800D01*
G01X391292Y391400D02*
X395692Y395800D01*
G01X391292Y390643D02*
Y391400D01*
G01X391552Y389673D02*
G02X391292Y390643I1679J970D01*
G01X391587Y387407D02*
G03X391552Y389673I-2050J1102D01*
G01Y387347D02*
X391587Y387407D01*
G01X391552Y385773D02*
G02Y387347I1364J787D01*
G01X391587Y383507D02*
G03X391552Y385773I-2050J1102D01*
G01Y383447D02*
X391587Y383507D01*
G01X391488Y383334D02*
X391552Y383447D01*
G01X389537Y380709D02*
X391488Y383334D01*
G01X363218Y397026D02*
Y404227D01*
G01X360918Y394726D02*
X363218Y397026D01*
G01X360918Y388040D02*
Y394726D01*
G01X362497Y384609D02*
X360918Y388040D01*
G01X381204Y376905D02*
G02X379397Y374860I-2061J0D01*
G01X381412Y377597D02*
G03X381204Y376905I1365J-788D01*
G01X381437Y379880D02*
G02X381412Y377597I-2040J-1119D01*
G01Y379922D02*
X381437Y379880D01*
G01X381393Y379956D02*
X381412Y379922D01*
G01Y381497D02*
G03X381393Y379956I1365J-787D01*
G01X381437Y383780D02*
G02X381412Y381497I-2040J-1119D01*
G01Y383822D02*
X381437Y383780D01*
G01X381393Y383856D02*
X381412Y383822D01*
G01Y385397D02*
G03X381393Y383856I1365J-787D01*
G01X381437Y387680D02*
G02X381412Y385397I-2040J-1119D01*
G01Y387722D02*
X381437Y387680D01*
G01X381393Y387756D02*
X381412Y387722D01*
G01Y389297D02*
G03X381393Y387756I1365J-787D01*
G01X382092Y390400D02*
G03X381412Y389297I18375J-12089D01*
G01X382092Y398400D02*
Y390400D01*
G01X387512Y403820D02*
X382092Y398400D01*
G01X356413Y396521D02*
Y405321D01*
G01X355822Y379134D02*
X355693D01*
G01X357752Y377972D02*
G03X355822Y379134I-2015J-1163D01*
G01X357818Y377859D02*
X357752Y377972D01*
G01X359117Y374860D02*
X357818Y377859D01*
G01X382192Y404064D02*
Y407043D01*
G01X394192Y405700D02*
Y406684D01*
G01X393492Y405000D02*
X394192Y405700D01*
G01X402192Y406700D02*
Y407687D01*
G01X400192Y404700D02*
X402192Y406700D01*
G01X362790Y407299D02*
Y408331D01*
G01X360818Y405327D02*
X362790Y407299D01*
G01X404192Y406400D02*
Y407669D01*
G01X401392Y403600D02*
X404192Y406400D01*
G01X356790Y407198D02*
Y407982D01*
G01X355663Y406071D02*
X356790Y407198D01*
G01X408192Y404216D02*
X408692Y403716D01*
G01X408192Y405358D02*
Y404216D01*
G01X406192Y404800D02*
X404692Y403300D01*
G01X406192Y405734D02*
Y404800D01*
G01X384192Y406734D02*
Y404304D01*
G01X414192Y405892D02*
Y406826D01*
G01X413592Y405292D02*
X414192Y405892D01*
G01X360790Y407498D02*
Y408385D01*
G01X359618Y406326D02*
X360790Y407498D01*
G01X396192Y406214D02*
Y406935D01*
G01X394592Y404614D02*
X396192Y406214D01*
G01X385792Y405592D02*
Y404104D01*
G01X386192Y405992D02*
X385792Y405592D01*
G01X386192Y406737D02*
Y405992D01*
G01X388992Y404566D02*
Y403500D01*
G01X390192Y405766D02*
X388992Y404566D01*
G01X390192Y406540D02*
Y405766D01*
G01X364790Y407397D02*
Y408465D01*
G01X362018Y404625D02*
X364790Y407397D01*
G01X410192Y404865D02*
Y405805D01*
G01X410692Y404365D02*
X410192Y404865D01*
G01X400192Y406800D02*
Y407615D01*
G01X396892Y403500D02*
X400192Y406800D01*
G01X392192Y405800D02*
X390092Y403700D01*
G01X392192Y406612D02*
Y405800D01*
G01X398192Y406300D02*
Y407132D01*
G01X395692Y403800D02*
X398192Y406300D01*
G01X366790Y407799D02*
Y408694D01*
G01X363218Y404227D02*
X366790Y407799D01*
G01X387512Y405216D02*
Y403820D01*
G01X388192Y405896D02*
X387512Y405216D01*
G01X388192Y406629D02*
Y405896D01*
G01X358790Y407698D02*
Y408586D01*
G01X356413Y405321D02*
X358790Y407698D01*
G01X444238Y216984D02*
G02X444213Y219267I2015J1164D01*
G01X444257Y215443D02*
G03X444238Y216984I-1384J754D01*
G01X444232Y213160D02*
G02X444257Y215443I2040J1119D01*
G01Y213118D02*
X444232Y213160D01*
G01X444276Y213084D02*
X444257Y213118D01*
G01Y211543D02*
G03X444276Y213084I-1365J787D01*
G01X443693Y210532D02*
X444257Y211543D01*
G01X443693Y205599D02*
Y210532D01*
G01X449992Y199300D02*
X443693Y205599D01*
G01X449992Y195270D02*
Y199300D01*
G01X455662Y189600D02*
X449992Y195270D01*
G01X455662Y185770D02*
Y189600D01*
G01X454692Y184800D02*
X455662Y185770D01*
G01X455028Y216984D02*
G03X455053Y219267I-2015J1164D01*
G01X455009Y215443D02*
G02X455028Y216984I1384J754D01*
G01Y215409D02*
X455009Y215443D01*
G01X455053Y215367D02*
X455028Y215409D01*
G01Y213084D02*
G03X455053Y215367I-2015J1164D01*
G01X455009Y211543D02*
G02X455028Y213084I1384J754D01*
G01X456292Y209301D02*
X455009Y211543D01*
G01X456292Y207590D02*
Y209301D01*
G01X464522Y199360D02*
X456292Y207590D01*
G01X464522Y196560D02*
Y199360D01*
G01X469162Y191920D02*
X464522Y196560D01*
G01X469162Y186130D02*
Y191920D01*
G01X469884Y185408D02*
X469162Y186130D01*
G01X417927Y196572D02*
X417925D01*
G01X417927Y191134D02*
Y196572D01*
G01X419046Y190015D02*
X417927Y191134D01*
G01X419046Y179345D02*
Y190015D01*
G01X419890Y178501D02*
X419046Y179345D01*
G01X440858Y217359D02*
G03X440877Y218900I-1365J787D01*
G01X440833Y215076D02*
G02X440858Y217359I2040J1119D01*
G01Y215034D02*
X440833Y215076D01*
G01X440877Y213493D02*
G03X440858Y215034I-1384J754D01*
G01Y213459D02*
X440877Y213493D01*
G01X440833Y213417D02*
X440858Y213459D01*
G01Y211134D02*
G02X440833Y213417I2015J1164D01*
G01X440876Y209590D02*
G03X440858Y211134I-1383J756D01*
G01X440192Y208410D02*
X440876Y209590D01*
G01X440192Y204740D02*
Y208410D01*
G01X446842Y198090D02*
X440192Y204740D01*
G01X446842Y194080D02*
Y198090D01*
G01X450622Y190300D02*
X446842Y194080D01*
G01X450622Y184630D02*
Y190300D01*
G01X449692Y183700D02*
X450622Y184630D01*
G01X423806Y179585D02*
X424890Y178501D01*
G01X423806Y180821D02*
Y179585D01*
G01X422064Y182563D02*
X423806Y180821D01*
G01X422064Y191561D02*
Y182563D01*
G01X420948Y192677D02*
X422064Y191561D01*
G01X420948Y192679D02*
Y192677D01*
G01X420946Y192681D02*
X420948Y192679D01*
G01X420946Y197824D02*
Y192681D01*
G01X417957Y200813D02*
X420946Y197824D01*
G01X417957Y209141D02*
Y200813D01*
G01X417728Y209554D02*
X417957Y209141D01*
G01X417728Y211140D02*
G03Y209554I1436J-793D01*
G01X417752Y211183D02*
X417728Y211140D01*
G01X417008Y214254D02*
G02X417752Y211183I-1374J-1958D01*
G01X416756Y214409D02*
G02X417008Y214254I-1101J-2072D01*
G01X478112Y202690D02*
X483737Y197065D01*
G01X476442Y202690D02*
X478112D01*
G01X474943Y204189D02*
X476442Y202690D01*
G01X473362Y204872D02*
G02X474943Y204189I-70J-2334D01*
G01X473233Y204872D02*
X473362D01*
G01X471908Y207200D02*
G03X473233Y204872I1384J-753D01*
G01X471927Y207234D02*
X471908Y207200D01*
G01X471952Y207276D02*
X471927Y207234D01*
G01Y209559D02*
G02X471952Y207276I-2015J-1164D01*
G01X471908Y211100D02*
G03X471927Y209559I1384J-754D01*
G01Y211134D02*
X471908Y211100D01*
G01X471952Y211176D02*
X471927Y211134D01*
G01Y213459D02*
G02X471952Y211176I-2015J-1164D01*
G01X471896Y214978D02*
G03X471927Y213459I1396J-731D01*
G01X471963Y215094D02*
X471896Y214978D01*
G01X471928Y217360D02*
G02X471963Y215094I-2015J-1164D01*
G01X471928Y218934D02*
G03Y217360I1364J-787D01*
G01X423058Y179166D02*
X422390Y178498D01*
G01X423058Y180511D02*
Y179166D01*
G01X421316Y182253D02*
X423058Y180511D01*
G01X421316Y191251D02*
Y182253D01*
G01X420197Y192370D02*
X421316Y191251D01*
G01X420197Y197511D02*
Y192370D01*
G01X417209Y200499D02*
X420197Y197511D01*
G01X417209Y208940D02*
Y200499D01*
G01X417070Y209190D02*
X417209Y208940D01*
G01X417046Y211460D02*
G03X417070Y209190I2118J-1113D01*
G01X417089Y211537D02*
X417046Y211460D01*
G01X417070Y213090D02*
G02X417089Y211537I-1436J-794D01*
G01X441576Y180697D02*
X440710Y179831D01*
G01X441576Y182277D02*
Y180697D01*
G01X433440Y190413D02*
X441576Y182277D01*
G01X433440Y194489D02*
Y190413D01*
G01X432328Y195601D02*
X433440Y194489D01*
G01X432328Y204892D02*
Y195601D01*
G01X430929Y206291D02*
X432328Y204892D01*
G01X430929Y212717D02*
Y206291D01*
G01X430718Y213082D02*
X430929Y212717D01*
G01X430676Y215336D02*
G03X430718Y213082I2057J-1089D01*
G01Y215409D02*
X430676Y215336D01*
G01X430718Y216983D02*
G02Y215409I-1364J-787D01*
G01X430683Y219249D02*
G03X430718Y216983I2050J-1102D01*
G01X474172Y186870D02*
X474884Y186158D01*
G01X474172Y191282D02*
Y186870D01*
G01X467442Y198012D02*
X474172Y191282D01*
G01X467442Y200880D02*
Y198012D01*
G01X458361Y209961D02*
X467442Y200880D01*
G01X458361Y210958D02*
Y209961D01*
G01X458408Y211133D02*
G03X458361Y210958I304J-175D01*
G01X458408Y213459D02*
G02Y211133I-2015J-1163D01*
G01X458389Y215000D02*
G03X458408Y213459I1384J-754D01*
G01Y215034D02*
X458389Y215000D01*
G01X458433Y215076D02*
X458408Y215034D01*
G01Y217359D02*
G02X458433Y215076I-2015J-1164D01*
G01X458389Y218900D02*
G03X458408Y217359I1384J-754D01*
G01X454378D02*
G03X454397Y218900I-1365J787D01*
G01X454353Y215076D02*
G02X454378Y217359I2040J1119D01*
G01Y215034D02*
X454353Y215076D01*
G01X454397Y215000D02*
X454378Y215034D01*
G01Y213459D02*
G03X454397Y215000I-1365J787D01*
G01X454353Y211176D02*
G02X454378Y213459I2040J1119D01*
G01X455461Y209156D02*
X454353Y211176D01*
G01X455461Y207170D02*
Y209156D01*
G01X463702Y198929D02*
X455461Y207170D01*
G01X463702Y196318D02*
Y198929D01*
G01X468412Y191608D02*
X463702Y196318D01*
G01X468412Y186220D02*
Y191608D01*
G01X467384Y185192D02*
X468412Y186220D01*
G01X437166Y180875D02*
X438210Y179831D01*
G01X437166Y183477D02*
Y180875D01*
G01X431170Y189473D02*
X437166Y183477D01*
G01X431170Y194589D02*
Y189473D01*
G01X430058Y195701D02*
X431170Y194589D01*
G01X430058Y204192D02*
Y195701D01*
G01X428669Y205581D02*
X430058Y204192D01*
G01X428669Y210327D02*
Y205581D01*
G01X427989Y211506D02*
X428669Y210327D01*
G01X427989Y213082D02*
G03Y211506I1365J-788D01*
G01Y215408D02*
G02Y213082I-2015J-1163D01*
G01Y216984D02*
G03Y215408I1365J-788D01*
G01X426044Y220472D02*
G02X427989Y216984I-70J-2325D01*
G01X444888Y217359D02*
G02X444869Y218900I1365J787D01*
G01X444913Y215076D02*
G03X444888Y217359I-2040J1119D01*
G01X444894Y213535D02*
G02X444913Y215076I1384J754D01*
G01Y213501D02*
X444894Y213535D01*
G01X444938Y213459D02*
X444913Y213501D01*
G01Y211176D02*
G03X444938Y213459I-2015J1164D01*
G01X444443Y210336D02*
X444913Y211176D01*
G01X444443Y205910D02*
Y210336D01*
G01X450742Y199611D02*
X444443Y205910D01*
G01X450742Y195582D02*
Y199611D01*
G01X456412Y189912D02*
X450742Y195582D01*
G01X456412Y185680D02*
Y189912D01*
G01X457192Y184900D02*
X456412Y185680D01*
G01X442324Y180717D02*
X443210Y179831D01*
G01X442324Y182587D02*
Y180717D01*
G01X434188Y190723D02*
X442324Y182587D01*
G01X434188Y194799D02*
Y190723D01*
G01X433078Y195909D02*
X434188Y194799D01*
G01X433078Y205203D02*
Y195909D01*
G01X431677Y206604D02*
X433078Y205203D01*
G01X431677Y212925D02*
Y206604D01*
G01X431369Y213459D02*
X431677Y212925D01*
G01X431350Y215000D02*
G03X431369Y213459I1383J-754D01*
G01Y215034D02*
X431350Y215000D01*
G01X431404Y215094D02*
X431369Y215034D01*
G01Y217360D02*
G02X431404Y215094I-2015J-1164D01*
G01X431369Y218934D02*
G03Y217360I1364J-787D01*
G01X418298Y179406D02*
X417666Y178774D01*
G01X418298Y189705D02*
Y179406D01*
G01X417178Y190825D02*
X418298Y189705D01*
G01X417178Y196215D02*
Y190825D01*
G01X436418Y180551D02*
X435698Y179831D01*
G01X436418Y183167D02*
Y180551D01*
G01X430422Y189163D02*
X436418Y183167D01*
G01X430422Y194279D02*
Y189163D01*
G01X429308Y195393D02*
X430422Y194279D01*
G01X429308Y203881D02*
Y195393D01*
G01X427919Y205270D02*
X429308Y203881D01*
G01X427919Y210125D02*
Y205270D01*
G01X427339Y211131D02*
X427919Y210125D01*
G01X427339Y213457D02*
G03Y211131I2015J-1163D01*
G01Y215033D02*
G02Y213457I-1365J-788D01*
G01Y217359D02*
G03Y215033I2015J-1163D01*
G01X426018Y219722D02*
G02X427339Y217359I-44J-1575D01*
G01X478029Y194825D02*
X479552Y193302D01*
G01X476837Y194825D02*
X478029D01*
G01X472602Y199060D02*
X476837Y194825D01*
G01X472602Y199891D02*
Y199060D01*
G01X470322Y202171D02*
X472602Y199891D01*
G01X469827Y202171D02*
X470322D01*
G01X467897Y205659D02*
G03X469827Y202171I2015J-1163D01*
G01X467897Y207233D02*
G02Y205659I-1364J-787D01*
G01X467872Y207275D02*
X467897Y207233D01*
G01Y209560D02*
G03X467872Y207275I2015J-1165D01*
G01X467897Y211134D02*
G02Y209560I-1364J-787D01*
G01X467862Y211194D02*
X467897Y211134D01*
G01Y213460D02*
G03X467862Y211194I2015J-1164D01*
G01X467923Y213505D02*
X467897Y213460D01*
G01X467898Y215034D02*
G02X467923Y213505I-1365J-787D01*
G01X467873Y215076D02*
X467898Y215034D01*
G01Y217359D02*
G03X467873Y215076I2015J-1164D01*
G01X467917Y218900D02*
G02X467898Y217359I-1384J-754D01*
G01X476343Y196380D02*
X479140D01*
G01X473352Y199371D02*
X476343Y196380D01*
G01X473352Y200202D02*
Y199371D01*
G01X470633Y202921D02*
X473352Y200202D01*
G01X469912Y202921D02*
X470633D01*
G01X468548Y205283D02*
G03X469912Y202921I1364J-787D01*
G01X468548Y207609D02*
G02Y205283I-2015J-1163D01*
G01Y209183D02*
G03Y207609I1364J-787D01*
G01X468583Y211449D02*
G02X468548Y209183I-2050J-1102D01*
G01Y211509D02*
X468583Y211449D01*
G01X468548Y213083D02*
G03Y211509I1364J-787D01*
G01X468583Y215349D02*
G02X468548Y213083I-2050J-1102D01*
G01Y215409D02*
X468583Y215349D01*
G01X468529Y215443D02*
X468548Y215409D01*
G01Y216984D02*
G03X468529Y215443I1365J-787D01*
G01X468573Y219267D02*
G02X468548Y216984I-2040J-1119D01*
G01X441508D02*
G03X441533Y219267I-2015J1164D01*
G01X441489Y215443D02*
G02X441508Y216984I1384J754D01*
G01Y215409D02*
X441489Y215443D01*
G01X441533Y213126D02*
G03X441508Y215409I-2040J1119D01*
G01Y213084D02*
X441533Y213126D01*
G01X441489Y213050D02*
X441508Y213084D01*
G01Y211509D02*
G02X441489Y213050I1365J787D01*
G01X441533Y209226D02*
G03X441508Y211509I-2040J1119D01*
G01X440997Y208268D02*
X441533Y209226D01*
G01X440992Y208263D02*
X440997Y208268D01*
G01X440992Y205001D02*
Y208263D01*
G01X447592Y198401D02*
X440992Y205001D01*
G01X447592Y194392D02*
Y198401D01*
G01X451496Y190488D02*
X447592Y194392D01*
G01X451496Y184696D02*
Y190488D01*
G01X452192Y184000D02*
X451496Y184696D01*
G01X473332Y186546D02*
X472384Y185598D01*
G01X473332Y191060D02*
Y186546D01*
G01X466692Y197700D02*
X473332Y191060D01*
G01X466692Y200460D02*
Y197700D01*
G01X457592Y209560D02*
X466692Y200460D01*
G01X457592Y210889D02*
Y209560D01*
G01X457758Y211509D02*
G03X457592Y210889I1074J-620D01*
G01X457777Y211543D02*
X457758Y211509D01*
G01Y213084D02*
G02X457777Y211543I-1365J-787D01*
G01X457733Y215367D02*
G03X457758Y213084I2040J-1119D01*
G01Y215409D02*
X457733Y215367D01*
G01X457777Y215443D02*
X457758Y215409D01*
G01Y216984D02*
G02X457777Y215443I-1365J-787D01*
G01X457733Y219267D02*
G03X457758Y216984I2040J-1119D01*
G01X477800Y201940D02*
X482292Y197448D01*
G01X476051Y201940D02*
X477800D01*
G01X474657Y203334D02*
X476051Y201940D01*
G01X473336Y204122D02*
G02X474657Y203334I-44J-1575D01*
G01X473207Y204122D02*
X473336D01*
G01X471252Y207567D02*
G03X473207Y204122I2040J-1120D01*
G01X471277Y207609D02*
X471252Y207567D01*
G01X471296Y207643D02*
X471277Y207609D01*
G01Y209184D02*
G02X471296Y207643I-1365J-787D01*
G01X471252Y211467D02*
G03X471277Y209184I2040J-1119D01*
G01Y211509D02*
X471252Y211467D01*
G01X471296Y211543D02*
X471277Y211509D01*
G01Y213084D02*
G02X471296Y211543I-1365J-787D01*
G01X471252Y215367D02*
G03X471277Y213084I2040J-1119D01*
G01Y215409D02*
X471252Y215367D01*
G01X471277Y216983D02*
G02Y215409I-1364J-787D01*
G01X471242Y219249D02*
G03X471277Y216983I2050J-1102D01*
G01X444303Y231124D02*
X446253Y233746D01*
G01X444238Y231010D02*
X444303Y231124D01*
G01X444238Y228684D02*
G02Y231010I2015J1163D01*
G01X444257Y227143D02*
G03X444238Y228684I-1384J754D01*
G01Y227109D02*
X444257Y227143D01*
G01X444213Y227067D02*
X444238Y227109D01*
G01Y224784D02*
G02X444213Y227067I2015J1164D01*
G01X444257Y223243D02*
G03X444238Y224784I-1384J754D01*
G01Y223209D02*
X444257Y223243D01*
G01X444213Y223167D02*
X444238Y223209D01*
G01Y220884D02*
G02X444213Y223167I2015J1164D01*
G01X444257Y219343D02*
G03X444238Y220884I-1384J754D01*
G01Y219309D02*
X444257Y219343D01*
G01X444213Y219267D02*
X444238Y219309D01*
G01X454962Y238925D02*
X453013Y241547D01*
G01X455028Y238809D02*
X454962Y238925D01*
G01X455053Y238767D02*
X455028Y238809D01*
G01Y236484D02*
G03X455053Y238767I-2015J1164D01*
G01X455009Y234943D02*
G02X455028Y236484I1384J754D01*
G01Y234909D02*
X455009Y234943D01*
G01X455053Y232626D02*
G03X455028Y234909I-2040J1119D01*
G01Y232584D02*
X455053Y232626D01*
G01X455028Y231010D02*
G02Y232584I1365J787D01*
G01Y228684D02*
G03Y231010I-2015J1163D01*
G01X455009Y227143D02*
G02X455028Y228684I1384J754D01*
G01Y227109D02*
X455009Y227143D01*
G01X455053Y227067D02*
X455028Y227109D01*
G01Y224784D02*
G03X455053Y227067I-2015J1164D01*
G01X455009Y223243D02*
G02X455028Y224784I1384J754D01*
G01Y223209D02*
X455009Y223243D01*
G01X455053Y223167D02*
X455028Y223209D01*
G01Y220884D02*
G03X455053Y223167I-2015J1164D01*
G01X455009Y219343D02*
G02X455028Y220884I1384J754D01*
G01Y219309D02*
X455009Y219343D01*
G01X455053Y219267D02*
X455028Y219309D01*
G01X417149Y227110D02*
G03Y228684I-1365J787D01*
G01X440924Y233075D02*
X442873Y235696D01*
G01X440858Y232959D02*
X440924Y233075D01*
G01X440833Y232917D02*
X440858Y232959D01*
G01Y230634D02*
G02X440833Y232917I2015J1164D01*
G01X440877Y230600D02*
X440858Y230634D01*
G01Y229059D02*
G03X440877Y230600I-1365J787D01*
G01X440833Y226776D02*
G02X440858Y229059I2040J1119D01*
G01Y226734D02*
X440833Y226776D01*
G01X440877Y226700D02*
X440858Y226734D01*
G01Y225159D02*
G03X440877Y226700I-1365J787D01*
G01X440833Y222876D02*
G02X440858Y225159I2040J1119D01*
G01Y222834D02*
X440833Y222876D01*
G01X440877Y222800D02*
X440858Y222834D01*
G01Y221259D02*
G03X440877Y222800I-1365J787D01*
G01X440833Y218976D02*
G02X440858Y221259I2040J1119D01*
G01Y218934D02*
X440833Y218976D01*
G01X440877Y218900D02*
X440858Y218934D01*
G01X471963Y218994D02*
X471928Y218934D01*
G01Y221260D02*
G02X471963Y218994I-2015J-1164D01*
G01X471928Y222834D02*
G03Y221260I1364J-787D01*
G01X471963Y222894D02*
X471928Y222834D01*
G01X470011Y226321D02*
G02X471963Y222894I-98J-2325D01*
G01X469869Y226321D02*
X470011D01*
G01X468548Y227109D02*
G03X469869Y226321I1365J787D01*
G01X466603Y228272D02*
G02X468548Y227109I-70J-2325D01*
G01X466474Y228272D02*
X466603D01*
G01X466069Y231352D02*
G03X466474Y228272I463J-1506D01*
G01X467873Y232917D02*
G02X466069Y231352I-3269J1946D01*
G01X467898Y232959D02*
X467873Y232917D01*
G01X467898Y234533D02*
G02Y232959I-1365J-787D01*
G01X467723Y234912D02*
G03X467898Y234533I2191J782D01*
G01X466002Y236163D02*
G02X467723Y234912I-1275J-3563D01*
G01X465149Y238400D02*
G03X466002Y236163I1384J-753D01*
G01X465236Y238551D02*
X465149Y238400D01*
G01X466533Y241547D02*
X465236Y238551D01*
G01X476928Y238009D02*
G02X478687Y236859I-256J-2312D01*
G01X476672Y238265D02*
X476928Y238009D01*
G01X476672Y239596D02*
Y238265D01*
G01X430718Y219309D02*
X430683Y219249D01*
G01X429354Y221671D02*
G02X430718Y219309I0J-1575D01*
G01X429284Y221671D02*
X429354D01*
G01X427339Y222834D02*
G03X429284Y221671I2015J1162D01*
G01X426202Y223606D02*
G02X427339Y222834I-228J-1559D01*
G01X425974Y223378D02*
X426202Y223606D01*
G01X425974Y222047D02*
Y223378D01*
G01X478037Y236484D02*
G03X480001Y235321I2015J1163D01*
G01X476900Y237255D02*
G02X478037Y236484I-228J-1560D01*
G01X476672Y237027D02*
X476900Y237255D01*
G01X476672Y235696D02*
Y237027D01*
G01X458408Y218934D02*
X458389Y218900D01*
G01X458433Y218976D02*
X458408Y218934D01*
G01Y221259D02*
G02X458433Y218976I-2015J-1164D01*
G01X458389Y222800D02*
G03X458408Y221259I1384J-754D01*
G01Y222834D02*
X458389Y222800D01*
G01X458433Y222876D02*
X458408Y222834D01*
G01Y225159D02*
G02X458433Y222876I-2015J-1164D01*
G01X458389Y226700D02*
G03X458408Y225159I1384J-754D01*
G01Y226734D02*
X458389Y226700D01*
G01X458433Y226776D02*
X458408Y226734D01*
G01Y229059D02*
G02X458433Y226776I-2015J-1164D01*
G01X458389Y230600D02*
G03X458408Y229059I1384J-754D01*
G01Y230634D02*
X458389Y230600D01*
G01X458433Y232917D02*
G02X458408Y230634I-2040J-1119D01*
G01Y232959D02*
X458433Y232917D01*
G01X458408Y234533D02*
G03Y232959I1365J-787D01*
G01Y236859D02*
G02Y234533I-2015J-1163D01*
G01X458342Y236975D02*
X458408Y236859D01*
G01X456393Y239596D02*
X458342Y236975D01*
G01X454313Y230746D02*
X453013Y233746D01*
G01X454397Y230600D02*
X454313Y230746D01*
G01X454378Y229059D02*
G03X454397Y230600I-1365J787D01*
G01X454353Y226776D02*
G02X454378Y229059I2040J1119D01*
G01Y226734D02*
X454353Y226776D01*
G01X454397Y226700D02*
X454378Y226734D01*
G01Y225159D02*
G03X454397Y226700I-1365J787D01*
G01X454353Y222876D02*
G02X454378Y225159I2040J1119D01*
G01Y222834D02*
X454353Y222876D01*
G01X454397Y222800D02*
X454378Y222834D01*
G01Y221259D02*
G03X454397Y222800I-1365J787D01*
G01X454353Y218976D02*
G02X454378Y221259I2040J1119D01*
G01Y218934D02*
X454353Y218976D01*
G01X454397Y218900D02*
X454378Y218934D01*
G01X476742Y234122D02*
G02X478687Y232959I-70J-2325D01*
G01X476601Y234122D02*
X476742D01*
G01X475307Y234909D02*
G03X476601Y234122I1365J787D01*
G01X474969Y235479D02*
X475307Y234909D01*
G01X474892Y238435D02*
X474969Y235479D01*
G01X473292Y241547D02*
X474892Y238435D01*
G01X425915Y220472D02*
X426044D01*
G01X424609Y222834D02*
G03X425915Y220472I1364J-788D01*
G01X424609Y225160D02*
G02Y222834I-2015J-1163D01*
G01X424544Y225273D02*
X424609Y225160D01*
G01X422594Y227897D02*
X424544Y225273D01*
G01X422594Y227896D02*
Y227897D01*
G01X444956Y238551D02*
X446253Y241547D01*
G01X444869Y238400D02*
X444956Y238551D01*
G01X446194Y236072D02*
G02X444869Y238400I59J1575D01*
G01X446304Y236072D02*
X446194D01*
G01X447552Y234647D02*
G03X446304Y236072I-4241J-2455D01*
G01X447618Y234533D02*
X447552Y234647D01*
G01X447618Y232959D02*
G03Y234533I-1365J787D01*
G01X447333Y232598D02*
G03X447618Y232959I-1081J1147D01*
G01X447097Y232415D02*
G03X447333Y232598I-843J1331D01*
G01X445741Y231337D02*
G02X447097Y232415I5692J-5768D01*
G01X444888Y229059D02*
G02X445741Y231337I1365J788D01*
G01X444954Y228946D02*
X444888Y229059D01*
G01X445099Y228573D02*
G03X444954Y228946I-2551J-777D01*
G01X444913Y226776D02*
G03X445099Y228573I-2040J1119D01*
G01X444888Y226734D02*
X444913Y226776D01*
G01X444869Y226700D02*
X444888Y226734D01*
G01Y225159D02*
G02X444869Y226700I1365J787D01*
G01X444913Y222876D02*
G03X444888Y225159I-2040J1119D01*
G01Y222834D02*
X444913Y222876D01*
G01X444869Y222800D02*
X444888Y222834D01*
G01Y221259D02*
G02X444869Y222800I1365J787D01*
G01X444913Y218976D02*
G03X444888Y221259I-2040J1119D01*
G01Y218934D02*
X444913Y218976D01*
G01X444869Y218900D02*
X444888Y218934D01*
G01X431404Y218994D02*
X431369Y218934D01*
G01X429452Y222421D02*
G02X431404Y218994I-98J-2325D01*
G01X429310Y222421D02*
X429452D01*
G01X427989Y223209D02*
G03X429310Y222421I1365J787D01*
G01X426231Y224359D02*
G02X427989Y223209I-257J-2312D01*
G01X425974Y224616D02*
X426231Y224359D01*
G01X425974Y225947D02*
Y224616D01*
G01X425889Y219722D02*
X426018D01*
G01X423959Y220884D02*
G03X425889Y219722I2015J1163D01*
G01X422822Y221655D02*
G02X423959Y220884I-228J-1560D01*
G01X422594Y221427D02*
X422822Y221655D01*
G01X422594Y220096D02*
Y221427D01*
G01X467898Y218934D02*
X467917Y218900D01*
G01X467873Y218976D02*
X467898Y218934D01*
G01Y221259D02*
G03X467873Y218976I2015J-1164D01*
G01X466577Y223622D02*
G02X467898Y221259I-44J-1575D01*
G01X466448Y223622D02*
X466577D01*
G01X464518Y224784D02*
G03X466448Y223622I2015J1163D01*
G01X463212Y225571D02*
G02X464518Y224784I-59J-1575D01*
G01X463083Y225571D02*
X463212D01*
G01X461138Y229059D02*
G03X463083Y225571I2015J-1163D01*
G01X461138Y230634D02*
G02Y229059I-1363J-787D01*
G01X461113Y232917D02*
G03X461138Y230634I2040J-1119D01*
G01Y232959D02*
X461113Y232917D01*
G01X461204Y233075D02*
X461138Y232959D01*
G01X463153Y235696D02*
X461204Y233075D01*
G01X468548Y219309D02*
X468573Y219267D01*
G01X468529Y219343D02*
X468548Y219309D01*
G01Y220884D02*
G03X468529Y219343I1365J-787D01*
G01X466603Y224372D02*
G02X468548Y220884I-70J-2325D01*
G01X466474Y224372D02*
X466603D01*
G01X465168Y225159D02*
G03X466474Y224372I1365J788D01*
G01X463238Y226321D02*
G02X465168Y225159I-85J-2325D01*
G01X463109Y226321D02*
X463238D01*
G01X461788Y228684D02*
G03X463109Y226321I1365J-788D01*
G01X461854Y228798D02*
X461788Y228684D01*
G01Y231010D02*
G02X461854Y228798I-2025J-1167D01*
G01X463082Y233371D02*
G03X461788Y231010I71J-1574D01*
G01X464784Y235152D02*
G02X463082Y233371I-1783J0D01*
G01X464784Y235490D02*
Y235152D01*
G01X464518Y236484D02*
G02X464784Y235490I-1725J-994D01*
G01X464452Y236597D02*
X464518Y236484D01*
G01X463153Y239596D02*
X464452Y236597D01*
G01X444172D02*
X442873Y239596D01*
G01X444238Y236484D02*
X444172Y236597D01*
G01X443952Y234314D02*
G03X444238Y236484I-1272J1271D01*
G01X443884Y234246D02*
X443952Y234314D01*
G01X443184Y233956D02*
G03X443884Y234246I0J990D01*
G01X442117Y233420D02*
G02X443184Y233956I1067J-794D01*
G01X441554Y232664D02*
X442117Y233420D01*
G01X441508Y232584D02*
X441554Y232664D01*
G01X441508Y231010D02*
G02Y232584I1365J787D01*
G01Y228684D02*
G03Y231010I-2015J1163D01*
G01X441489Y227143D02*
G02X441508Y228684I1384J754D01*
G01Y227109D02*
X441489Y227143D01*
G01X441533Y227067D02*
X441508Y227109D01*
G01Y224784D02*
G03X441533Y227067I-2015J1164D01*
G01X441489Y223243D02*
G02X441508Y224784I1384J754D01*
G01Y223209D02*
X441489Y223243D01*
G01X441533Y223167D02*
X441508Y223209D01*
G01Y220884D02*
G03X441533Y223167I-2015J1164D01*
G01X441489Y219343D02*
G02X441508Y220884I1384J754D01*
G01Y219309D02*
X441489Y219343D01*
G01X441533Y219267D02*
X441508Y219309D01*
G01X457758D02*
X457733Y219267D01*
G01X457777Y219343D02*
X457758Y219309D01*
G01Y220884D02*
G02X457777Y219343I-1365J-787D01*
G01X457733Y223167D02*
G03X457758Y220884I2040J-1119D01*
G01Y223209D02*
X457733Y223167D01*
G01X457777Y223243D02*
X457758Y223209D01*
G01Y224784D02*
G02X457777Y223243I-1365J-787D01*
G01X457733Y227067D02*
G03X457758Y224784I2040J-1119D01*
G01Y227109D02*
X457733Y227067D01*
G01X457777Y227143D02*
X457758Y227109D01*
G01Y228684D02*
G02X457777Y227143I-1365J-787D01*
G01X457758Y231010D02*
G03Y228684I2015J-1163D01*
G01Y232584D02*
G02Y231010I-1365J-787D01*
G01X457691Y232699D02*
X457758Y232584D01*
G01X456393Y235696D02*
X457691Y232699D01*
G01X478037Y232584D02*
G03X479982Y231421I2015J1162D01*
G01X476743Y233371D02*
G02X478037Y232584I-71J-1574D01*
G01X476587Y233371D02*
X476743D01*
G01X475421Y233363D02*
X476587Y233371D01*
G01X473292Y233746D02*
X475421Y233363D01*
G01X471277Y219309D02*
X471242Y219249D01*
G01X471277Y220883D02*
G02Y219309I-1364J-787D01*
G01X471242Y223149D02*
G03X471277Y220883I2050J-1102D01*
G01Y223209D02*
X471242Y223149D01*
G01X469913Y225571D02*
G02X471277Y223209I0J-1575D01*
G01X469843Y225571D02*
X469913D01*
G01X467898Y226734D02*
G03X469843Y225571I2015J1162D01*
G01X466577Y227522D02*
G02X467898Y226734I-44J-1575D01*
G01X466448Y227522D02*
X466577D01*
G01X464518Y231010D02*
G03X466448Y227522I2015J-1163D01*
G01X464583Y231124D02*
X464518Y231010D01*
G01X466533Y233746D02*
X464583Y231124D01*
G01X474413Y339421D02*
X474267D01*
G01X475764Y340186D02*
G02X474413Y339421I-1351J810D01*
G01X475777Y340209D02*
X475764Y340186D01*
G01X479807Y340209D02*
G03X475777I-2015J-1162D01*
G01X436020Y394718D02*
Y404698D01*
G01X435869Y394434D02*
X436020Y394718D01*
G01X433924Y393271D02*
G03X435869Y394434I-70J2325D01*
G01X433795Y393271D02*
X433924D01*
G01X432489Y392484D02*
G02X433795Y393271I1365J-788D01*
G01X431099Y391406D02*
G03X432489Y392484I-622J2237D01*
G01X430758Y391191D02*
X431099Y391406D01*
G01X430474Y390907D02*
X430758Y391191D01*
G01X430474Y389747D02*
Y390907D01*
G01X473224Y378832D02*
X474413Y376096D01*
G01X473049Y379209D02*
G02X473224Y378832I-2014J-1164D01*
G01X473049Y380783D02*
G03Y379209I1365J-787D01*
G01Y383109D02*
G02Y380783I-2015J-1163D01*
G01Y384683D02*
G03Y383109I1365J-787D01*
G01Y387009D02*
G02Y384683I-2015J-1163D01*
G01Y388583D02*
G03Y387009I1365J-787D01*
G01Y390909D02*
G02Y388583I-2015J-1163D01*
G01X473029Y390943D02*
X473049Y390909D01*
G01X473048Y392484D02*
G03X473029Y390943I1365J-787D01*
G01X473073Y394767D02*
G02X473048Y392484I-2040J-1119D01*
G01Y394809D02*
X473073Y394767D01*
G01X473029Y394843D02*
X473048Y394809D01*
G01Y396384D02*
G03X473029Y394843I1365J-787D01*
G01X473073Y398667D02*
G02X473048Y396384I-2040J-1119D01*
G01Y398709D02*
X473073Y398667D01*
G01X473029Y398743D02*
X473048Y398709D01*
G01Y400284D02*
G03X473029Y398743I1365J-787D01*
G01X473073Y402567D02*
G02X473048Y400284I-2040J-1119D01*
G01Y402609D02*
X473073Y402567D01*
G01X473029Y402643D02*
X473048Y402609D01*
G01X474354Y404971D02*
G03X473029Y402643I59J-1575D01*
G01X465638Y402233D02*
G02Y404559I2015J1163D01*
G01X465657Y400692D02*
G03X465638Y402233I-1384J754D01*
G01Y400658D02*
X465657Y400692D01*
G01X465603Y400598D02*
X465638Y400658D01*
G01Y398332D02*
G02X465603Y400598I2015J1164D01*
G01X465665Y396806D02*
G03X465638Y398332I-1392J739D01*
G01Y396758D02*
X465665Y396806D01*
G01X465613Y396716D02*
X465638Y396758D01*
G01Y394433D02*
G02X465613Y396716I2015J1164D01*
G01X465657Y392892D02*
G03X465638Y394433I-1384J754D01*
G01Y392861D02*
G02X465657Y392892I597J-344D01*
G01X465638Y390535D02*
G02Y392861I2015J1163D01*
G01Y388961D02*
G03Y390535I-1365J787D01*
G01Y386635D02*
G02Y388961I2015J1163D01*
G01Y385061D02*
G03Y386635I-1365J787D01*
G01Y382735D02*
G02Y385061I2015J1163D01*
G01Y381161D02*
G03Y382735I-1365J787D01*
G01Y378835D02*
G02Y381161I2015J1163D01*
G01Y377261D02*
G03Y378835I-1365J787D01*
G01X463703Y375617D02*
G03X465638Y377261I-1400J3609D01*
G01X462833Y373509D02*
G02X463703Y375617I1440J639D01*
G01X464273Y370247D02*
X462833Y373509D01*
G01X476897Y360873D02*
X478445D01*
G01X475699Y362071D02*
X476897Y360873D01*
G01X473651Y362071D02*
X475699D01*
G01X472270Y360690D02*
X473651Y362071D01*
G01X470074Y360690D02*
X472270D01*
G01X468306Y358922D02*
X470074Y360690D01*
G01X467000Y358922D02*
X468306D01*
G01X465222Y360700D02*
X467000Y358922D01*
G01X463324Y360700D02*
X465222D01*
G01X461546Y358922D02*
X463324Y360700D01*
G01X460128Y358922D02*
X461546D01*
G01X458928Y360122D02*
X460128Y358922D01*
G01X455986Y360122D02*
X458928D01*
G01X454786Y358922D02*
X455986Y360122D01*
G01X453298Y358922D02*
X454786D01*
G01X451630Y360590D02*
X453298Y358922D01*
G01X449694Y360590D02*
X451630D01*
G01X448026Y358922D02*
X449694Y360590D01*
G01X446720Y358922D02*
X448026D01*
G01X445402Y360240D02*
X446720Y358922D01*
G01X442584Y360240D02*
X445402D01*
G01X441266Y358922D02*
X442584Y360240D01*
G01X439960Y358922D02*
X441266D01*
G01X438702Y360180D02*
X439960Y358922D01*
G01X435765Y360180D02*
X438702D01*
G01X434507Y358922D02*
X435765Y360180D01*
G01X433068Y358922D02*
X434507D01*
G01X431590Y360400D02*
X433068Y358922D01*
G01X430270Y360400D02*
X431590D01*
G01X428600Y362070D02*
X430270Y360400D01*
G01X426087Y362070D02*
X428600D01*
G01X425508Y361491D02*
X426087Y362070D01*
G01X424678Y360661D02*
X425008Y360991D01*
G01X476964Y364092D02*
X478384D01*
G01X475693Y362821D02*
X476964Y364092D01*
G01X473209Y362821D02*
X475693D01*
G01X471994Y364036D02*
X473209Y362821D01*
G01X470090Y364036D02*
X471994D01*
G01X468676Y362622D02*
X470090Y364036D01*
G01X466941Y362622D02*
X468676D01*
G01X465443Y364120D02*
X466941Y362622D01*
G01X463287Y364120D02*
X465443D01*
G01X461887Y362720D02*
X463287Y364120D01*
G01X460472Y362720D02*
X461887D01*
G01X458624Y360872D02*
X460472Y362720D01*
G01X456415Y360872D02*
X458624D01*
G01X454497Y362790D02*
X456415Y360872D01*
G01X453083Y362790D02*
X454497D01*
G01X451837Y364036D02*
X453083Y362790D01*
G01X449165Y364036D02*
X451837D01*
G01X448738Y363609D02*
X449165Y364036D01*
G01X446008Y363609D02*
G03X448738I1365J787D01*
G01X444063Y364772D02*
G02X446008Y363609I-70J-2325D01*
G01X443923Y364772D02*
X444063D01*
G01X441978Y363609D02*
G02X443923Y364772I2015J-1162D01*
G01X439248Y363609D02*
G03X441978I1365J787D01*
G01X437303Y364772D02*
G02X439248Y363609I-70J-2325D01*
G01X437163Y364772D02*
X437303D01*
G01X435218Y363609D02*
G02X437163Y364772I2015J-1162D01*
G01X435205Y363586D02*
X435218Y363609D01*
G01X432489D02*
G03X435205Y363586I1365J787D01*
G01X430544Y364772D02*
G02X432489Y363609I-70J-2325D01*
G01X430404Y364772D02*
X430544D01*
G01X428459Y363609D02*
G02X430404Y364772I2015J-1162D01*
G01X427138Y362821D02*
G03X428459Y363609I-44J1575D01*
G01X425878Y362821D02*
X427138D01*
G01X424599Y364100D02*
X425878Y362821D01*
G01X453015Y378590D02*
X454133Y376096D01*
G01X452768Y379211D02*
G02X453015Y378590I-2016J-1161D01*
G01X452768Y380785D02*
G03Y379211I1365J-787D01*
G01Y383111D02*
G02Y380785I-2015J-1163D01*
G01Y384685D02*
G03Y383111I1365J-787D01*
G01Y387011D02*
G02Y384685I-2015J-1163D01*
G01Y388585D02*
G03Y387011I1365J-787D01*
G01Y390911D02*
G02Y388585I-2015J-1163D01*
G01Y392485D02*
G03Y390911I1365J-787D01*
G01X452884Y392713D02*
G02X452768Y392485I-2233J993D01*
G01X452793Y394767D02*
G02X452884Y392713I-2040J-1119D01*
G01X452768Y394809D02*
X452793Y394767D01*
G01X452749Y394843D02*
X452768Y394809D01*
G01Y396384D02*
G03X452749Y394843I1365J-787D01*
G01X452793Y398667D02*
G02X452768Y396384I-2040J-1119D01*
G01Y398709D02*
X452793Y398667D01*
G01X452749Y398743D02*
X452768Y398709D01*
G01Y400284D02*
G03X452749Y398743I1365J-787D01*
G01X452793Y402567D02*
G02X452768Y400284I-2040J-1119D01*
G01Y402609D02*
X452793Y402567D01*
G01X452749Y402643D02*
X452768Y402609D01*
G01Y404184D02*
G03X452749Y402643I1365J-787D01*
G01X462415Y378144D02*
X460893Y376096D01*
G01X462842Y378718D02*
X462415Y378144D01*
G01X462908Y378834D02*
X462842Y378718D01*
G01X462933Y378876D02*
X462908Y378834D01*
G01Y381159D02*
G02X462933Y378876I-2015J-1164D01*
G01X462889Y382700D02*
G03X462908Y381159I1384J-754D01*
G01Y382734D02*
X462889Y382700D01*
G01X462933Y382776D02*
X462908Y382734D01*
G01Y385059D02*
G02X462933Y382776I-2015J-1164D01*
G01X462889Y386600D02*
G03X462908Y385059I1384J-754D01*
G01Y386634D02*
X462889Y386600D01*
G01X462933Y386676D02*
X462908Y386634D01*
G01Y388959D02*
G02X462933Y386676I-2015J-1164D01*
G01X462889Y390500D02*
G03X462908Y388959I1384J-754D01*
G01Y390534D02*
X462889Y390500D01*
G01X462933Y390576D02*
X462908Y390534D01*
G01Y392859D02*
G02X462933Y390576I-2015J-1164D01*
G01X462889Y394400D02*
G03X462908Y392859I1384J-754D01*
G01Y394432D02*
G03X462889Y394400I423J-273D01*
G01X462933Y396715D02*
G02X462908Y394432I-2040J-1119D01*
G01Y396757D02*
X462933Y396715D01*
G01X462889Y396791D02*
X462908Y396757D01*
G01Y398332D02*
G03X462889Y396791I1365J-787D01*
G01X462908Y400658D02*
G02Y398332I-2015J-1163D01*
G01Y402232D02*
G03Y400658I1365J-787D01*
G01X462933Y402274D02*
X462908Y402232D01*
G01Y404559D02*
G02X462933Y402274I-2015J-1165D01*
G01X422139Y393970D02*
Y403026D01*
G01X422462Y393647D02*
X422139Y393970D01*
G01X423714Y393647D02*
X422462D01*
G01X421389Y390160D02*
Y403334D01*
G01X421802Y389747D02*
X421389Y390160D01*
G01X423714Y389747D02*
X421802D01*
G01X472977Y372842D02*
G03X472916Y374037I-1197J538D01*
G01X473049Y371409D02*
G02X472977Y372842I1365J787D01*
G01X473234Y371003D02*
G03X473049Y371409I-2200J-757D01*
G01X474413Y368296D02*
X473234Y371003D01*
G01X472399Y374933D02*
X472916Y374037D01*
G01X472373Y402276D02*
G02X474328Y405721I2040J1120D01*
G01X472398Y402234D02*
X472373Y402276D01*
G01X472417Y402200D02*
X472398Y402234D01*
G01Y400659D02*
G03X472417Y402200I-1365J787D01*
G01X472373Y398376D02*
G02X472398Y400659I2040J1119D01*
G01Y398334D02*
X472373Y398376D01*
G01X472417Y398300D02*
X472398Y398334D01*
G01Y396759D02*
G03X472417Y398300I-1365J787D01*
G01X472373Y394476D02*
G02X472398Y396759I2040J1119D01*
G01Y394434D02*
X472373Y394476D01*
G01X472417Y394400D02*
X472398Y394434D01*
G01Y392859D02*
G03X472417Y394400I-1365J787D01*
G01X472373Y390576D02*
G02X472398Y392859I2040J1119D01*
G01X472399Y390533D02*
G03X472373Y390576I-1045J-603D01*
G01X472399Y388959D02*
G03Y390533I-1365J787D01*
G01Y386633D02*
G02Y388959I2015J1163D01*
G01Y385059D02*
G03Y386633I-1365J787D01*
G01Y382733D02*
G02Y385059I2015J1163D01*
G01Y381159D02*
G03Y382733I-1365J787D01*
G01Y378833D02*
G02Y381159I2015J1163D01*
G01Y377259D02*
G03Y378833I-1365J787D01*
G01Y374933D02*
G02Y377259I2015J1163D01*
G01X435272Y394911D02*
Y405008D01*
G01X435205Y394786D02*
X435272Y394911D01*
G01X433854Y394021D02*
G03X435205Y394786I0J1575D01*
G01X433769Y394021D02*
X433854D01*
G01X431839Y392859D02*
G02X433769Y394021I2015J-1163D01*
G01X430894Y392128D02*
G03X431839Y392859I-420J1519D01*
G01X430266Y391762D02*
G02X430894Y392128I1008J-1007D01*
G01X429438Y390934D02*
X430266Y391762D01*
G01X429109Y388959D02*
G02X429438Y390934I1365J788D01*
G01X429134Y386676D02*
G03X429109Y388959I-2040J1119D01*
G01Y386634D02*
X429134Y386676D01*
G01X429090Y386600D02*
X429109Y386634D01*
G01Y385059D02*
G02X429090Y386600I1365J787D01*
G01X429175Y384946D02*
X429109Y385059D01*
G01X430474Y381947D02*
X429175Y384946D01*
G01X462277Y402642D02*
G03X462258Y404183I-1384J754D01*
G01Y402608D02*
X462277Y402642D01*
G01X462258Y400282D02*
G02Y402608I2015J1163D01*
G01X462277Y400248D02*
X462258Y400282D01*
G01Y398707D02*
G03X462277Y400248I-1365J787D01*
G01X462233Y396424D02*
G02X462258Y398707I2040J1119D01*
G01Y396382D02*
X462233Y396424D01*
G01X462258Y394808D02*
G03Y396382I-1365J787D01*
G01X462145Y394587D02*
G02X462258Y394808I2249J-1011D01*
G01Y392484D02*
G02X462145Y394587I2015J1163D01*
G01X462277Y390943D02*
G03X462258Y392484I-1384J754D01*
G01Y390909D02*
X462277Y390943D01*
G01X462258Y388585D02*
G02Y390909I2015J1162D01*
G01Y387011D02*
G03Y388585I-1365J787D01*
G01Y384685D02*
G02Y387011I2015J1163D01*
G01Y383111D02*
G03Y384685I-1365J787D01*
G01Y380785D02*
G02Y383111I2015J1163D01*
G01Y379211D02*
G03Y380785I-1364J787D01*
G01X462018Y378880D02*
G03X462258Y379211I-1465J1315D01*
G01X460818Y378280D02*
G03X462018Y378880I-161J1821D01*
G01X460368Y378130D02*
G02X460818Y378280I540J-871D01*
G01X459918Y377530D02*
G02X460368Y378130I993J-276D01*
G01X459528Y376884D02*
G02X459918Y377530I16228J-9356D01*
G01X459509Y375343D02*
G02X459528Y376884I1384J754D01*
G01Y375309D02*
X459509Y375343D01*
G01X459553Y373026D02*
G03X459528Y375309I-2040J1119D01*
G01Y372984D02*
X459553Y373026D01*
G01X459528Y371410D02*
G02Y372984I1365J787D01*
G01X459594Y371296D02*
X459528Y371410D01*
G01X460893Y368296D02*
X459594Y371296D01*
G01X469904Y376689D02*
X471033Y374146D01*
G01X469669Y377259D02*
G02X469904Y376689I-2015J-1164D01*
G01X469669Y378833D02*
G03Y377259I1365J-787D01*
G01Y381159D02*
G02Y378833I-2015J-1163D01*
G01Y382733D02*
G03Y381159I1365J-787D01*
G01Y385059D02*
G02Y382733I-2015J-1163D01*
G01Y386633D02*
G03Y385059I1365J-787D01*
G01Y388959D02*
G02Y386633I-2015J-1163D01*
G01Y390533D02*
G03Y388959I1365J-787D01*
G01X469693Y390576D02*
G02X469669Y390533I-1555J840D01*
G01X469668Y392859D02*
G02X469693Y390576I-2015J-1164D01*
G01X469649Y394400D02*
G03X469668Y392859I1384J-754D01*
G01Y394434D02*
X469649Y394400D01*
G01X469693Y394476D02*
X469668Y394434D01*
G01Y396759D02*
G02X469693Y394476I-2015J-1164D01*
G01X469649Y398300D02*
G03X469668Y396759I1384J-754D01*
G01Y398334D02*
X469649Y398300D01*
G01X469693Y398376D02*
X469668Y398334D01*
G01Y400659D02*
G02X469693Y398376I-2015J-1164D01*
G01X469649Y402200D02*
G03X469668Y400659I1384J-754D01*
G01Y402234D02*
X469649Y402200D01*
G01X469693Y402276D02*
X469668Y402234D01*
G01Y404559D02*
G02X469693Y402276I-2015J-1164D01*
G01X449413D02*
G03X449388Y404559I-2040J1119D01*
G01Y402234D02*
X449413Y402276D01*
G01X449369Y402200D02*
X449388Y402234D01*
G01Y400659D02*
G02X449369Y402200I1365J787D01*
G01X449413Y398376D02*
G03X449388Y400659I-2040J1119D01*
G01Y398334D02*
X449413Y398376D01*
G01X449369Y398300D02*
X449388Y398334D01*
G01Y396759D02*
G02X449369Y398300I1365J787D01*
G01X449413Y394476D02*
G03X449388Y396759I-2040J1119D01*
G01Y394434D02*
X449413Y394476D01*
G01X449369Y394400D02*
X449388Y394434D01*
G01Y392859D02*
G02X449369Y394400I1365J787D01*
G01X449413Y390576D02*
G03X449388Y392859I-2040J1119D01*
G01Y390535D02*
G02X449413Y390576I847J-488D01*
G01X449388Y388961D02*
G02Y390535I1365J787D01*
G01Y386635D02*
G03Y388961I-2015J1163D01*
G01Y385061D02*
G02Y386635I1365J787D01*
G01Y382735D02*
G03Y385061I-2015J1163D01*
G01Y381161D02*
G02Y382735I1365J787D01*
G01Y378835D02*
G03Y381161I-2015J1163D01*
G01Y377261D02*
G02Y378835I1365J787D01*
G01X449636Y376639D02*
G03X449388Y377261I-2263J-542D01*
G01X450753Y374146D02*
X449636Y376639D01*
G01X434885Y389604D02*
G03X433854Y387796I1069J-1808D01*
G01X435038Y389694D02*
X434885Y389604D01*
G01X439038Y395169D02*
Y403447D01*
G01X439273Y394767D02*
X439038Y395169D01*
G01X437318Y391322D02*
G03X439273Y394767I-85J2325D01*
G01X437233Y391322D02*
X437318D01*
G01X435882Y390557D02*
G02X437233Y391322I1351J-810D01*
G01X435869Y390534D02*
X435882Y390557D01*
G01X435038Y389694D02*
G03X435869Y390534I-1184J2002D01*
G01X438290Y396543D02*
Y403757D01*
G01X438288Y396541D02*
X438290Y396543D01*
G01X438288Y394968D02*
Y396541D01*
G01X438625Y394385D02*
X438288Y394968D01*
G01X437292Y392072D02*
G03X438625Y394385I-59J1575D01*
G01X437163Y392072D02*
X437292D01*
G01X435218Y390909D02*
G02X437163Y392072I2015J-1162D01*
G01X435205Y390886D02*
X435218Y390909D01*
G01X434255Y390173D02*
G03X435205Y390886I-401J1524D01*
G01X434074Y390069D02*
G02X434255Y390173I283J-283D01*
G01X433261Y389256D02*
X434074Y390069D01*
G01X432390Y387215D02*
G02X433261Y389256I1463J582D01*
G01X432514Y386967D02*
G02X432390Y387215I1375J842D01*
G01X432708Y385194D02*
G03X432514Y386967I-2222J654D01*
G01X433679Y383896D02*
G02X432708Y385194I0J1012D01*
G01X433854Y383896D02*
X433679D01*
G01X418539Y388370D02*
Y404512D01*
G01X421391Y385518D02*
X418539Y388370D01*
G01X421391Y378594D02*
Y385518D01*
G01X421938Y378047D02*
X421391Y378594D01*
G01X423714Y378047D02*
X421938D01*
G01X476943Y360123D02*
X479318D01*
G01X475380Y358560D02*
X476943Y360123D01*
G01X473390Y358560D02*
X475380D01*
G01X471670Y356840D02*
X473390Y358560D01*
G01X470296Y356840D02*
X471670D01*
G01X468328Y354872D02*
X470296Y356840D01*
G01X466486Y354872D02*
X468328D01*
G01X464826Y356532D02*
X466486Y354872D01*
G01X463451Y356532D02*
X464826D01*
G01X461600Y354681D02*
X463451Y356532D01*
G01X460228Y354681D02*
X461600D01*
G01X458456Y356453D02*
X460228Y354681D01*
G01X456333Y356453D02*
X458456D01*
G01X454787Y354907D02*
X456333Y356453D01*
G01X453275Y354907D02*
X454787D01*
G01X451615Y356567D02*
X453275Y354907D01*
G01X449806Y356567D02*
X451615D01*
G01X448041Y354802D02*
X449806Y356567D01*
G01X446391Y354802D02*
X448041D01*
G01X444549Y356644D02*
X446391Y354802D01*
G01X443090Y356644D02*
X444549D01*
G01X441457Y355011D02*
X443090Y356644D01*
G01X439594Y355011D02*
X441457D01*
G01X437895Y356710D02*
X439594Y355011D01*
G01X436300Y356710D02*
X437895D01*
G01X434497Y354907D02*
X436300Y356710D01*
G01X432571Y354907D02*
X434497D01*
G01X430658Y356820D02*
X432571Y354907D01*
G01X429320Y356820D02*
X430658D01*
G01X427799Y358341D02*
X429320Y356820D01*
G01X426028Y358341D02*
X427799D01*
G01X425594Y357907D02*
X426028Y358341D01*
G01X448757Y402643D02*
G03X448738Y404184I-1384J754D01*
G01Y402609D02*
X448757Y402643D01*
G01X448713Y402567D02*
X448738Y402609D01*
G01Y400284D02*
G02X448713Y402567I2015J1164D01*
G01X448757Y398743D02*
G03X448738Y400284I-1384J754D01*
G01Y398709D02*
X448757Y398743D01*
G01X448713Y398667D02*
X448738Y398709D01*
G01Y396384D02*
G02X448713Y398667I2015J1164D01*
G01X448757Y394843D02*
G03X448738Y396384I-1384J754D01*
G01Y394809D02*
X448757Y394843D01*
G01X448713Y394767D02*
X448738Y394809D01*
G01Y392484D02*
G02X448713Y394767I2015J1164D01*
G01X448757Y390943D02*
G03X448738Y392484I-1384J754D01*
G01Y390911D02*
X448757Y390943D01*
G01X448738Y388585D02*
G02Y390911I2015J1163D01*
G01Y387011D02*
G03Y388585I-1365J787D01*
G01Y384685D02*
G02Y387011I2015J1163D01*
G01Y383111D02*
G03Y384685I-1365J787D01*
G01Y380785D02*
G02Y383111I2015J1163D01*
G01Y379211D02*
G03Y380785I-1365J787D01*
G01Y376885D02*
G02Y379211I2015J1163D01*
G01Y375311D02*
G03Y376885I-1365J787D01*
G01X449180Y372433D02*
G02X448738Y375311I1573J1715D01*
G01X450753Y370247D02*
X449180Y372433D01*
G01X466288Y402608D02*
G02Y404184I1365J788D01*
G01X466313Y400325D02*
G03X466288Y402608I-2040J1119D01*
G01Y400283D02*
X466313Y400325D01*
G01X466269Y400249D02*
X466288Y400283D01*
G01Y398708D02*
G02X466269Y400249I1365J787D01*
G01X466323Y396442D02*
G03X466288Y398708I-2050J1102D01*
G01X466261Y396334D02*
X466323Y396442D01*
G01X466288Y394808D02*
G02X466261Y396334I1365J787D01*
G01X466313Y392525D02*
G03X466288Y394808I-2040J1119D01*
G01Y392485D02*
G02X466313Y392525I574J-331D01*
G01X466288Y390911D02*
G02Y392485I1365J787D01*
G01Y388585D02*
G03Y390911I-2015J1163D01*
G01Y387011D02*
G02Y388585I1365J787D01*
G01Y384685D02*
G03Y387011I-2015J1163D01*
G01Y383111D02*
G02Y384685I1365J787D01*
G01Y380785D02*
G03Y383111I-2015J1163D01*
G01Y379211D02*
G02Y380785I1365J787D01*
G01Y376885D02*
G03Y379211I-2015J1163D01*
G01X464273Y374146D02*
G03X466288Y376885I-11302J10425D01*
G01X469037Y402643D02*
G03X469018Y404184I-1384J754D01*
G01Y402609D02*
X469037Y402643D01*
G01X468993Y402567D02*
X469018Y402609D01*
G01Y400284D02*
G02X468993Y402567I2015J1164D01*
G01X469037Y398743D02*
G03X469018Y400284I-1384J754D01*
G01Y398709D02*
X469037Y398743D01*
G01X468993Y398667D02*
X469018Y398709D01*
G01Y396384D02*
G02X468993Y398667I2015J1164D01*
G01X469037Y394843D02*
G03X469018Y396384I-1384J754D01*
G01Y394809D02*
X469037Y394843D01*
G01X468993Y394767D02*
X469018Y394809D01*
G01Y392484D02*
G02X468993Y394767I2015J1164D01*
G01X469037Y390943D02*
G03X469018Y392484I-1384J754D01*
G01X469019Y390909D02*
G03X469037Y390943I-456J263D01*
G01X469019Y388583D02*
G02Y390909I2015J1163D01*
G01Y387009D02*
G03Y388583I-1365J787D01*
G01Y384683D02*
G02Y387009I2015J1163D01*
G01Y383109D02*
G03Y384683I-1365J787D01*
G01Y380783D02*
G02Y383109I2015J1163D01*
G01Y379209D02*
G03Y380783I-1365J787D01*
G01Y376883D02*
G02Y379209I2015J1163D01*
G01Y375309D02*
G03Y376883I-1365J787D01*
G01X468894Y373234D02*
G02X469019Y375309I2140J912D01*
G01X471033Y370247D02*
X468894Y373234D01*
G01X419289Y389970D02*
Y404204D01*
G01X419290Y389969D02*
X419289Y389970D01*
G01X419290Y388677D02*
Y389969D01*
G01X422139Y385828D02*
X419290Y388677D01*
G01X422139Y382194D02*
Y385828D01*
G01X422386Y381947D02*
X422139Y382194D01*
G01X423714Y381947D02*
X422386D01*
G01X452118Y374935D02*
X452635Y374039D01*
G01X452118Y377261D02*
G03Y374935I2015J-1163D01*
G01Y378835D02*
G02Y377261I-1365J-787D01*
G01Y381161D02*
G03Y378835I2015J-1163D01*
G01Y382735D02*
G02Y381161I-1365J-787D01*
G01Y385061D02*
G03Y382735I2015J-1163D01*
G01Y386635D02*
G02Y385061I-1365J-787D01*
G01Y388961D02*
G03Y386635I2015J-1163D01*
G01Y390535D02*
G02Y388961I-1365J-787D01*
G01Y392861D02*
G03Y390535I2015J-1163D01*
G01X452194Y393009D02*
G02X452118Y392861I-1321J585D01*
G01X452137Y394400D02*
G02X452194Y393009I-1384J-753D01*
G01X452118Y394434D02*
X452137Y394400D01*
G01X452093Y394476D02*
X452118Y394434D01*
G01Y396759D02*
G03X452093Y394476I2015J-1164D01*
G01X452137Y398300D02*
G02X452118Y396759I-1384J-754D01*
G01Y398334D02*
X452137Y398300D01*
G01X452093Y398376D02*
X452118Y398334D01*
G01Y400659D02*
G03X452093Y398376I2015J-1164D01*
G01X452137Y402200D02*
G02X452118Y400659I-1384J-754D01*
G01Y402234D02*
X452137Y402200D01*
G01X452093Y402276D02*
X452118Y402234D01*
G01Y404559D02*
G03X452093Y402276I2015J-1164D01*
G01X452696Y372844D02*
G03X452635Y374039I-1197J538D01*
G01X452768Y371411D02*
G02X452696Y372844I1365J787D01*
G01X452995Y370869D02*
G03X452768Y371411I-2242J-621D01*
G01X454133Y368296D02*
X452995Y370869D01*
G01X438183Y410410D02*
X439308Y411535D01*
G01X438183Y406861D02*
Y410410D01*
G01X436020Y404698D02*
X438183Y406861D01*
G01X474483Y404971D02*
X474354D01*
G01X476428Y408460D02*
G02X474483Y404971I-2014J-1164D01*
G01X476428Y410034D02*
G03Y408460I1364J-787D01*
G01X476463Y410094D02*
X476428Y410034D01*
G01Y412360D02*
G02X476463Y410094I-2015J-1164D01*
G01X477792Y414722D02*
G03X476428Y412360I0J-1575D01*
G01X477877Y414722D02*
X477792D01*
G01X479807Y415884D02*
G02X477877Y414722I-2015J1163D01*
G01X472608Y421248D02*
X471732Y422124D01*
G01X472608Y420524D02*
Y421248D01*
G01X472398Y420159D02*
X472608Y420524D01*
G01X471092Y419372D02*
G03X472398Y420159I-59J1575D01*
G01X470963Y419372D02*
X471092D01*
G01X469018Y418209D02*
G02X470963Y419372I2015J-1162D01*
G01X468993Y418167D02*
X469018Y418209D01*
G01Y415884D02*
G02X468993Y418167I1858J1162D01*
G01X469037Y414343D02*
G03X469018Y415884I-1384J754D01*
G01Y414309D02*
X469037Y414343D01*
G01X468993Y414267D02*
X469018Y414309D01*
G01Y411984D02*
G02X468993Y414267I2015J1164D01*
G01X469037Y410443D02*
G03X469018Y411984I-1384J754D01*
G01Y410409D02*
X469037Y410443D01*
G01X467697Y409621D02*
G03X469018Y410409I-44J1575D01*
G01X467568Y409621D02*
X467697D01*
G01X465638Y408459D02*
G02X467568Y409621I2015J-1163D01*
G01X465613Y406176D02*
G02X465638Y408459I2040J1119D01*
G01Y406134D02*
X465613Y406176D01*
G01X465657Y406100D02*
X465638Y406134D01*
G01Y404559D02*
G03X465657Y406100I-1365J787D01*
G01X452793Y406467D02*
G02X452768Y404184I-2040J-1119D01*
G01Y406509D02*
X452793Y406467D01*
G01X452749Y406543D02*
X452768Y406509D01*
G01Y408084D02*
G03X452749Y406543I1365J-787D01*
G01X452793Y410367D02*
G02X452768Y408084I-2040J-1119D01*
G01Y410409D02*
X452793Y410367D01*
G01X452749Y410443D02*
X452768Y410409D01*
G01Y411984D02*
G03X452749Y410443I1365J-787D01*
G01X452793Y414267D02*
G02X452768Y411984I-2040J-1119D01*
G01Y414309D02*
X452793Y414267D01*
G01X452749Y414343D02*
X452768Y414309D01*
G01X454074Y416671D02*
G03X452749Y414343I59J-1575D01*
G01X454203Y416671D02*
X454074D01*
G01X456173Y417876D02*
G02X454203Y416671I-2039J1120D01*
G01X456148Y420159D02*
G02X456173Y417876I-2015J-1164D01*
G01X456148Y421640D02*
Y420159D01*
G01X456632Y422124D02*
X456148Y421640D01*
G01X466600Y418819D02*
Y417047D01*
G01X468248Y420467D02*
X466600Y418819D01*
G01X468248Y421140D02*
Y420467D01*
G01X469232Y422124D02*
X468248Y421140D01*
G01X462881Y406085D02*
G03X462908Y404559I1392J-739D01*
G01X462943Y406193D02*
X462881Y406085D01*
G01X462908Y408459D02*
G02X462943Y406193I-2015J-1164D01*
G01X464254Y410822D02*
G03X462908Y408459I19J-1576D01*
G01X464358Y410822D02*
X464254D01*
G01X466313Y414267D02*
G02X464358Y410822I-2040J-1120D01*
G01X466288Y414309D02*
X466313Y414267D01*
G01X466269Y414343D02*
X466288Y414309D01*
G01Y415884D02*
G03X466269Y414343I1365J-787D01*
G01X466600Y417047D02*
G02X466288Y415884I-2327J1D01*
G01X425859Y417672D02*
X426708Y418521D01*
G01X425859Y406746D02*
Y417672D01*
G01X422139Y403026D02*
X425859Y406746D01*
G01X425111Y417608D02*
X424208Y418511D01*
G01X425111Y407056D02*
Y417608D01*
G01X421389Y403334D02*
X425111Y407056D01*
G01X477851Y415472D02*
G03X479157Y416259I-59J1575D01*
G01X477722Y415472D02*
X477851D01*
G01X475777Y411983D02*
G02X477722Y415472I2015J1163D01*
G01X475777Y410409D02*
G03Y411983I-1364J787D01*
G01X475742Y410349D02*
X475777Y410409D01*
G01Y408083D02*
G02X475742Y410349I2015J1164D01*
G01X474413Y405721D02*
G03X475777Y408083I0J1575D01*
G01X474328Y405721D02*
X474413D01*
G01X437435Y410395D02*
X436808Y411022D01*
G01X437435Y407171D02*
Y410395D01*
G01X435272Y405008D02*
X437435Y407171D01*
G01X467498Y421358D02*
X466732Y422124D01*
G01X467498Y420791D02*
Y421358D01*
G01X465849Y419142D02*
X467498Y420791D01*
G01X465849Y417047D02*
Y419142D01*
G01X465638Y416259D02*
G03X465849Y417047I-1365J788D01*
G01X465613Y413976D02*
G02X465638Y416259I2040J1119D01*
G01Y413934D02*
X465613Y413976D01*
G01X465657Y413900D02*
X465638Y413934D01*
G01X464332Y411572D02*
G03X465657Y413900I-59J1575D01*
G01X464203Y411572D02*
X464332D01*
G01X462258Y408083D02*
G02X464203Y411572I2015J1163D01*
G01X462285Y406557D02*
G03X462258Y408083I-1392J739D01*
G01X462223Y406449D02*
X462285Y406557D01*
G01X462258Y404183D02*
G02X462223Y406449I2015J1164D01*
G01X470989Y406922D02*
G03X469668Y404559I44J-1575D01*
G01X471118Y406922D02*
X470989D01*
G01X473073Y410367D02*
G02X471118Y406922I-2040J-1120D01*
G01X473048Y410409D02*
X473073Y410367D01*
G01X473029Y410443D02*
X473048Y410409D01*
G01Y411984D02*
G03X473029Y410443I1365J-787D01*
G01X473073Y414267D02*
G02X473048Y411984I-2040J-1119D01*
G01Y414309D02*
X473073Y414267D01*
G01X473029Y414343D02*
X473048Y414309D01*
G01X474354Y416671D02*
G03X473029Y414343I59J-1575D01*
G01X474483Y416671D02*
X474354D01*
G01X476428Y417834D02*
G02X474483Y416671I-2015J1162D01*
G01X477744Y418621D02*
G03X476428Y417834I48J-1574D01*
G01X477792Y418621D02*
X477744D01*
G01X477890Y418620D02*
X477792Y418621D01*
G01X479808Y419783D02*
G02X477890Y418620I-2016J1161D01*
G01X450698Y421190D02*
X451632Y422124D01*
G01X450698Y418830D02*
Y421190D01*
G01X449177Y417309D02*
X450698Y418830D01*
G01X449177Y417046D02*
Y417309D01*
G01X449388Y416259D02*
G02X449177Y417046I1365J788D01*
G01X449413Y413976D02*
G03X449388Y416259I-2040J1119D01*
G01Y413934D02*
X449413Y413976D01*
G01X449369Y413900D02*
X449388Y413934D01*
G01Y412359D02*
G02X449369Y413900I1365J787D01*
G01X449413Y410076D02*
G03X449388Y412359I-2040J1119D01*
G01Y410034D02*
X449413Y410076D01*
G01X449369Y410000D02*
X449388Y410034D01*
G01Y408459D02*
G02X449369Y410000I1365J787D01*
G01X449413Y406176D02*
G03X449388Y408459I-2040J1119D01*
G01Y406134D02*
X449413Y406176D01*
G01X449369Y406100D02*
X449388Y406134D01*
G01Y404559D02*
G02X449369Y406100I1365J787D01*
G01X443301Y408664D02*
X444318Y409681D01*
G01X443301Y407710D02*
Y408664D01*
G01X439038Y403447D02*
X443301Y407710D01*
G01X441818Y409586D02*
Y410424D01*
G01X442553Y408851D02*
X441818Y409586D01*
G01X442553Y408020D02*
Y408851D01*
G01X438290Y403757D02*
X442553Y408020D01*
G01X420141Y416909D02*
X419208Y417842D01*
G01X420141Y406114D02*
Y416909D01*
G01X418539Y404512D02*
X420141Y406114D01*
G01X449948Y421308D02*
X449132Y422124D01*
G01X449948Y419141D02*
Y421308D01*
G01X448427Y417620D02*
X449948Y419141D01*
G01X448427Y417047D02*
Y417620D01*
G01X448738Y415884D02*
G02X448427Y417047I2015J1162D01*
G01X448757Y414343D02*
G03X448738Y415884I-1384J754D01*
G01Y414309D02*
X448757Y414343D01*
G01X448713Y414267D02*
X448738Y414309D01*
G01Y411984D02*
G02X448713Y414267I2015J1164D01*
G01X448757Y410443D02*
G03X448738Y411984I-1384J754D01*
G01Y410409D02*
X448757Y410443D01*
G01X448713Y410367D02*
X448738Y410409D01*
G01Y408084D02*
G02X448713Y410367I2015J1164D01*
G01X448757Y406543D02*
G03X448738Y408084I-1384J754D01*
G01Y406509D02*
X448757Y406543D01*
G01X448713Y406467D02*
X448738Y406509D01*
G01Y404184D02*
G02X448713Y406467I2015J1164D01*
G01X473358Y421250D02*
X474232Y422124D01*
G01X473358Y420320D02*
Y421250D01*
G01X473048Y419784D02*
X473358Y420320D01*
G01X471118Y418622D02*
G03X473048Y419784I-85J2325D01*
G01X470989Y418622D02*
X471118D01*
G01X469668Y417834D02*
G02X470989Y418622I1365J-787D01*
G01X469649Y417800D02*
X469668Y417834D01*
G01Y416259D02*
G02X469649Y417800I1330J787D01*
G01X469693Y413976D02*
G03X469668Y416259I-2040J1119D01*
G01Y413934D02*
X469693Y413976D01*
G01X469649Y413900D02*
X469668Y413934D01*
G01Y412359D02*
G02X469649Y413900I1365J787D01*
G01X469693Y410076D02*
G03X469668Y412359I-2040J1119D01*
G01Y410034D02*
X469693Y410076D01*
G01X467723Y408871D02*
G03X469668Y410034I-70J2325D01*
G01X467594Y408871D02*
X467723D01*
G01X466288Y408084D02*
G02X467594Y408871I1365J-788D01*
G01X466269Y406543D02*
G02X466288Y408084I1384J754D01*
G01Y406509D02*
X466269Y406543D01*
G01X466313Y406467D02*
X466288Y406509D01*
G01Y404184D02*
G03X466313Y406467I-2015J1164D01*
G01X477841Y419371D02*
G03X479157Y420158I-48J1574D01*
G01X477793Y419371D02*
X477841D01*
G01X477695Y419372D02*
X477793Y419371D01*
G01X475777Y418209D02*
G02X477695Y419372I2016J-1161D01*
G01X475764Y418186D02*
X475777Y418209D01*
G01X474413Y417421D02*
G03X475764Y418186I0J1575D01*
G01X474328Y417421D02*
X474413D01*
G01X472373Y413976D02*
G02X474328Y417421I2040J1120D01*
G01X472398Y413934D02*
X472373Y413976D01*
G01X472417Y413900D02*
X472398Y413934D01*
G01Y412359D02*
G03X472417Y413900I-1365J787D01*
G01X472373Y410076D02*
G02X472398Y412359I2040J1119D01*
G01Y410034D02*
X472373Y410076D01*
G01X472417Y410000D02*
X472398Y410034D01*
G01X471092Y407672D02*
G03X472417Y410000I-59J1575D01*
G01X470963Y407672D02*
X471092D01*
G01X469018Y404184D02*
G02X470963Y407672I2015J1163D01*
G01X420891Y417264D02*
X421708Y418081D01*
G01X420891Y405806D02*
Y417264D01*
G01X419289Y404204D02*
X420891Y405806D01*
G01X452137Y406100D02*
G02X452118Y404559I-1384J-754D01*
G01Y406134D02*
X452137Y406100D01*
G01X452093Y406176D02*
X452118Y406134D01*
G01Y408459D02*
G03X452093Y406176I2015J-1164D01*
G01X452137Y410000D02*
G02X452118Y408459I-1384J-754D01*
G01Y410034D02*
X452137Y410000D01*
G01X452093Y410076D02*
X452118Y410034D01*
G01Y412359D02*
G03X452093Y410076I2015J-1164D01*
G01X452137Y413900D02*
G02X452118Y412359I-1384J-754D01*
G01Y413934D02*
X452137Y413900D01*
G01X452093Y413976D02*
X452118Y413934D01*
G01X454048Y417421D02*
G03X452093Y413976I85J-2325D01*
G01X454177Y417421D02*
X454048D01*
G01X455200Y419990D02*
G02X454177Y417421I-1065J-1064D01*
G01X455200Y421056D02*
Y419990D01*
G01X454242Y422014D02*
X455200Y421056D01*
G01X483737Y197065D02*
X483787D01*
G01X496182Y207450D02*
X498491D01*
G01X490960Y212672D02*
X496182Y207450D01*
G01X486753Y212672D02*
X490960D01*
G01X485428Y215000D02*
G03X486753Y212672I1384J-753D01*
G01X485447Y215034D02*
X485428Y215000D01*
G01X485472Y215076D02*
X485447Y215034D01*
G01Y217359D02*
G02X485472Y215076I-2015J-1164D01*
G01X485428Y218900D02*
G03X485447Y217359I1384J-754D01*
G01X497066Y206209D02*
X498410Y204865D01*
G01X496362Y206209D02*
X497066D01*
G01X490650Y211921D02*
X496362Y206209D01*
G01X486761Y211921D02*
X490650D01*
G01X484772Y215367D02*
G03X486761Y211921I2040J-1120D01*
G01X484797Y215409D02*
X484772Y215367D01*
G01X484816Y215443D02*
X484797Y215409D01*
G01Y216984D02*
G02X484816Y215443I-1365J-787D01*
G01X484772Y219267D02*
G03X484797Y216984I2040J-1119D01*
G01X493903Y205100D02*
X495508D01*
G01X490232Y208771D02*
X493903Y205100D01*
G01X486768Y208771D02*
X490232D01*
G01X485447Y209559D02*
G03X486768Y208771I1365J787D01*
G01X483517Y210721D02*
G02X485447Y209559I-85J-2325D01*
G01X483388Y210721D02*
X483517D01*
G01X482067Y213084D02*
G03X483388Y210721I1365J-788D01*
G01X482092Y215367D02*
G02X482067Y213084I-2040J-1119D01*
G01Y215409D02*
X482092Y215367D01*
G01X482048Y215443D02*
X482067Y215409D01*
G01Y216984D02*
G03X482048Y215443I1365J-787D01*
G01X482092Y219267D02*
G02X482067Y216984I-2040J-1119D01*
G01X479140Y196380D02*
X480885Y194635D01*
G01X489921Y208021D02*
X495527Y202415D01*
G01X486727Y208021D02*
X489921D01*
G01X484797Y209183D02*
G03X486727Y208021I2015J1163D01*
G01X483476Y209971D02*
G02X484797Y209183I-44J-1575D01*
G01X483347Y209971D02*
X483476D01*
G01X481417Y213459D02*
G03X483347Y209971I2015J-1163D01*
G01X481436Y215000D02*
G02X481417Y213459I-1384J-754D01*
G01Y215034D02*
X481436Y215000D01*
G01X481392Y215076D02*
X481417Y215034D01*
G01Y217359D02*
G03X481392Y215076I2015J-1164D01*
G01X481436Y218900D02*
G02X481417Y217359I-1384J-754D01*
G01X482292Y197448D02*
Y195894D01*
G01X521790Y256771D02*
X521593D01*
G01X523096Y255984D02*
G03X521790Y256771I-1365J-788D01*
G01X525026Y254822D02*
G02X523096Y255984I85J2325D01*
G01X525196Y254822D02*
X525026D01*
G01X527126Y255984D02*
G02X525196Y254822I-2015J1163D01*
G01X528432Y256771D02*
G03X527126Y255984I59J-1575D01*
G01X528550Y256771D02*
X528432D01*
G01X529856Y255984D02*
G03X528550Y256771I-1365J-788D01*
G01X531786Y254822D02*
G02X529856Y255984I85J2325D01*
G01X531956Y254822D02*
X531786D01*
G01X533886Y255984D02*
G02X531956Y254822I-2015J1163D01*
G01X536616Y255984D02*
G03X533886I-1365J-788D01*
G01X538630Y254821D02*
G02X536616Y255984I0J2325D01*
G01X538632Y254821D02*
X538630D01*
G01X540646Y255984D02*
G02X538632Y254821I-2014J1162D01*
G01X485447Y218934D02*
X485428Y218900D01*
G01X485472Y218976D02*
X485447Y218934D01*
G01Y221259D02*
G02X485472Y218976I-2015J-1164D01*
G01X485428Y222800D02*
G03X485447Y221259I1384J-754D01*
G01Y222834D02*
X485428Y222800D01*
G01X485472Y222876D02*
X485447Y222834D01*
G01Y225159D02*
G02X485472Y222876I-2015J-1164D01*
G01X485428Y226700D02*
G03X485447Y225159I1384J-754D01*
G01Y226734D02*
X485428Y226700D01*
G01X485472Y226776D02*
X485447Y226734D01*
G01Y229059D02*
G02X485472Y226776I-2015J-1164D01*
G01X485428Y230600D02*
G03X485447Y229059I1384J-754D01*
G01Y230634D02*
X485428Y230600D01*
G01X483502Y234122D02*
G02X485447Y230634I-70J-2325D01*
G01X483361Y234122D02*
X483502D01*
G01X482067Y234909D02*
G03X483361Y234122I1365J787D01*
G01X480103Y236072D02*
G02X482067Y234909I-51J-2326D01*
G01X479993Y236072D02*
X480103D01*
G01X478687Y236859D02*
G03X479993Y236072I1365J788D01*
G01X484797Y219309D02*
X484772Y219267D01*
G01X484816Y219343D02*
X484797Y219309D01*
G01Y220884D02*
G02X484816Y219343I-1365J-787D01*
G01X484772Y223167D02*
G03X484797Y220884I2040J-1119D01*
G01Y223209D02*
X484772Y223167D01*
G01X484816Y223243D02*
X484797Y223209D01*
G01Y224784D02*
G02X484816Y223243I-1365J-787D01*
G01X484772Y227067D02*
G03X484797Y224784I2040J-1119D01*
G01Y227109D02*
X484772Y227067D01*
G01X484816Y227143D02*
X484797Y227109D01*
G01Y228684D02*
G02X484816Y227143I-1365J-787D01*
G01X484797Y231010D02*
G03Y228684I2015J-1163D01*
G01X483503Y233371D02*
G02X484797Y231010I-71J-1574D01*
G01X483347Y233371D02*
X483503D01*
G01X481417Y234533D02*
G03X483347Y233371I2015J1163D01*
G01X480096Y235321D02*
G02X481417Y234533I-44J-1575D01*
G01X480001Y235321D02*
X480096D01*
G01X482067Y219309D02*
X482092Y219267D01*
G01X482048Y219343D02*
X482067Y219309D01*
G01Y220884D02*
G03X482048Y219343I1365J-787D01*
G01X482092Y223167D02*
G02X482067Y220884I-2040J-1119D01*
G01Y223209D02*
X482092Y223167D01*
G01X482048Y223243D02*
X482067Y223209D01*
G01Y224784D02*
G03X482048Y223243I1365J-787D01*
G01X482092Y227067D02*
G02X482067Y224784I-2040J-1119D01*
G01Y227109D02*
X482092Y227067D01*
G01X482048Y227143D02*
X482067Y227109D01*
G01Y228684D02*
G03X482048Y227143I1365J-787D01*
G01X480137Y232172D02*
G02X482067Y228684I-85J-2325D01*
G01X479981Y232172D02*
X480137D01*
G01X478687Y232959D02*
G03X479981Y232172I1365J787D01*
G01X527337Y259762D02*
X528491Y259096D01*
G01X527254Y260072D02*
X527337Y259762D01*
G01X528432Y260671D02*
G03X527254Y260072I60J-1575D01*
G01X528550Y260671D02*
X528432D01*
G01X529856Y259884D02*
G03X528550Y260671I-1365J-788D01*
G01X531786Y258722D02*
G02X529856Y259884I85J2325D01*
G01X531956Y258722D02*
X531786D01*
G01X533886Y259884D02*
G02X531956Y258722I-2015J1163D01*
G01X535192Y260671D02*
G03X533886Y259884I59J-1575D01*
G01X535310Y260671D02*
X535192D01*
G01X536616Y259884D02*
G03X535310Y260671I-1365J-788D01*
G01X538546Y258722D02*
G02X536616Y259884I85J2325D01*
G01X538716Y258722D02*
X538546D01*
G01X540646Y259884D02*
G02X538716Y258722I-2015J1163D01*
G01X538702Y274321D02*
G02X539996Y273534I-71J-1574D01*
G01X538560Y274321D02*
X538702D01*
G01X537266Y273534D02*
G02X538560Y274321I1365J-787D01*
G01X535321Y272371D02*
G03X537266Y273534I-70J2325D01*
G01X535181Y272371D02*
X535321D01*
G01X533236Y273534D02*
G03X535181Y272371I2015J1162D01*
G01X530506Y273534D02*
G02X533236I1365J-787D01*
G01X528561Y272371D02*
G03X530506Y273534I-70J2325D01*
G01X528421Y272371D02*
X528561D01*
G01X526476Y273534D02*
G03X528421Y272371I2015J1162D01*
G01X525182Y274321D02*
G02X526476Y273534I-71J-1574D01*
G01X525040Y274321D02*
X525182D01*
G01X523746Y273534D02*
G02X525040Y274321I1365J-787D01*
G01X521801Y272371D02*
G03X523746Y273534I-70J2325D01*
G01X521661Y272371D02*
X521801D01*
G01X519716Y273534D02*
G03X521661Y272371I2015J1162D01*
G01X518400Y274321D02*
G02X519716Y273534I-48J-1574D01*
G01X518281Y274321D02*
X518400D01*
G01X516987Y273534D02*
G02X518281Y274321I1365J-787D01*
G01X515042Y272371D02*
G03X516987Y273534I-70J2325D01*
G01X514902Y272371D02*
X515042D01*
G01X512957Y273534D02*
G03X514902Y272371I2015J1162D01*
G01X510227Y273534D02*
G02X512957I1365J-787D01*
G01X508282Y272371D02*
G03X510227Y273534I-70J2325D01*
G01X508142Y272371D02*
X508282D01*
G01X506197Y273534D02*
G03X508142Y272371I2015J1162D01*
G01X503467Y273534D02*
G02X506197I1365J-787D01*
G01X501522Y272371D02*
G03X503467Y273534I-70J2325D01*
G01X501382Y272371D02*
X501522D01*
G01X499437Y273534D02*
G03X501382Y272371I2015J1162D01*
G01X496707Y271959D02*
G02X499437Y273534I1365J787D01*
G01X496732Y269676D02*
G03X496707Y271959I-2040J1119D01*
G01Y269634D02*
X496732Y269676D01*
G01X494692Y266896D02*
X496707Y269634D01*
G01X528345Y257521D02*
X525111Y257147D01*
G01X528576Y257521D02*
X528345D01*
G01X530506Y256359D02*
G03X528576Y257521I-2015J-1163D01*
G01X531812Y255572D02*
G02X530506Y256359I59J1575D01*
G01X531930Y255572D02*
X531812D01*
G01X533236Y256359D02*
G02X531930Y255572I-1365J788D01*
G01X535250Y257522D02*
G03X533236Y256359I0J-2325D01*
G01X535252Y257522D02*
X535250D01*
G01X537266Y256359D02*
G03X535252Y257522I-2014J-1162D01*
G01X539996Y256359D02*
G02X537266I-1365J788D01*
G01X538701Y275072D02*
G02X540646Y273909I-70J-2325D01*
G01X538561Y275072D02*
X538701D01*
G01X536616Y273909D02*
G02X538561Y275072I2015J-1162D01*
G01X533886Y273909D02*
G03X536616I1365J787D01*
G01X529856D02*
G02X533886I2015J-1162D01*
G01X527126D02*
G03X529856I1365J787D01*
G01X525181Y275072D02*
G02X527126Y273909I-70J-2325D01*
G01X525041Y275072D02*
X525181D01*
G01X523096Y273909D02*
G02X525041Y275072I2015J-1162D01*
G01X520380Y273886D02*
G03X523096Y273909I1351J810D01*
G01X520367D02*
X520380Y273886D01*
G01X518422Y275072D02*
G02X520367Y273909I-70J-2325D01*
G01X518282Y275072D02*
X518422D01*
G01X516337Y273909D02*
G02X518282Y275072I2015J-1162D01*
G01X513607Y273909D02*
G03X516337I1365J787D01*
G01X511662Y275072D02*
G02X513607Y273909I-70J-2325D01*
G01X511522Y275072D02*
X511662D01*
G01X509577Y273909D02*
G02X511522Y275072I2015J-1162D01*
G01X506847Y273909D02*
G03X509577I1365J787D01*
G01X504902Y275072D02*
G02X506847Y273909I-70J-2325D01*
G01X504762Y275072D02*
X504902D01*
G01X502817Y273909D02*
G02X504762Y275072I2015J-1162D01*
G01X500087Y273909D02*
G03X502817I1365J787D01*
G01X498142Y275072D02*
G02X500087Y273909I-70J-2325D01*
G01X498002Y275072D02*
X498142D01*
G01X496057Y273909D02*
G02X498002Y275072I2015J-1162D01*
G01X496032Y273867D02*
X496057Y273909D01*
G01X494736Y273121D02*
G03X496032Y273867I0J1499D01*
G01X494607Y273121D02*
X494736D01*
G01X492677Y271959D02*
G02X494607Y273121I2015J-1163D01*
G01X491371Y271172D02*
G03X492677Y271959I-59J1575D01*
G01X491253Y271172D02*
X491371D01*
G01X489947Y271959D02*
G03X491253Y271172I1365J788D01*
G01X488017Y273121D02*
G02X489947Y271959I-85J-2325D01*
G01X487847Y273121D02*
X488017D01*
G01X485917Y271959D02*
G02X487847Y273121I2015J-1163D01*
G01X484500Y271177D02*
G03X485917Y271959I61J1565D01*
G01X526265Y260381D02*
X525111Y261047D01*
G01X526617Y260476D02*
X526265Y260381D01*
G01X528406Y261421D02*
G03X526617Y260476I84J-2325D01*
G01X528576Y261421D02*
X528406D01*
G01X530506Y260259D02*
G03X528576Y261421I-2015J-1163D01*
G01X531812Y259472D02*
G02X530506Y260259I59J1575D01*
G01X531930Y259472D02*
X531812D01*
G01X533236Y260259D02*
G02X531930Y259472I-1365J788D01*
G01X535166Y261421D02*
G03X533236Y260259I85J-2325D01*
G01X535336Y261421D02*
X535166D01*
G01X537266Y260259D02*
G03X535336Y261421I-2015J-1163D01*
G01X538572Y259472D02*
G02X537266Y260259I59J1575D01*
G01X538690Y259472D02*
X538572D01*
G01X539996Y260259D02*
G02X538690Y259472I-1365J788D01*
G01X481417Y218934D02*
X481436Y218900D01*
G01X481392Y218976D02*
X481417Y218934D01*
G01Y221259D02*
G03X481392Y218976I2015J-1164D01*
G01X481436Y222800D02*
G02X481417Y221259I-1384J-754D01*
G01Y222834D02*
X481436Y222800D01*
G01X481392Y222876D02*
X481417Y222834D01*
G01Y225159D02*
G03X481392Y222876I2015J-1164D01*
G01X481436Y226700D02*
G02X481417Y225159I-1384J-754D01*
G01Y226734D02*
X481436Y226700D01*
G01X481392Y226776D02*
X481417Y226734D01*
G01Y229059D02*
G03X481392Y226776I2015J-1164D01*
G01X480123Y231421D02*
G02X481417Y229059I-71J-1574D01*
G01X479982Y231421D02*
X480123D01*
G01X482537Y340209D02*
G02X479807I-1365J787D01*
G01X486567D02*
G03X482537I-2015J-1162D01*
G01X489297D02*
G02X486567I-1365J787D01*
G01X493327D02*
G03X489297I-2015J-1162D01*
G01X496057D02*
G02X493327I-1365J787D01*
G01X500087D02*
G03X496057I-2015J-1162D01*
G01X502817D02*
G02X500087I-1365J787D01*
G01X506847D02*
G03X502817I-2015J-1162D01*
G01X509577D02*
G02X506847I-1365J787D01*
G01X513607D02*
G03X509577I-2015J-1162D01*
G01X516337D02*
G02X513607I-1365J787D01*
G01X518282Y341372D02*
G03X516337Y340209I70J-2325D01*
G01X527126D02*
G03X525181Y341372I-2015J-1162D01*
G01X529856Y340209D02*
G02X527126I-1365J787D01*
G01X533886D02*
G03X529856I-2015J-1162D01*
G01X536616D02*
G02X533886I-1365J787D01*
G01X540646D02*
G03X536616I-2015J-1162D01*
G01X489316Y402643D02*
G03X489297Y404184I-1384J754D01*
G01Y402609D02*
X489316Y402643D01*
G01X489272Y402567D02*
X489297Y402609D01*
G01Y400284D02*
G02X489272Y402567I2015J1164D01*
G01X488003Y397922D02*
G03X489297Y400284I-71J1574D01*
G01X487847Y397922D02*
X488003D01*
G01X485917Y394434D02*
G02X487847Y397922I2015J1163D01*
G01X485936Y394400D02*
X485917Y394434D01*
G01Y392859D02*
G03X485936Y394400I-1365J787D01*
G01X485892Y390576D02*
G02X485917Y392859I2040J1119D01*
G01Y390534D02*
X485892Y390576D01*
G01X485936Y390500D02*
X485917Y390534D01*
G01Y388959D02*
G03X485936Y390500I-1365J787D01*
G01X485892Y386676D02*
G02X485917Y388959I2040J1119D01*
G01Y386634D02*
X485892Y386676D01*
G01X485936Y386600D02*
X485917Y386634D01*
G01Y385059D02*
G03X485936Y386600I-1365J787D01*
G01X485892Y382776D02*
G02X485917Y385059I2040J1119D01*
G01Y382734D02*
X485892Y382776D01*
G01X485936Y382700D02*
X485917Y382734D01*
G01Y381159D02*
G03X485936Y382700I-1365J787D01*
G01X485892Y378876D02*
G02X485917Y381159I2040J1119D01*
G01Y378834D02*
X485892Y378876D01*
G01X485936Y378800D02*
X485917Y378834D01*
G01X484611Y376472D02*
G03X485936Y378800I-59J1575D01*
G01X484501Y376472D02*
X484611D01*
G01X482512Y373026D02*
G02X484501Y376472I2040J1120D01*
G01X482537Y372984D02*
X482512Y373026D01*
G01X482603Y372868D02*
X482537Y372984D01*
G01Y371410D02*
G03X482603Y372868I-1123J781D01*
G01X482537Y369084D02*
G02Y371410I2015J1163D01*
G01X482556Y367543D02*
G03X482537Y369084I-1384J754D01*
G01X482469Y367392D02*
X482556Y367543D01*
G01X481172Y364396D02*
X482469Y367392D01*
G01X492067Y368333D02*
X493734Y370000D01*
G01X490803Y368333D02*
X492067D01*
G01X490185Y367715D02*
X490803Y368333D01*
G01X488002Y365971D02*
G03X490185Y367715I-70J2325D01*
G01X487873Y365971D02*
X488002D01*
G01X486567Y365184D02*
G02X487873Y365971I1365J-788D01*
G01X484637Y364022D02*
G03X486567Y365184I-85J2325D01*
G01X484508Y364022D02*
X484637D01*
G01X483187Y363234D02*
G02X484508Y364022I1365J-787D01*
G01X483077Y363044D02*
X483187Y363234D01*
G01X482395Y362154D02*
G03X483077Y363044I-3031J3029D01*
G01X482312Y362071D02*
X482395Y362154D01*
G01X479643Y362071D02*
X482312D01*
G01X478445Y360873D02*
X479643Y362071D01*
G01X485892Y402276D02*
G02X485917Y404559I2040J1119D01*
G01Y402234D02*
X485892Y402276D01*
G01X485936Y402200D02*
X485917Y402234D01*
G01X484611Y399872D02*
G03X485936Y402200I-59J1575D01*
G01X484482Y399872D02*
X484611D01*
G01X482537Y396384D02*
G02X484482Y399872I2015J1163D01*
G01X482556Y394843D02*
G03X482537Y396384I-1384J754D01*
G01Y394809D02*
X482556Y394843D01*
G01X482512Y394767D02*
X482537Y394809D01*
G01Y392484D02*
G02X482512Y394767I2015J1164D01*
G01X482556Y390943D02*
G03X482537Y392484I-1384J754D01*
G01Y390909D02*
X482556Y390943D01*
G01X482537Y388583D02*
G02Y390909I2017J1163D01*
G01Y387009D02*
G03Y388583I-1365J787D01*
G01Y384683D02*
G02Y387009I2015J1163D01*
G01Y383109D02*
G03Y384683I-1365J787D01*
G01Y380783D02*
G02Y383109I2015J1163D01*
G01Y379209D02*
G03Y380783I-1364J787D01*
G01X481906Y378602D02*
G03X482537Y379209I-731J1392D01*
G01X480092Y377243D02*
G02X481906Y378602I5140J-4970D01*
G01X479807Y375309D02*
G02X480092Y377243I1365J787D01*
G01X479807Y372983D02*
G03Y375309I-2015J1163D01*
G01X479786Y371447D02*
G02X479807Y372983I1386J749D01*
G01X481172Y368296D02*
X479786Y371447D01*
G01X489506Y370914D02*
X490819Y372227D01*
G01X489506Y368294D02*
Y370914D01*
G01X487976Y366721D02*
G03X489506Y368294I-44J1573D01*
G01X487847Y366721D02*
X487976D01*
G01X485917Y365559D02*
G02X487847Y366721I2015J-1163D01*
G01X484611Y364772D02*
G03X485917Y365559I-59J1575D01*
G01X484482Y364772D02*
X484611D01*
G01X482537Y363609D02*
G02X484482Y364772I2015J-1162D01*
G01X482271Y363262D02*
G03X482537Y363609I-1184J1183D01*
G01X482115Y363106D02*
X482271Y363262D01*
G01X481427Y362821D02*
G03X482115Y363106I0J973D01*
G01X480105Y362821D02*
X481427D01*
G01X479337Y363139D02*
G03X480105Y362821I768J768D01*
G01X478384Y364092D02*
X479337Y363139D01*
G01X518352Y341372D02*
X518282D01*
G01X519703Y342137D02*
G02X518352Y341372I-1351J810D01*
G01X519716Y342160D02*
X519703Y342137D01*
G01X521633Y343321D02*
G03X519716Y342160I98J-2325D01*
G01X521816Y343321D02*
X521633D01*
G01X523746Y342159D02*
G03X521816Y343321I-2015J-1163D01*
G01X525052Y341372D02*
G02X523746Y342159I59J1575D01*
G01X525181Y341372D02*
X525052D01*
G01X488148Y362341D02*
X490148Y364341D01*
G01X487148Y362341D02*
X488148D01*
G01X485148Y360341D02*
X487148Y362341D01*
G01X483648Y360341D02*
X485148D01*
G01X482229Y358922D02*
X483648Y360341D01*
G01X480519Y358922D02*
X482229D01*
G01X479318Y360123D02*
X480519Y358922D01*
G01X489972Y402276D02*
G03X489947Y404559I-2040J1119D01*
G01Y402234D02*
X489972Y402276D01*
G01X489928Y402200D02*
X489947Y402234D01*
G01Y400659D02*
G02X489928Y402200I1365J787D01*
G01X488017Y397171D02*
G03X489947Y400659I-85J2325D01*
G01X487861Y397171D02*
X488017D01*
G01X486567Y394810D02*
G02X487861Y397171I1365J787D01*
G01X486567Y392484D02*
G03Y394810I-2015J1163D01*
G01X486548Y390943D02*
G02X486567Y392484I1384J754D01*
G01Y390909D02*
X486548Y390943D01*
G01X486592Y390867D02*
X486567Y390909D01*
G01Y388584D02*
G03X486592Y390867I-2015J1164D01*
G01X486548Y387043D02*
G02X486567Y388584I1384J754D01*
G01Y387009D02*
X486548Y387043D01*
G01X486592Y386967D02*
X486567Y387009D01*
G01Y384684D02*
G03X486592Y386967I-2015J1164D01*
G01X486548Y383143D02*
G02X486567Y384684I1384J754D01*
G01Y383109D02*
X486548Y383143D01*
G01X486592Y383067D02*
X486567Y383109D01*
G01Y380784D02*
G03X486592Y383067I-2015J1164D01*
G01X486548Y379243D02*
G02X486567Y380784I1384J754D01*
G01Y379209D02*
X486548Y379243D01*
G01X486592Y379167D02*
X486567Y379209D01*
G01Y376884D02*
G03X486592Y379167I-2015J1164D01*
G01X486501Y376769D02*
X486567Y376884D01*
G01X484552Y374146D02*
X486501Y376769D01*
G01X486548Y402643D02*
G02X486567Y404184I1384J754D01*
G01Y402609D02*
X486548Y402643D01*
G01X486592Y402567D02*
X486567Y402609D01*
G01X484637Y399122D02*
G03X486592Y402567I-85J2325D01*
G01X484508Y399122D02*
X484637D01*
G01X483187Y396759D02*
G02X484508Y399122I1365J788D01*
G01X483212Y394476D02*
G03X483187Y396759I-2040J1119D01*
G01Y394434D02*
X483212Y394476D01*
G01X483168Y394400D02*
X483187Y394434D01*
G01Y392859D02*
G02X483168Y394400I1365J787D01*
G01X483212Y390576D02*
G03X483187Y392859I-2040J1119D01*
G01Y388959D02*
G02X483212Y390576I1365J788D01*
G01X483187Y386633D02*
G03Y388959I-2015J1163D01*
G01Y385059D02*
G02Y386633I1365J787D01*
G01Y382733D02*
G03Y385059I-2015J1163D01*
G01Y381159D02*
G02Y382733I1365J787D01*
G01Y378833D02*
G03Y381159I-2017J1163D01*
G01X483043Y378498D02*
G02X483187Y378833I1510J-450D01*
G01X482893Y377986D02*
G02X483043Y378498I5621J-1369D01*
G01X481172Y376096D02*
X482893Y377986D01*
G01X481113Y416671D02*
G03X479807Y415884I59J-1575D01*
G01X481242Y416671D02*
X481113D01*
G01X483190Y417836D02*
G02X481242Y416671I-2018J1163D01*
G01X483364Y418138D02*
X483190Y417836D01*
G01X485598Y420372D02*
X483364Y418138D01*
G01X485598Y421970D02*
Y420372D01*
G01X486492Y422864D02*
X485598Y421970D01*
G01X501981Y413435D02*
Y414534D01*
G01X500117Y411571D02*
X501981Y413435D01*
G01X497987Y411571D02*
X500117D01*
G01X496057Y410409D02*
G02X497987Y411571I2015J-1163D01*
G01X494736Y409621D02*
G03X496057Y410409I-44J1575D01*
G01X494607Y409621D02*
X494736D01*
G01X492677Y408459D02*
G02X494607Y409621I2015J-1163D01*
G01X491371Y407672D02*
G03X492677Y408459I-59J1575D01*
G01X491242Y407672D02*
X491371D01*
G01X489297Y404184D02*
G02X491242Y407672I2015J1163D01*
G01X498063Y416761D02*
Y417688D01*
G01X496668Y415366D02*
X498063Y416761D01*
G01X496057Y414309D02*
X496668Y415366D01*
G01X494736Y413521D02*
G03X496057Y414309I-44J1575D01*
G01X494607Y413521D02*
X494736D01*
G01X492677Y412359D02*
G02X494607Y413521I2015J-1163D01*
G01X491371Y411572D02*
G03X492677Y412359I-59J1575D01*
G01X491242Y411572D02*
X491371D01*
G01X489297Y410409D02*
G02X491242Y411572I2015J-1162D01*
G01X487976Y409621D02*
G03X489297Y410409I-44J1575D01*
G01X487847Y409621D02*
X487976D01*
G01X485892Y406176D02*
G02X487847Y409621I2040J1120D01*
G01X485917Y406134D02*
X485892Y406176D01*
G01X485936Y406100D02*
X485917Y406134D01*
G01Y404559D02*
G03X485936Y406100I-1365J787D01*
G01X484848Y422289D02*
X484032Y423105D01*
G01X484848Y420683D02*
Y422289D01*
G01X482760Y418595D02*
X484848Y420683D01*
G01X482537Y418209D02*
X482760Y418595D01*
G01X481216Y417421D02*
G03X482537Y418209I-44J1575D01*
G01X481087Y417421D02*
X481216D01*
G01X479157Y416259D02*
G02X481087Y417421I2015J-1163D01*
G01X480498Y420983D02*
X479808Y419783D01*
G01X480498Y422106D02*
Y420983D01*
G01X481532Y423140D02*
X480498Y422106D01*
G01X502398Y412791D02*
X503774D01*
G01X500428Y410821D02*
X502398Y412791D01*
G01X498028Y410821D02*
X500428D01*
G01X496707Y410033D02*
G02X498028Y410821I1365J-787D01*
G01X494777Y408871D02*
G03X496707Y410033I-85J2325D01*
G01X494633Y408871D02*
X494777D01*
G01X493327Y408084D02*
G02X494633Y408871I1365J-788D01*
G01X491397Y406922D02*
G03X493327Y408084I-85J2325D01*
G01X491268Y406922D02*
X491397D01*
G01X489947Y404559D02*
G02X491268Y406922I1365J788D01*
G01X479748Y421994D02*
X479032Y422710D01*
G01X479748Y421185D02*
Y421994D01*
G01X479157Y420158D02*
X479748Y421185D01*
G01X498380Y416002D02*
X499913D01*
G01X497243Y414862D02*
X498380Y416002D01*
G01X496705Y413935D02*
X497243Y414862D01*
G01X496707Y413933D02*
X496705Y413935D01*
G01X494777Y412771D02*
G03X496707Y413933I-85J2325D01*
G01X494633Y412771D02*
X494777D01*
G01X493327Y411984D02*
G02X494633Y412771I1365J-788D01*
G01X491397Y410822D02*
G03X493327Y411984I-85J2325D01*
G01X491268Y410822D02*
X491397D01*
G01X489947Y410034D02*
G02X491268Y410822I1365J-787D01*
G01X488002Y408871D02*
G03X489947Y410034I-70J2325D01*
G01X487873Y408871D02*
X488002D01*
G01X486548Y406543D02*
G02X487873Y408871I1384J753D01*
G01X486567Y406509D02*
X486548Y406543D01*
G01X486592Y406467D02*
X486567Y406509D01*
G01Y404184D02*
G03X486592Y406467I-2015J1164D01*
G01X541952Y256771D02*
G03X540646Y255984I59J-1575D01*
G01X542070Y256771D02*
X541952D01*
G01X543376Y255984D02*
G03X542070Y256771I-1365J-788D01*
G01X545306Y254822D02*
G02X543376Y255984I85J2325D01*
G01X545476Y254822D02*
X545306D01*
G01X547406Y255984D02*
G02X545476Y254822I-2015J1163D01*
G01X548712Y256771D02*
G03X547406Y255984I59J-1575D01*
G01X548830Y256771D02*
X548712D01*
G01X550136Y255984D02*
G03X548830Y256771I-1365J-788D01*
G01X552066Y254822D02*
G02X550136Y255984I85J2325D01*
G01X552236Y254822D02*
X552066D01*
G01X554166Y255984D02*
G02X552236Y254822I-2015J1163D01*
G01X555472Y256771D02*
G03X554166Y255984I59J-1575D01*
G01X556429Y256771D02*
X555472D01*
G01X558000Y255200D02*
X556429Y256771D01*
G01X560376Y255200D02*
X558000D01*
G01X561941Y256765D02*
X560376Y255200D01*
G01X563936Y256765D02*
X561941D01*
G01X541952Y260671D02*
G03X540646Y259884I59J-1575D01*
G01X542070Y260671D02*
X541952D01*
G01X543376Y259884D02*
G03X542070Y260671I-1365J-788D01*
G01X545306Y258722D02*
G02X543376Y259884I85J2325D01*
G01X545476Y258722D02*
X545306D01*
G01X547406Y259884D02*
G02X545476Y258722I-2015J1163D01*
G01X548712Y260671D02*
G03X547406Y259884I59J-1575D01*
G01X548830Y260671D02*
X548712D01*
G01X550136Y259884D02*
G03X548830Y260671I-1365J-788D01*
G01X552066Y258722D02*
G02X550136Y259884I85J2325D01*
G01X552236Y258722D02*
X552066D01*
G01X554166Y259884D02*
G02X552236Y258722I-2015J1163D01*
G01X555472Y260671D02*
G03X554166Y259884I59J-1575D01*
G01X555939Y260671D02*
X555472D01*
G01X555966Y260644D02*
X555939Y260671D01*
G01X556256Y260644D02*
X555966D01*
G01X558534Y274600D02*
X560900D01*
G01X557796Y273862D02*
X558534Y274600D01*
G01X557546Y273534D02*
G02X557796Y273862I1368J-783D01*
G01X555601Y272371D02*
G03X557546Y273534I-70J2325D01*
G01X555461Y272371D02*
X555601D01*
G01X553516Y273534D02*
G03X555461Y272371I2015J1162D01*
G01X552222Y274321D02*
G02X553516Y273534I-71J-1574D01*
G01X552080Y274321D02*
X552222D01*
G01X550786Y273534D02*
G02X552080Y274321I1365J-787D01*
G01X548841Y272371D02*
G03X550786Y273534I-70J2325D01*
G01X548701Y272371D02*
X548841D01*
G01X546756Y273534D02*
G03X548701Y272371I2015J1162D01*
G01X545462Y274321D02*
G02X546756Y273534I-71J-1574D01*
G01X545320Y274321D02*
X545462D01*
G01X544026Y273534D02*
G02X545320Y274321I1365J-787D01*
G01X542081Y272371D02*
G03X544026Y273534I-70J2325D01*
G01X541941Y272371D02*
X542081D01*
G01X539996Y273534D02*
G03X541941Y272371I2015J1162D01*
G01X541926Y257521D02*
G03X539996Y256359I85J-2325D01*
G01X542096Y257521D02*
X541926D01*
G01X544026Y256359D02*
G03X542096Y257521I-2015J-1163D01*
G01X545332Y255572D02*
G02X544026Y256359I59J1575D01*
G01X545450Y255572D02*
X545332D01*
G01X546756Y256359D02*
G02X545450Y255572I-1365J788D01*
G01X548686Y257521D02*
G03X546756Y256359I85J-2325D01*
G01X548856Y257521D02*
X548686D01*
G01X550786Y256359D02*
G03X548856Y257521I-2015J-1163D01*
G01X552092Y255572D02*
G02X550786Y256359I59J1575D01*
G01X552210Y255572D02*
X552092D01*
G01X553516Y256359D02*
G02X552210Y255572I-1365J788D01*
G01X555446Y257521D02*
G03X553516Y256359I85J-2325D01*
G01X556921Y257521D02*
X555446D01*
G01X558349Y258949D02*
X556921Y257521D01*
G01X566368Y258949D02*
X558349D01*
G01X558224Y275351D02*
X561213D01*
G01X557265Y274392D02*
X558224Y275351D01*
G01X557000Y274074D02*
G02X557265Y274392I1912J-1324D01*
G01X556896Y273909D02*
G02X557000Y274074I2018J-1157D01*
G01X554166Y273909D02*
G03X556896I1365J787D01*
G01X552221Y275072D02*
G02X554166Y273909I-70J-2325D01*
G01X552081Y275072D02*
X552221D01*
G01X550136Y273909D02*
G02X552081Y275072I2015J-1162D01*
G01X547406Y273909D02*
G03X550136I1365J787D01*
G01X545461Y275072D02*
G02X547406Y273909I-70J-2325D01*
G01X545321Y275072D02*
X545461D01*
G01X543376Y273909D02*
G02X545321Y275072I2015J-1162D01*
G01X540646Y273909D02*
G03X543376I1365J787D01*
G01X541926Y261421D02*
G03X539996Y260259I85J-2325D01*
G01X542096Y261421D02*
X541926D01*
G01X544026Y260259D02*
G03X542096Y261421I-2015J-1163D01*
G01X545332Y259472D02*
G02X544026Y260259I59J1575D01*
G01X545450Y259472D02*
X545332D01*
G01X546756Y260259D02*
G02X545450Y259472I-1365J788D01*
G01X548686Y261421D02*
G03X546756Y260259I85J-2325D01*
G01X548856Y261421D02*
X548686D01*
G01X550786Y260259D02*
G03X548856Y261421I-2015J-1163D01*
G01X552092Y259472D02*
G02X550786Y260259I59J1575D01*
G01X552210Y259472D02*
X552092D01*
G01X553516Y260259D02*
G02X552210Y259472I-1365J788D01*
G01X555446Y261421D02*
G03X553516Y260259I85J-2325D01*
G01X556341Y261421D02*
X555446D01*
G01X543376Y340209D02*
G02X540646I-1365J787D01*
G01X547406D02*
G03X543376I-2015J-1162D01*
G01X550136D02*
G02X547406I-1365J787D01*
G01X554166D02*
G03X550136I-2015J-1162D01*
G01X556684Y339922D02*
G02X554166Y340209I-1153J1074D01*
G01X559102Y340881D02*
G03X556684Y339922I399J-4533D01*
G01X561195Y341805D02*
G02X559102Y340881I-2093J1908D01*
G01X561695Y342305D02*
X561195Y341805D01*
G01X564600Y343327D02*
G03X561695Y342305I0J-4640D01*
G01X568986Y343327D02*
X564600D01*
G01X708400Y8600D02*
X705250D01*
G01X709500Y9700D02*
X708400Y8600D01*
G01X715000Y9700D02*
X709500D01*
G01X719102Y5598D02*
X715000Y9700D01*
G01X719102Y2224D02*
Y5598D01*
G01X720749Y577D02*
X719102Y2224D01*
G01X720749Y334D02*
Y577D01*
G01X720750Y333D02*
X720749Y334D01*
G01X720750Y-6875D02*
Y333D01*
G01X719802Y-7823D02*
X720750Y-6875D01*
G01X716427Y-7823D02*
X719802D01*
G01X715083Y-9167D02*
X716427Y-7823D01*
G01X715083Y-15283D02*
Y-9167D01*
G01X719895Y-20095D02*
X715083Y-15283D01*
G01X1273605Y-20095D02*
X719895D01*
G01X907291Y191656D02*
X912744Y197109D01*
G01X906055Y191656D02*
X907291D01*
G01X904900Y190501D02*
X906055Y191656D01*
G01X907817Y191122D02*
Y188367D01*
G01X913055Y196360D02*
X907817Y191122D01*
G01X904289Y249585D02*
X910989Y256285D01*
G01X903303Y249585D02*
X904289D01*
G01X905281Y249519D02*
X911297Y255535D01*
G01X905281Y248007D02*
Y249519D01*
G01X909886Y239841D02*
X910995D01*
G01X907956Y248972D02*
X911369Y252385D01*
G01X907956Y245859D02*
Y248972D01*
G01X907136Y245039D02*
X907956Y245859D01*
G01X905849Y245039D02*
X907136D01*
G01X908706Y248661D02*
X911680Y251635D01*
G01X908706Y245551D02*
Y248661D01*
G01X908017Y244862D02*
X908706Y245551D01*
G01X908017Y243671D02*
Y244862D01*
G01X905856Y341741D02*
X905056Y340941D01*
G01X909707Y328989D02*
X908816Y329880D01*
G01X910466Y328989D02*
X909707D01*
G01X910277Y323429D02*
X909426Y324280D01*
G01X910327Y322681D02*
X909426Y321780D01*
G01X895538Y313601D02*
X921242D01*
G01X909557Y328241D02*
X908696Y327380D01*
G01X910156Y328241D02*
X909557D01*
G01X912356Y341741D02*
X905856D01*
G01X902941Y348100D02*
X901966D01*
G01X904000Y347041D02*
X902941Y348100D01*
G01X910456Y347041D02*
X904000D01*
G01X906556Y357499D02*
X911604Y352451D01*
G01X906556Y358616D02*
Y357499D01*
G01X908256Y379641D02*
X906947D01*
G01X915756Y372141D02*
X908256Y379641D01*
G01X903400Y349333D02*
X902716Y350017D01*
G01X903400Y348801D02*
Y349333D01*
G01X904412Y347789D02*
X903400Y348801D01*
G01X910766Y347789D02*
X904412D01*
G01X909800Y361455D02*
Y362444D01*
G01X912266Y358989D02*
X909800Y361455D01*
G01X906256Y356741D02*
X904895D01*
G01X910856Y352141D02*
X906256Y356741D01*
G01X906008Y342489D02*
X905056Y343441D01*
G01X912669Y342489D02*
X906008D01*
G01X908656Y380299D02*
Y381468D01*
G01X916066Y372889D02*
X908656Y380299D01*
G01X909556Y360641D02*
X908067D01*
G01X911956Y358241D02*
X909556Y360641D01*
G01X912152Y187217D02*
Y186099D01*
G01X917938Y193003D02*
X912152Y187217D01*
G01X919532Y193003D02*
X917938D01*
G01X925640Y199110D02*
X919532Y193003D01*
G01X926242Y200147D02*
X925640Y199110D01*
G01X927548Y200935D02*
G03X926242Y200147I59J-1574D01*
G01X927956Y200935D02*
X927548D01*
G01X930047Y200045D02*
X927956Y200935D01*
G01X930928Y199735D02*
G02X930047Y200045I59J1574D01*
G01X931046Y199735D02*
X930928D01*
G01X932352Y200523D02*
G02X931046Y199735I-1365J786D01*
G01X934297Y201686D02*
G03X932352Y200523I70J-2325D01*
G01X934448Y201686D02*
X934297D01*
G01X935732Y202472D02*
G02X934448Y201686I-1365J788D01*
G01X935751Y204013D02*
G02X935732Y202472I-1384J-754D01*
G01Y204047D02*
X935751Y204013D01*
G01X935561Y204344D02*
X935732Y204047D01*
G01X935319Y204533D02*
X935561Y204344D01*
G01X933408Y205909D02*
X935319Y204533D01*
G01X933002Y206372D02*
G03X933408Y205909I1365J787D01*
G01X933002Y207946D02*
G03Y206372I1365J-787D01*
G01X933068Y208060D02*
X933002Y207946D01*
G01X934367Y211060D02*
X933068Y208060D01*
G01X944507Y207778D02*
Y209109D01*
G01X944763Y207522D02*
X944507Y207778D01*
G01X946522Y204047D02*
G03X944763Y207522I-2015J1163D01*
G01X946503Y204013D02*
X946522Y204047D01*
G01Y202472D02*
G02X946503Y204013I1365J787D01*
G01X946547Y200189D02*
G03X946522Y202472I-2040J1119D01*
G01Y200147D02*
X946547Y200189D01*
G01X946503Y200113D02*
X946522Y200147D01*
G01X946573Y198492D02*
G02X946503Y200113I1311J869D01*
G01X946866Y198050D02*
X946573Y198492D01*
G01X946866Y195431D02*
Y198050D01*
G01X934727Y183292D02*
X946866Y195431D01*
G01X934727Y182551D02*
Y183292D01*
G01X953934Y198219D02*
X953056Y197341D01*
G01X953934Y201213D02*
Y198219D01*
G01X956222Y203501D02*
X953934Y201213D01*
G01X956222Y211060D02*
Y203501D01*
G01X956011Y211847D02*
G02X956222Y211060I-1364J-787D01*
G01X955976Y211907D02*
X956011Y211847D01*
G01Y214173D02*
G03X955976Y211907I2015J-1164D01*
G01X956011Y215747D02*
G02Y214173I-1364J-787D01*
G01X955976Y215807D02*
X956011Y215747D01*
G01Y218073D02*
G03X955976Y215807I2015J-1164D01*
G01X959676Y198221D02*
X960556Y197341D01*
G01X959676Y198977D02*
Y198221D01*
G01X960359Y199660D02*
X959676Y198977D01*
G01X960359Y202416D02*
Y199660D01*
G01X960188Y202587D02*
X960359Y202416D01*
G01X960188Y210017D02*
Y202587D01*
G01X960041Y210272D02*
X960188Y210017D01*
G01X960022Y211813D02*
G03X960041Y210272I1384J-754D01*
G01Y211847D02*
X960022Y211813D01*
G01X960066Y211889D02*
X960041Y211847D01*
G01Y214172D02*
G02X960066Y211889I-2015J-1164D01*
G01X960022Y215713D02*
G03X960041Y214172I1384J-754D01*
G01Y215747D02*
X960022Y215713D01*
G01X960066Y215789D02*
X960041Y215747D01*
G01Y218072D02*
G02X960066Y215789I-2015J-1164D01*
G01X931123Y202884D02*
X934367Y203260D01*
G01X930928Y202884D02*
X931123D01*
G01X930037Y202566D02*
G02X930928Y202884I951J-1257D01*
G01X928156Y201686D02*
G03X930037Y202566I-1123J4850D01*
G01X927537Y201686D02*
X928156D01*
G01X925592Y200523D02*
G02X927537Y201686I2015J-1162D01*
G01X925041Y199570D02*
X925592Y200523D01*
G01X919222Y193751D02*
X925041Y199570D01*
G01X919221Y193751D02*
X919222D01*
G01X919220Y193752D02*
X919221Y193751D01*
G01X917627Y193752D02*
X919220D01*
G01X911731Y187856D02*
X917627Y193752D01*
G01X910394Y187856D02*
X911731D01*
G01X925495Y215490D02*
X925005Y215000D01*
G01X925686Y215951D02*
G02X925495Y215490I-652J0D01*
G01X925686Y216005D02*
Y215951D01*
G01X925887Y216525D02*
G03X925686Y216005I572J-520D01*
G01X927537Y217285D02*
G03X925887Y216525I71J-2325D01*
G01X927666Y217285D02*
X927537D01*
G01X928991Y219613D02*
G02X927666Y217285I-1384J-753D01*
G01X942492Y207948D02*
X941127Y211060D01*
G01X942679Y206891D02*
G03X942492Y207948I-1552J270D01*
G01X943142Y204424D02*
G02X942679Y206891I3278J1892D01*
G01X943142Y204423D02*
Y204424D01*
G01Y202097D02*
G03Y204423I-2015J1163D01*
G01X943123Y200556D02*
G02X943142Y202097I1384J754D01*
G01Y200522D02*
X943123Y200556D01*
G01X943167Y200480D02*
X943142Y200522D01*
G01Y198197D02*
G03X943167Y200480I-2015J1164D01*
G01X942856Y197704D02*
X943142Y198197D01*
G01X942856Y195709D02*
Y197704D01*
G01X936038Y188891D02*
X942856Y195709D01*
G01X933127Y188891D02*
X936038D01*
G01X931242Y187006D02*
X933127Y188891D01*
G01X931242Y186145D02*
Y187006D01*
G01X971444Y200207D02*
X973450Y198201D01*
G01X971444Y201888D02*
Y200207D01*
G01X971967Y202801D02*
X971444Y201888D01*
G01X969506Y208905D02*
X971967Y206444D01*
G01X969506Y217424D02*
Y208905D01*
G01X969741Y217659D02*
X969506Y217424D01*
G01X969741Y218869D02*
Y217659D01*
G01X923089Y218484D02*
X922216Y217611D01*
G01X929452Y217444D02*
G03X929647Y219980I-1845J1417D01*
G01X929408Y217138D02*
X929452Y217444D01*
G01X929407Y216900D02*
X929408Y217138D01*
G01X929407Y215372D02*
Y216900D01*
G01X931133Y187958D02*
X929519D01*
G01X932816Y189641D02*
X931133Y187958D01*
G01X935727Y189641D02*
X932816D01*
G01X942106Y196020D02*
X935727Y189641D01*
G01X942106Y197904D02*
Y196020D01*
G01X942492Y198572D02*
X942106Y197904D01*
G01X942511Y200113D02*
G02X942492Y198572I-1384J-754D01*
G01Y200147D02*
X942511Y200113D01*
G01X942467Y200189D02*
X942492Y200147D01*
G01Y202472D02*
G03X942467Y200189I2015J-1164D01*
G01X942598Y202694D02*
G02X942492Y202472I-1445J554D01*
G01X942686Y203032D02*
G02X942598Y202694I-1560J226D01*
G01X942458Y203260D02*
X942686Y203032D01*
G01X941127Y203260D02*
X942458D01*
G01X944507Y206541D02*
Y205210D01*
G01X944735Y206769D02*
X944507Y206541D01*
G01X945872Y204423D02*
G03X944735Y206769I-1365J787D01*
G01X945872Y202097D02*
G02Y204423I2015J1163D01*
G01X945891Y200556D02*
G03X945872Y202097I-1384J754D01*
G01Y200522D02*
X945891Y200556D01*
G01X945847Y200480D02*
X945872Y200522D01*
G01Y198197D02*
G02X945847Y200480I2015J1164D01*
G01X946116Y197737D02*
X945872Y198197D01*
G01X946116Y195741D02*
Y197737D01*
G01X934767Y184392D02*
X946116Y195741D01*
G01X933025Y184392D02*
X934767D01*
G01X956974Y211060D02*
X956973Y209837D01*
G01X956697Y212162D02*
G02X956974Y211060I-2050J-1101D01*
G01X956662Y212222D02*
X956697Y212162D01*
G01X956662Y213796D02*
G03Y212222I1364J-787D01*
G01X956697Y216062D02*
G02X956662Y213796I-2050J-1102D01*
G01Y216122D02*
X956697Y216062D01*
G01X956662Y217696D02*
G03Y216122I1364J-787D01*
G01X956697Y219962D02*
G02X956662Y217696I-2050J-1102D01*
G01X954684Y198213D02*
X955556Y197341D01*
G01X954684Y200901D02*
Y198213D01*
G01X956973Y203190D02*
X954684Y200901D01*
G01X956973Y209837D02*
Y203190D01*
G01X958926Y198211D02*
X958056Y197341D01*
G01X958926Y199311D02*
Y198211D01*
G01X959609Y199994D02*
X958926Y199311D01*
G01X959609Y202108D02*
Y199994D01*
G01X959438Y202279D02*
X959609Y202108D01*
G01X959438Y209815D02*
Y202279D01*
G01X959391Y209897D02*
X959438Y209815D01*
G01X959366Y212180D02*
G03X959391Y209897I2040J-1119D01*
G01Y212222D02*
X959366Y212180D01*
G01X959410Y212256D02*
X959391Y212222D01*
G01Y213797D02*
G02X959410Y212256I-1365J-787D01*
G01X959366Y216080D02*
G03X959391Y213797I2040J-1119D01*
G01Y216122D02*
X959366Y216080D01*
G01X959410Y216156D02*
X959391Y216122D01*
G01Y217697D02*
G02X959410Y216156I-1365J-787D01*
G01X959366Y219980D02*
G03X959391Y217697I2040J-1119D01*
G01X929540Y205437D02*
X930987Y205210D01*
G01X928259Y205585D02*
X929540Y205437D01*
G01X927522Y205585D02*
X928259D01*
G01X925592Y204423D02*
G02X927522Y205585I2015J-1163D01*
G01X924271Y203635D02*
G03X925592Y204423I-44J1575D01*
G01X924176Y203635D02*
X924271D01*
G01X922212Y202472D02*
G02X924176Y203635I2015J-1163D01*
G01X922214Y202471D02*
X922212Y202472D01*
G01X921460Y201164D02*
X922214Y202471D01*
G01X917405Y197109D02*
X921460Y201164D01*
G01X912744Y197109D02*
X917405D01*
G01X970491Y217327D02*
Y218870D01*
G01X970256Y217092D02*
X970491Y217327D01*
G01X970256Y209245D02*
Y217092D01*
G01X972717Y206784D02*
X970256Y209245D01*
G01X917714Y196360D02*
X913055D01*
G01X922059Y200705D02*
X917714Y196360D01*
G01X922862Y202097D02*
X922059Y200705D01*
G01X924168Y202884D02*
G03X922862Y202097I59J-1575D01*
G01X924278Y202884D02*
X924168D01*
G01X926242Y204047D02*
G02X924278Y202884I-2015J1163D01*
G01X927536Y204834D02*
G03X926242Y204047I71J-1574D01*
G01X927856Y204834D02*
X927536D01*
G01X928262Y204784D02*
X927856Y204834D01*
G01X928799Y204588D02*
X928262Y204784D01*
G01X930035Y203955D02*
X928799Y204588D01*
G01X932352Y205997D02*
G02X930035Y203955I-1365J-787D01*
G01X932327Y206039D02*
G03X932352Y205997I619J340D01*
G01X932235Y208092D02*
G03X932327Y206039I2131J-933D01*
G01X932141Y208444D02*
X932235Y208092D01*
G01X930987Y209109D02*
X932141Y208444D01*
G01X914572Y235222D02*
Y233875D01*
G01X915489Y236139D02*
X914572Y235222D01*
G01X916100Y237198D02*
X915489Y236139D01*
G01X916102Y237197D02*
X916100Y237198D01*
G01X916127Y239480D02*
G02X916102Y237197I-2040J-1119D01*
G01Y239522D02*
X916127Y239480D01*
G01X916083Y239556D02*
X916102Y239522D01*
G01Y241097D02*
G03X916083Y239556I1365J-787D01*
G01X916127Y243380D02*
G02X916102Y241097I-2040J-1119D01*
G01Y243422D02*
X916127Y243380D01*
G01X916083Y243456D02*
X916102Y243422D01*
G01X917408Y245784D02*
G03X916083Y243456I59J-1575D01*
G01X917537Y245784D02*
X917408D01*
G01X919482Y246947D02*
G02X917537Y245784I-2015J1162D01*
G01X920803Y247735D02*
G03X919482Y246947I44J-1575D01*
G01X920932Y247735D02*
X920803D01*
G01X922862Y248897D02*
G02X920932Y247735I-2015J1163D01*
G01X924168Y249684D02*
G03X922862Y248897I59J-1575D01*
G01X924981Y249684D02*
X924168D01*
G01X926304Y249136D02*
G03X924981Y249684I-1323J-1323D01*
G01X926536Y248904D02*
X926304Y249136D01*
G01X927548Y248485D02*
G02X926536Y248904I59J1575D01*
G01X927677Y248485D02*
X927548D01*
G01X929622Y247322D02*
G03X927677Y248485I-2015J-1162D01*
G01X930943Y246534D02*
G02X929622Y247322I44J1575D01*
G01X931456Y246534D02*
X930943D01*
G01X932034Y246817D02*
X931456Y246534D01*
G01X933601Y247656D02*
X932034Y246817D01*
G01X934061Y247735D02*
G03X933601Y247656I1J-1383D01*
G01X934411Y247735D02*
X934061D01*
G01X935732Y246947D02*
G03X934411Y247735I-1365J-787D01*
G01X935798Y246831D02*
X935732Y246947D01*
G01X937747Y244209D02*
X935798Y246831D01*
G01X924373Y262134D02*
X927607Y261760D01*
G01X924142Y262134D02*
X924373D01*
G01X922212Y260972D02*
G02X924142Y262134I2015J-1163D01*
G01X920906Y260185D02*
G03X922212Y260972I-59J1575D01*
G01X920777Y260185D02*
X920906D01*
G01X918832Y259022D02*
G02X920777Y260185I2015J-1162D01*
G01X917511Y258234D02*
G03X918832Y259022I-44J1575D01*
G01X916667Y258234D02*
X917511D01*
G01X915295Y257061D02*
G02X916667Y258234I2172J-1152D01*
G01X914444Y256285D02*
G03X915295Y257061I-657J1575D01*
G01X910989Y256285D02*
X914444D01*
G01X956011Y219647D02*
G02Y218073I-1364J-787D01*
G01X955976Y219707D02*
X956011Y219647D01*
G01Y221973D02*
G03X955976Y219707I2015J-1164D01*
G01X956011Y223547D02*
G02Y221973I-1364J-787D01*
G01X955976Y223607D02*
X956011Y223547D01*
G01Y225873D02*
G03X955976Y223607I2015J-1164D01*
G01X956011Y227447D02*
G02Y225873I-1364J-787D01*
G01X955986Y229730D02*
G03X956011Y227447I2040J-1119D01*
G01Y229772D02*
X955986Y229730D01*
G01X956011Y231346D02*
G02Y229772I-1364J-787D01*
G01X955986Y231388D02*
X956011Y231346D01*
G01Y233673D02*
G03X955986Y231388I2015J-1165D01*
G01X956011Y235247D02*
G02Y233673I-1364J-787D01*
G01X955976Y235307D02*
X956011Y235247D01*
G01Y237573D02*
G03X955976Y235307I2015J-1164D01*
G01X956011Y239147D02*
G02Y237573I-1364J-787D01*
G01X955976Y239207D02*
X956011Y239147D01*
G01Y241473D02*
G03X955976Y239207I2015J-1164D01*
G01X956011Y243047D02*
G02Y241473I-1364J-787D01*
G01X955976Y243107D02*
X956011Y243047D01*
G01Y245373D02*
G03X955976Y243107I2015J-1164D01*
G01X956011Y246947D02*
G02Y245373I-1364J-787D01*
G01X955976Y247007D02*
X956011Y246947D01*
G01Y249273D02*
G03X955976Y247007I2015J-1164D01*
G01X956011Y250847D02*
G02Y249273I-1364J-787D01*
G01X955976Y250907D02*
X956011Y250847D01*
G01Y253173D02*
G03X955976Y250907I2015J-1164D01*
G01X956011Y254747D02*
G02Y253173I-1364J-787D01*
G01X955976Y254807D02*
X956011Y254747D01*
G01Y257073D02*
G03X955976Y254807I2015J-1164D01*
G01X956011Y258647D02*
G02Y257073I-1364J-787D01*
G01X955976Y258707D02*
X956011Y258647D01*
G01Y260972D02*
G03X955976Y258707I2017J-1164D01*
G01X956011Y262546D02*
G02Y260972I-1364J-787D01*
G01Y264872D02*
G03Y262546I2015J-1163D01*
G01X956027Y264900D02*
X956011Y264872D01*
G01X957795Y267360D02*
G03X956027Y264900I11400J-10059D01*
G01X958026Y267609D02*
X957795Y267360D01*
G01X960022Y219613D02*
G03X960041Y218072I1384J-754D01*
G01Y219647D02*
X960022Y219613D01*
G01X960066Y219689D02*
X960041Y219647D01*
G01Y221972D02*
G02X960066Y219689I-2015J-1164D01*
G01X960022Y223513D02*
G03X960041Y221972I1384J-754D01*
G01Y223547D02*
X960022Y223513D01*
G01X960066Y223589D02*
X960041Y223547D01*
G01Y225872D02*
G02X960066Y223589I-2015J-1164D01*
G01X960022Y227413D02*
G03X960041Y225872I1384J-754D01*
G01Y227447D02*
X960022Y227413D01*
G01X960066Y229730D02*
G02X960041Y227447I-2040J-1119D01*
G01Y229772D02*
X960066Y229730D01*
G01X960041Y231346D02*
G03Y229772I1365J-787D01*
G01Y233672D02*
G02Y231346I-2015J-1163D01*
G01X960022Y235213D02*
G03X960041Y233672I1384J-754D01*
G01Y235247D02*
X960022Y235213D01*
G01X960066Y235289D02*
X960041Y235247D01*
G01Y237572D02*
G02X960066Y235289I-2015J-1164D01*
G01X960022Y239113D02*
G03X960041Y237572I1384J-754D01*
G01Y239147D02*
X960022Y239113D01*
G01X960066Y239189D02*
X960041Y239147D01*
G01Y241472D02*
G02X960066Y239189I-2015J-1164D01*
G01X960022Y243013D02*
G03X960041Y241472I1384J-754D01*
G01Y243047D02*
X960022Y243013D01*
G01X960066Y243089D02*
X960041Y243047D01*
G01Y245372D02*
G02X960066Y243089I-2015J-1164D01*
G01X960022Y246913D02*
G03X960041Y245372I1384J-754D01*
G01Y246947D02*
X960022Y246913D01*
G01X960066Y246989D02*
X960041Y246947D01*
G01Y249272D02*
G02X960066Y246989I-2015J-1164D01*
G01X960022Y250813D02*
G03X960041Y249272I1384J-754D01*
G01Y250847D02*
X960022Y250813D01*
G01X960066Y250889D02*
X960041Y250847D01*
G01Y253172D02*
G02X960066Y250889I-2015J-1164D01*
G01X960022Y254713D02*
G03X960041Y253172I1384J-754D01*
G01Y254747D02*
X960022Y254713D01*
G01X960066Y254789D02*
X960041Y254747D01*
G01Y257072D02*
G02X960066Y254789I-2015J-1164D01*
G01X960022Y258613D02*
G03X960041Y257072I1384J-754D01*
G01Y258647D02*
X960022Y258613D01*
G01X960066Y258689D02*
X960041Y258647D01*
G01Y260972D02*
G02X960066Y258689I-2018J-1164D01*
G01X960041Y262546D02*
G03Y260972I1365J-787D01*
G01X961980Y264192D02*
G03X960041Y262546I1328J-3530D01*
G01X962656Y266618D02*
G02X961980Y264192I-1250J-959D01*
G01X960802Y268104D02*
G02X962656Y266618I-1636J-3940D01*
G01X960041Y270346D02*
G03X960802Y268104I1365J-787D01*
G01X961406Y273460D02*
X960041Y270346D01*
G01X931133Y258234D02*
X934367Y257860D01*
G01X930943Y258234D02*
X931133D01*
G01X929622Y259022D02*
G03X930943Y258234I1365J787D01*
G01X927677Y260185D02*
G02X929622Y259022I-70J-2325D01*
G01X926306Y260185D02*
X927677D01*
G01X925592Y260597D02*
G03X926306Y260185I714J413D01*
G01X924286Y261384D02*
G02X925592Y260597I-59J-1575D01*
G01X924168Y261384D02*
X924286D01*
G01X922862Y260597D02*
G02X924168Y261384I1365J-788D01*
G01X920932Y259435D02*
G03X922862Y260597I-85J2325D01*
G01X920803Y259435D02*
X920932D01*
G01X919482Y258647D02*
G02X920803Y259435I1365J-787D01*
G01X917537Y257484D02*
G03X919482Y258647I-70J2325D01*
G01X916810Y257484D02*
X917537D01*
G01X915959Y256708D02*
G02X916810Y257484I1508J-799D01*
G01X914587Y255535D02*
G03X915959Y256708I-800J2325D01*
G01X911297Y255535D02*
X914587D01*
G01X934511Y267986D02*
X937747Y267609D01*
G01X934323Y267986D02*
X934511D01*
G01X933757Y268108D02*
G03X934323Y267986I609J1453D01*
G01X932406Y268841D02*
G03X933757Y268108I1433J1030D01*
G01X932327Y270680D02*
G03X932406Y268841I1443J-859D01*
G01X932352Y270722D02*
X932327Y270680D01*
G01X932371Y270756D02*
X932352Y270722D01*
G01X931046Y273084D02*
G02X932371Y270756I-59J-1575D01*
G01X930917Y273084D02*
X931046D01*
G01X928972Y274247D02*
G03X930917Y273084I2015J1162D01*
G01X927651Y275035D02*
G02X928972Y274247I-44J-1575D01*
G01X927522Y275035D02*
X927651D01*
G01X925592Y276197D02*
G03X927522Y275035I2015J1163D01*
G01X924286Y276984D02*
G02X925592Y276197I-59J-1575D01*
G01X924168Y276984D02*
X924286D01*
G01X922862Y276197D02*
G02X924168Y276984I1365J-788D01*
G01X920932Y275035D02*
G03X922862Y276197I-85J2325D01*
G01X920072Y275035D02*
X920932D01*
G01X919331Y274345D02*
G02X920072Y275035I1516J-885D01*
G01X917951Y273229D02*
G03X919331Y274345I-784J2380D01*
G01X917345Y273184D02*
X917951Y273229D01*
G01X916553Y273184D02*
X917345D01*
G01X915898Y272529D02*
X916553Y273184D01*
G01X928972Y219647D02*
X928991Y219613D01*
G01X928947Y219689D02*
X928972Y219647D01*
G01Y221972D02*
G03X928947Y219689I2015J-1164D01*
G01X928991Y223513D02*
G02X928972Y221972I-1384J-754D01*
G01Y223547D02*
X928991Y223513D01*
G01X928947Y223589D02*
X928972Y223547D01*
G01Y225872D02*
G03X928947Y223589I2015J-1164D01*
G01X928991Y227413D02*
G02X928972Y225872I-1384J-754D01*
G01Y227447D02*
X928991Y227413D01*
G01X928947Y229730D02*
G03X928972Y227447I2040J-1119D01*
G01Y229772D02*
X928947Y229730D01*
G01X928972Y231346D02*
G02Y229772I-1365J-787D01*
G01Y233672D02*
G03Y231346I2015J-1163D01*
G01X928991Y235213D02*
G02X928972Y233672I-1384J-754D01*
G01Y235247D02*
X928991Y235213D01*
G01X928947Y235289D02*
X928972Y235247D01*
G01X928855Y237342D02*
G03X928947Y235289I2131J-933D01*
G01X928761Y237694D02*
X928855Y237342D01*
G01X927607Y238360D02*
X928761Y237694D01*
G01X972845Y264610D02*
X971546Y267609D01*
G01X933239Y251600D02*
X934367Y250060D01*
G01X932246Y252957D02*
X933239Y251600D01*
G01X931675Y253427D02*
G02X932246Y252957I-688J-1418D01*
G01X929873Y254307D02*
X931675Y253427D01*
G01X928746Y255049D02*
X929873Y254307D01*
G01X927651Y255535D02*
G02X928746Y255049I-44J-1575D01*
G01X927306Y255535D02*
X927651D01*
G01X925953Y254999D02*
X927306Y255535D01*
G01X924909Y254489D02*
X925953Y254999D01*
G01X924271Y254334D02*
G03X924909Y254489I-45J1575D01*
G01X924142Y254334D02*
X924271D01*
G01X922212Y253172D02*
G02X924142Y254334I2015J-1163D01*
G01X920906Y252385D02*
G03X922212Y253172I-59J1575D01*
G01X920777Y252385D02*
X920906D01*
G01X918832Y251222D02*
G02X920777Y252385I2015J-1162D01*
G01X917511Y250434D02*
G03X918832Y251222I-44J1575D01*
G01X917382Y250434D02*
X917511D01*
G01X915452Y249272D02*
G02X917382Y250434I2015J-1163D01*
G01X914146Y248485D02*
G03X915452Y249272I-59J1575D01*
G01X912539Y248485D02*
X914146D01*
G01X911376Y247322D02*
X912539Y248485D01*
G01X911376Y240222D02*
Y247322D01*
G01X910995Y239841D02*
X911376Y240222D01*
G01X969643Y219410D02*
G02X969741Y218869I-1444J-541D01*
G01X969506Y219689D02*
G02X969643Y219410I-1351J-836D01*
G01X969531Y221972D02*
G03X969506Y219689I2015J-1164D01*
G01X969550Y223513D02*
G02X969531Y221972I-1384J-754D01*
G01Y223547D02*
X969550Y223513D01*
G01X969506Y223589D02*
X969531Y223547D01*
G01Y225872D02*
G03X969506Y223589I2015J-1164D01*
G01X969550Y227413D02*
G02X969531Y225872I-1384J-754D01*
G01Y227447D02*
X969550Y227413D01*
G01X969506Y229730D02*
G03X969531Y227447I2040J-1119D01*
G01Y229772D02*
X969506Y229730D01*
G01X969531Y231346D02*
G02Y229772I-1365J-787D01*
G01Y233672D02*
G03Y231346I2015J-1163D01*
G01X969550Y235213D02*
G02X969531Y233672I-1384J-754D01*
G01Y235247D02*
X969550Y235213D01*
G01X969506Y235289D02*
X969531Y235247D01*
G01Y237572D02*
G03X969506Y235289I2015J-1164D01*
G01X969550Y239113D02*
G02X969531Y237572I-1384J-754D01*
G01Y239147D02*
X969550Y239113D01*
G01X969506Y239189D02*
X969531Y239147D01*
G01Y241472D02*
G03X969506Y239189I2015J-1164D01*
G01X969550Y243013D02*
G02X969531Y241472I-1384J-754D01*
G01Y243047D02*
X969550Y243013D01*
G01X969506Y243089D02*
X969531Y243047D01*
G01Y245372D02*
G03X969506Y243089I2015J-1164D01*
G01X969550Y246913D02*
G02X969531Y245372I-1384J-754D01*
G01Y246947D02*
X969550Y246913D01*
G01X969506Y246989D02*
X969531Y246947D01*
G01Y249272D02*
G03X969506Y246989I2015J-1164D01*
G01X969550Y250813D02*
G02X969531Y249272I-1384J-754D01*
G01Y250847D02*
X969550Y250813D01*
G01X969506Y250889D02*
X969531Y250847D01*
G01Y253172D02*
G03X969506Y250889I2015J-1164D01*
G01X969550Y254713D02*
G02X969531Y253172I-1384J-754D01*
G01Y254747D02*
X969550Y254713D01*
G01X969506Y254789D02*
X969531Y254747D01*
G01Y257072D02*
G03X969506Y254789I2015J-1164D01*
G01X969550Y258613D02*
G02X969531Y257072I-1384J-754D01*
G01Y258647D02*
X969550Y258613D01*
G01X969506Y258689D02*
X969531Y258647D01*
G01Y260972D02*
G03X969506Y258689I2018J-1164D01*
G01X969531Y262546D02*
G02Y260972I-1365J-787D01*
G01X969506Y262589D02*
G03X969531Y262546I896J492D01*
G01X969414Y264642D02*
G03X969506Y262589I2131J-933D01*
G01X969320Y264994D02*
X969414Y264642D01*
G01X968166Y265660D02*
X969320Y264994D01*
G01X924297Y218484D02*
X923089D01*
G01X926101Y219430D02*
G02X924297Y218484I-1873J1379D01*
G01X926242Y219647D02*
G02X926101Y219430I-2830J1684D01*
G01X926267Y219689D02*
X926242Y219647D01*
G01Y221972D02*
G02X926267Y219689I-2015J-1164D01*
G01X926242Y223546D02*
G03Y221972I1365J-787D01*
G01Y225872D02*
G02Y223546I-2015J-1163D01*
G01Y227446D02*
G03Y225872I1365J-787D01*
G01Y229772D02*
G02Y227446I-2015J-1163D01*
G01Y231346D02*
G03Y229772I1365J-787D01*
G01Y233672D02*
G02Y231346I-2015J-1163D01*
G01Y235246D02*
G03Y233672I1365J-787D01*
G01Y237572D02*
G02Y235246I-2015J-1163D01*
G01X927563Y239934D02*
G03X926242Y237572I44J-1575D01*
G01X928909Y239934D02*
X927563D01*
G01X930484Y238359D02*
X928909Y239934D01*
G01X934367Y238359D02*
X930484D01*
G01X934367Y238360D02*
Y238359D01*
G01X912842Y267985D02*
X911506Y269321D01*
G01X914444Y267985D02*
X912842D01*
G01X915295Y268761D02*
G02X914444Y267985I-1508J799D01*
G01X916667Y269934D02*
G03X915295Y268761I800J-2325D01*
G01X917511Y269934D02*
X916667D01*
G01X918832Y270722D02*
G02X917511Y269934I-1365J787D01*
G01X920777Y271885D02*
G03X918832Y270722I70J-2325D01*
G01X920906Y271885D02*
X920777D01*
G01X922212Y272672D02*
G02X920906Y271885I-1365J788D01*
G01X924142Y273834D02*
G03X922212Y272672I85J-2325D01*
G01X924312Y273834D02*
X924142D01*
G01X926242Y272672D02*
G03X924312Y273834I-2015J-1163D01*
G01X927548Y271885D02*
G02X926242Y272672I59J1575D01*
G01X927677Y271885D02*
X927548D01*
G01X929622Y270722D02*
G03X927677Y271885I-2015J-1162D01*
G01X929690Y270605D02*
X929622Y270722D01*
G01X930131Y269891D02*
X929690Y270605D01*
G01X930987Y267609D02*
X930131Y269891D01*
G01X927555Y257926D02*
X927607Y257860D01*
G01X924890Y258234D02*
X927555Y257926D01*
G01X924142Y258234D02*
X924890D01*
G01X922212Y257072D02*
G02X924142Y258234I2015J-1163D01*
G01X920906Y256285D02*
G03X922212Y257072I-59J1575D01*
G01X920777Y256285D02*
X920906D01*
G01X918832Y255122D02*
G02X920777Y256285I2015J-1162D01*
G01X917511Y254334D02*
G03X918832Y255122I-44J1575D01*
G01X916667Y254334D02*
X917511D01*
G01X915295Y253161D02*
G02X916667Y254334I2172J-1152D01*
G01X914444Y252385D02*
G03X915295Y253161I-657J1575D01*
G01X911369Y252385D02*
X914444D01*
G01X927749Y256285D02*
X930987Y255909D01*
G01X927548Y256285D02*
X927749D01*
G01X926513Y256726D02*
G03X927548Y256285I1095J1134D01*
G01X924683Y257484D02*
G02X926513Y256726I0J-2588D01*
G01X924168Y257484D02*
X924683D01*
G01X922862Y256697D02*
G02X924168Y257484I1365J-788D01*
G01X920932Y255535D02*
G03X922862Y256697I-85J2325D01*
G01X920803Y255535D02*
X920932D01*
G01X919482Y254747D02*
G02X920803Y255535I1365J-787D01*
G01X917537Y253584D02*
G03X919482Y254747I-70J2325D01*
G01X916810Y253584D02*
X917537D01*
G01X915959Y252808D02*
G02X916810Y253584I1508J-799D01*
G01X914587Y251635D02*
G03X915959Y252808I-800J2325D01*
G01X911680Y251635D02*
X914587D01*
G01X929833Y237075D02*
X930987Y236409D01*
G01X929523Y236991D02*
X929833Y237075D01*
G01X929603Y235656D02*
G02X929523Y236991I1385J753D01*
G01X929622Y235622D02*
X929603Y235656D01*
G01X929647Y235580D02*
X929622Y235622D01*
G01Y233297D02*
G03X929647Y235580I-2015J1164D01*
G01X929603Y231756D02*
G02X929622Y233297I1384J754D01*
G01Y231722D02*
X929603Y231756D01*
G01X929647Y229439D02*
G03X929622Y231722I-2040J1119D01*
G01Y229397D02*
X929647Y229439D01*
G01X929622Y227823D02*
G02Y229397I1365J787D01*
G01Y225497D02*
G03Y227823I-2015J1163D01*
G01X929603Y223956D02*
G02X929622Y225497I1384J754D01*
G01Y223922D02*
X929603Y223956D01*
G01X929647Y223880D02*
X929622Y223922D01*
G01Y221597D02*
G03X929647Y223880I-2015J1164D01*
G01X929603Y220056D02*
G02X929622Y221597I1384J754D01*
G01Y220022D02*
X929603Y220056D01*
G01X929647Y219980D02*
X929622Y220022D01*
G01X933277Y271920D02*
X934367Y269560D01*
G01X931072Y273834D02*
G02X933277Y271920I-85J-2325D01*
G01X930943Y273834D02*
X931072D01*
G01X929622Y274622D02*
G03X930943Y273834I1365J787D01*
G01X927677Y275785D02*
G02X929622Y274622I-70J-2325D01*
G01X927548Y275785D02*
X927677D01*
G01X926242Y276572D02*
G03X927548Y275785I1365J788D01*
G01X922212Y276572D02*
G02X926242I2015J-1163D01*
G01X920906Y275785D02*
G03X922212Y276572I-59J1575D01*
G01X919911Y275785D02*
X920906D01*
G01X918683Y274724D02*
G02X919911Y275785I2164J-1264D01*
G01X917798Y273971D02*
G03X918683Y274724I-631J1638D01*
G01X917289Y273934D02*
X917798Y273971D01*
G01X916963Y273934D02*
X917289D01*
G01X916112Y273935D02*
X916963Y273934D01*
G01X915786Y274261D02*
X916112Y273935D01*
G01X934509Y248485D02*
X937747Y248109D01*
G01X934308Y248485D02*
X934509D01*
G01X933002Y249272D02*
G03X934308Y248485I1365J788D01*
G01X931072Y250434D02*
G02X933002Y249272I-85J-2325D01*
G01X930943Y250434D02*
X931072D01*
G01X929622Y251222D02*
G03X930943Y250434I1365J787D01*
G01X927677Y252385D02*
G02X929622Y251222I-70J-2325D01*
G01X927548Y252385D02*
X927677D01*
G01X926631Y252723D02*
G03X927548Y252385I977J1237D01*
G01X925481Y253297D02*
X926631Y252723D01*
G01X924606Y253584D02*
X925481Y253297D01*
G01X924168Y253584D02*
X924606D01*
G01X922862Y252797D02*
G02X924168Y253584I1365J-788D01*
G01X920932Y251635D02*
G03X922862Y252797I-85J2325D01*
G01X920803Y251635D02*
X920932D01*
G01X919482Y250847D02*
G02X920803Y251635I1365J-787D01*
G01X917537Y249684D02*
G03X919482Y250847I-70J2325D01*
G01X917408Y249684D02*
X917537D01*
G01X916102Y248897D02*
G02X917408Y249684I1365J-788D01*
G01X914172Y247735D02*
G03X916102Y248897I-85J2325D01*
G01X912850Y247735D02*
X914172D01*
G01X912126Y247011D02*
X912850Y247735D01*
G01X912126Y239861D02*
Y247011D01*
G01X911081Y238816D02*
X912126Y239861D01*
G01X911081Y237484D02*
Y238816D01*
G01X956662Y220022D02*
X956697Y219962D01*
G01X956662Y221596D02*
G03Y220022I1364J-787D01*
G01X956697Y223862D02*
G02X956662Y221596I-2050J-1102D01*
G01Y223922D02*
X956697Y223862D01*
G01X956662Y225496D02*
G03Y223922I1364J-787D01*
G01X956687Y227781D02*
G02X956662Y225496I-2040J-1120D01*
G01Y227823D02*
X956687Y227781D01*
G01X956662Y229397D02*
G03Y227823I1364J-787D01*
G01X956687Y229439D02*
X956662Y229397D01*
G01Y231722D02*
G02X956687Y229439I-2015J-1164D01*
G01X956662Y233296D02*
G03Y231722I1364J-787D01*
G01X956697Y235562D02*
G02X956662Y233296I-2050J-1102D01*
G01Y235622D02*
X956697Y235562D01*
G01X956662Y237196D02*
G03Y235622I1364J-787D01*
G01X956697Y239462D02*
G02X956662Y237196I-2050J-1102D01*
G01Y239522D02*
X956697Y239462D01*
G01X956662Y241096D02*
G03Y239522I1364J-787D01*
G01X956697Y243362D02*
G02X956662Y241096I-2050J-1102D01*
G01Y243422D02*
X956697Y243362D01*
G01X956662Y244996D02*
G03Y243422I1364J-787D01*
G01X956697Y247262D02*
G02X956662Y244996I-2050J-1102D01*
G01Y247322D02*
X956697Y247262D01*
G01X956662Y248896D02*
G03Y247322I1364J-787D01*
G01X956697Y251162D02*
G02X956662Y248896I-2050J-1102D01*
G01Y251222D02*
X956697Y251162D01*
G01X956662Y252796D02*
G03Y251222I1364J-787D01*
G01X956697Y255062D02*
G02X956662Y252796I-2050J-1102D01*
G01Y255122D02*
X956697Y255062D01*
G01X956662Y256696D02*
G03Y255122I1364J-787D01*
G01X956697Y258962D02*
G02X956662Y256696I-2050J-1102D01*
G01Y259022D02*
X956697Y258962D01*
G01X956662Y260596D02*
G03Y259022I1364J-787D01*
G01Y262922D02*
G02Y260596I-2015J-1163D01*
G01Y264496D02*
G03Y262922I1364J-787D01*
G01X958625Y266135D02*
G03X956662Y264496I1191J-3422D01*
G01X958634Y266138D02*
X958625Y266135D01*
G01X959106Y268756D02*
G02X958634Y266138I-1088J-1155D01*
G01X958200Y271065D02*
X959106Y268756D01*
G01X958026Y271509D02*
X958200Y271065D01*
G01X935798Y266331D02*
X937747Y263709D01*
G01X935732Y266447D02*
X935798Y266331D01*
G01X933511Y266983D02*
G02X935732Y266447I856J-1323D01*
G01X931356Y266034D02*
X933511Y266983D01*
G01X930943Y266034D02*
X931356D01*
G01X929413Y267686D02*
G03X930943Y266034I1574J-77D01*
G01X929186Y269976D02*
X929413Y267686D01*
G01X928972Y270347D02*
X929186Y269976D01*
G01X927651Y271135D02*
G02X928972Y270347I-44J-1575D01*
G01X927522Y271135D02*
X927651D01*
G01X925592Y272297D02*
G03X927522Y271135I2015J1163D01*
G01X924286Y273084D02*
G02X925592Y272297I-59J-1575D01*
G01X924168Y273084D02*
X924286D01*
G01X922862Y272297D02*
G02X924168Y273084I1365J-788D01*
G01X920932Y271135D02*
G03X922862Y272297I-85J2325D01*
G01X920803Y271135D02*
X920932D01*
G01X919482Y270347D02*
G02X920803Y271135I1365J-787D01*
G01X917537Y269184D02*
G03X919482Y270347I-70J2325D01*
G01X916810Y269184D02*
X917537D01*
G01X915959Y268408D02*
G02X916810Y269184I1508J-799D01*
G01X914587Y267235D02*
G03X915959Y268408I-800J2325D01*
G01X911920Y267235D02*
X914587D01*
G01X911506Y266821D02*
X911920Y267235D01*
G01X959391Y220022D02*
X959366Y219980D01*
G01X959410Y220056D02*
X959391Y220022D01*
G01Y221597D02*
G02X959410Y220056I-1365J-787D01*
G01X959366Y223880D02*
G03X959391Y221597I2040J-1119D01*
G01Y223922D02*
X959366Y223880D01*
G01X959410Y223956D02*
X959391Y223922D01*
G01Y225497D02*
G02X959410Y223956I-1365J-787D01*
G01X959391Y227823D02*
G03Y225497I2015J-1163D01*
G01Y229397D02*
G02Y227823I-1365J-787D01*
G01X959366Y229439D02*
X959391Y229397D01*
G01Y231722D02*
G03X959366Y229439I2015J-1164D01*
G01X959410Y231756D02*
X959391Y231722D01*
G01Y233297D02*
G02X959410Y231756I-1365J-787D01*
G01X959366Y235580D02*
G03X959391Y233297I2040J-1119D01*
G01Y235622D02*
X959366Y235580D01*
G01X959410Y235656D02*
X959391Y235622D01*
G01Y237197D02*
G02X959410Y235656I-1365J-787D01*
G01X959366Y239480D02*
G03X959391Y237197I2040J-1119D01*
G01Y239522D02*
X959366Y239480D01*
G01X959410Y239556D02*
X959391Y239522D01*
G01Y241097D02*
G02X959410Y239556I-1365J-787D01*
G01X959366Y243380D02*
G03X959391Y241097I2040J-1119D01*
G01Y243422D02*
X959366Y243380D01*
G01X959410Y243456D02*
X959391Y243422D01*
G01Y244997D02*
G02X959410Y243456I-1365J-787D01*
G01X959366Y247280D02*
G03X959391Y244997I2040J-1119D01*
G01Y247322D02*
X959366Y247280D01*
G01X959410Y247356D02*
X959391Y247322D01*
G01Y248897D02*
G02X959410Y247356I-1365J-787D01*
G01X959366Y251180D02*
G03X959391Y248897I2040J-1119D01*
G01Y251222D02*
X959366Y251180D01*
G01X959410Y251256D02*
X959391Y251222D01*
G01Y252797D02*
G02X959410Y251256I-1365J-787D01*
G01X959366Y255080D02*
G03X959391Y252797I2040J-1119D01*
G01Y255122D02*
X959366Y255080D01*
G01X959410Y255156D02*
X959391Y255122D01*
G01Y256697D02*
G02X959410Y255156I-1365J-787D01*
G01X959366Y258980D02*
G03X959391Y256697I2040J-1119D01*
G01Y259022D02*
X959366Y258980D01*
G01X959410Y259056D02*
X959391Y259022D01*
G01Y260596D02*
G02X959410Y259056I-1363J-787D01*
G01X959391Y262922D02*
G03Y260596I2015J-1163D01*
G01X959407Y262950D02*
X959391Y262922D01*
G01X960498Y264585D02*
G03X959407Y262950I12078J-9241D01*
G01X961406Y265660D02*
G03X960498Y264585I10671J-9934D01*
G01X929038Y250731D02*
X930987Y248109D01*
G01X928972Y250847D02*
X929038Y250731D01*
G01X926463Y251143D02*
G02X928972Y250847I1144J-1083D01*
G01X926406Y251087D02*
X926463Y251143D01*
G01X924831Y250434D02*
G03X926406Y251087I-1J2228D01*
G01X924142Y250434D02*
X924831D01*
G01X922212Y249272D02*
G02X924142Y250434I2015J-1163D01*
G01X920906Y248485D02*
G03X922212Y249272I-59J1575D01*
G01X920777Y248485D02*
X920906D01*
G01X918832Y247322D02*
G02X920777Y248485I2015J-1162D01*
G01X917511Y246534D02*
G03X918832Y247322I-44J1575D01*
G01X917382Y246534D02*
X917511D01*
G01X915427Y243089D02*
G02X917382Y246534I2040J1120D01*
G01X915452Y243047D02*
X915427Y243089D01*
G01X915471Y243013D02*
X915452Y243047D01*
G01Y241472D02*
G03X915471Y243013I-1365J787D01*
G01X915427Y239189D02*
G02X915452Y241472I2040J1119D01*
G01Y239147D02*
X915427Y239189D01*
G01X915471Y239113D02*
X915452Y239147D01*
G01Y237572D02*
G03X915471Y239113I-1365J787D01*
G01X914890Y236598D02*
X915452Y237572D01*
G01X914677Y236385D02*
X914890Y236598D01*
G01X913532Y236385D02*
X914677D01*
G01X969345Y270754D02*
X968166Y273460D01*
G01X969531Y270346D02*
G02X969345Y270754I2014J1165D01*
G01X969718Y269289D02*
G03X969531Y270346I-1552J270D01*
G01X970181Y266822D02*
G02X969718Y269289I3278J1892D01*
G01X970181Y264496D02*
G03Y266822I-2015J1163D01*
G01Y262922D02*
G02Y264496I1365J787D01*
G01Y260596D02*
G03Y262922I-2015J1163D01*
G01X970162Y259056D02*
G02X970181Y260596I1382J753D01*
G01Y259022D02*
X970162Y259056D01*
G01X970206Y258980D02*
X970181Y259022D01*
G01Y256697D02*
G03X970206Y258980I-2015J1164D01*
G01X970162Y255156D02*
G02X970181Y256697I1384J754D01*
G01Y255122D02*
X970162Y255156D01*
G01X970206Y255080D02*
X970181Y255122D01*
G01Y252797D02*
G03X970206Y255080I-2015J1164D01*
G01X970162Y251256D02*
G02X970181Y252797I1384J754D01*
G01Y251222D02*
X970162Y251256D01*
G01X970206Y251180D02*
X970181Y251222D01*
G01Y248897D02*
G03X970206Y251180I-2015J1164D01*
G01X970162Y247356D02*
G02X970181Y248897I1384J754D01*
G01Y247322D02*
X970162Y247356D01*
G01X970206Y247280D02*
X970181Y247322D01*
G01Y244997D02*
G03X970206Y247280I-2015J1164D01*
G01X970162Y243456D02*
G02X970181Y244997I1384J754D01*
G01Y243422D02*
X970162Y243456D01*
G01X970206Y243380D02*
X970181Y243422D01*
G01Y241097D02*
G03X970206Y243380I-2015J1164D01*
G01X970162Y239556D02*
G02X970181Y241097I1384J754D01*
G01Y239522D02*
X970162Y239556D01*
G01X970206Y239480D02*
X970181Y239522D01*
G01Y237197D02*
G03X970206Y239480I-2015J1164D01*
G01X970162Y235656D02*
G02X970181Y237197I1384J754D01*
G01Y235622D02*
X970162Y235656D01*
G01X970206Y235580D02*
X970181Y235622D01*
G01Y233297D02*
G03X970206Y235580I-2015J1164D01*
G01X970162Y231756D02*
G02X970181Y233297I1384J754D01*
G01Y231722D02*
X970162Y231756D01*
G01X970206Y229439D02*
G03X970181Y231722I-2040J1119D01*
G01Y229397D02*
X970206Y229439D01*
G01X970181Y227823D02*
G02Y229397I1365J787D01*
G01Y225497D02*
G03Y227823I-2015J1163D01*
G01X970162Y223956D02*
G02X970181Y225497I1384J754D01*
G01Y223922D02*
X970162Y223956D01*
G01X970206Y223880D02*
X970181Y223922D01*
G01Y221597D02*
G03X970206Y223880I-2015J1164D01*
G01X970180Y221598D02*
X970181Y221597D01*
G01X970162Y220052D02*
G02X970180Y221598I1384J757D01*
G01X970352Y219658D02*
G03X970162Y220052I-2058J-750D01*
G01X970491Y218870D02*
G03X970352Y219658I-2301J0D01*
G01X972811Y268862D02*
X971546Y271509D01*
G01X927607Y242259D02*
Y242260D01*
G01X925592Y239522D02*
G02X927607Y242259I13269J-7658D01*
G01X925592Y237196D02*
G02Y239522I2015J1163D01*
G01Y235622D02*
G03Y237196I-1365J787D01*
G01Y233296D02*
G02Y235622I2015J1163D01*
G01Y231722D02*
G03Y233296I-1365J787D01*
G01Y229396D02*
G02Y231722I2015J1163D01*
G01Y227822D02*
G03Y229396I-1365J787D01*
G01Y225496D02*
G02Y227822I2015J1163D01*
G01Y223922D02*
G03Y225496I-1365J787D01*
G01Y221596D02*
G02Y223922I2015J1163D01*
G01X925719Y221315D02*
G03X925592Y221596I-1500J-509D01*
G01X925611Y220056D02*
G03X925719Y221315I-1384J753D01*
G01X925592Y220022D02*
X925611Y220056D01*
G01X925464Y219834D02*
G03X925592Y220022I-999J818D01*
G01X924271Y219234D02*
G03X925464Y219834I-45J1575D01*
G01X923093Y219234D02*
X924271D01*
G01X922216Y220111D02*
X923093Y219234D01*
G01X921512Y318549D02*
X920364D01*
G01X923327Y316734D02*
X921512Y318549D01*
G01X924271Y316734D02*
X923327D01*
G01X925592Y317522D02*
G02X924271Y316734I-1365J787D01*
G01X927537Y318685D02*
G03X925592Y317522I70J-2325D01*
G01X927677Y318685D02*
X927537D01*
G01X929622Y317522D02*
G03X927677Y318685I-2015J-1162D01*
G01X932352Y317522D02*
G02X929622I-1365J787D01*
G01X934297Y318685D02*
G03X932352Y317522I70J-2325D01*
G01X934437Y318685D02*
X934297D01*
G01X936382Y317522D02*
G03X934437Y318685I-2015J-1162D01*
G01X939112Y317522D02*
G02X936382I-1365J787D01*
G01X941057Y318685D02*
G03X939112Y317522I70J-2325D01*
G01X941186Y318685D02*
X941057D01*
G01X942492Y319472D02*
G02X941186Y318685I-1365J788D01*
G01X944422Y320634D02*
G03X942492Y319472I85J-2325D01*
G01X944592Y320634D02*
X944422D01*
G01X946522Y319472D02*
G03X944592Y320634I-2015J-1163D01*
G01X947828Y318685D02*
G02X946522Y319472I59J1575D01*
G01X947946Y318685D02*
X947828D01*
G01X949252Y319472D02*
G02X947946Y318685I-1365J788D01*
G01X951182Y320634D02*
G03X949252Y319472I85J-2325D01*
G01X951352Y320634D02*
X951182D01*
G01X953282Y319472D02*
G03X951352Y320634I-2015J-1163D01*
G01X955998Y319450D02*
G02X953282Y319472I-1352J810D01*
G01X956011Y319473D02*
X955998Y319450D01*
G01X957928Y320634D02*
G03X956011Y319473I98J-2325D01*
G01X958070Y320634D02*
X957928D01*
G01X959391Y321422D02*
G02X958070Y320634I-1365J787D01*
G01X961336Y322585D02*
G03X959391Y321422I70J-2325D01*
G01X961476Y322585D02*
X961336D01*
G01X963421Y321422D02*
G03X961476Y322585I-2015J-1162D01*
G01X964742Y320634D02*
G02X963421Y321422I44J1575D01*
G01X964871Y320634D02*
X964742D01*
G01X966801Y319472D02*
G03X964871Y320634I-2015J-1163D01*
G01X968107Y318685D02*
G02X966801Y319472I59J1575D01*
G01X968225Y318685D02*
X968107D01*
G01X969531Y319472D02*
G02X968225Y318685I-1365J788D01*
G01X971461Y320634D02*
G03X969531Y319472I85J-2325D01*
G01X971590Y320634D02*
X971461D01*
G01X972911Y321422D02*
G02X971590Y320634I-1365J787D01*
G01X961406Y331960D02*
X960107Y334959D01*
G01X960066Y340589D02*
G03X960041Y342872I-2040J1119D01*
G01Y340547D02*
X960066Y340589D01*
G01X960022Y340513D02*
X960041Y340547D01*
G01Y338972D02*
G02X960022Y340513I1365J787D01*
G01X960066Y336689D02*
G03X960041Y338972I-2040J1119D01*
G01Y336647D02*
X960066Y336689D01*
G01X960022Y336613D02*
X960041Y336647D01*
G01Y335072D02*
G02X960022Y336613I1365J787D01*
G01X960107Y334959D02*
X960041Y335072D01*
G01X915452Y340547D02*
G03X914131Y341335I-1365J-787D01*
G01X917397Y339384D02*
G02X915452Y340547I70J2325D01*
G01X917526Y339384D02*
X917397D01*
G01X918832Y338597D02*
G03X917526Y339384I-1365J-788D01*
G01X920762Y337435D02*
G02X918832Y338597I85J2325D01*
G01X920891Y337435D02*
X920762D01*
G01X922212Y336647D02*
G03X920891Y337435I-1365J-787D01*
G01X924157Y335484D02*
G02X922212Y336647I70J2325D01*
G01X924286Y335484D02*
X924157D01*
G01X925592Y334697D02*
G03X924286Y335484I-1365J-788D01*
G01X926306Y334285D02*
G02X925592Y334697I0J825D01*
G01X927666Y334285D02*
X926306D01*
G01X928972Y335072D02*
G02X927666Y334285I-1365J788D01*
G01X930902Y336234D02*
G03X928972Y335072I85J-2325D01*
G01X931031Y336234D02*
X930902D01*
G01X932352Y337022D02*
G02X931031Y336234I-1365J787D01*
G01X932418Y337138D02*
X932352Y337022D01*
G01X934367Y339760D02*
X932418Y337138D01*
G01X922212Y340547D02*
G03X920891Y341335I-1365J-787D01*
G01X924157Y339384D02*
G02X922212Y340547I70J2325D01*
G01X924286Y339384D02*
X924157D01*
G01X925592Y338597D02*
G03X924286Y339384I-1365J-788D01*
G01X927522Y337435D02*
G02X925592Y338597I85J2325D01*
G01X927692Y337435D02*
X927522D01*
G01X929622Y338597D02*
G02X927692Y337435I-2015J1163D01*
G01X929688Y338710D02*
X929622Y338597D01*
G01X930987Y341709D02*
X929688Y338710D01*
G01X971616Y308184D02*
G03X973561Y309347I-70J2325D01*
G01X971487Y308184D02*
X971616D01*
G01X970181Y307397D02*
G02X971487Y308184I1365J-788D01*
G01X968251Y306235D02*
G03X970181Y307397I-85J2325D01*
G01X968081Y306235D02*
X968251D01*
G01X966151Y307397D02*
G03X968081Y306235I2015J1163D01*
G01X964845Y308184D02*
G02X966151Y307397I-59J-1575D01*
G01X964716Y308184D02*
X964845D01*
G01X962771Y309347D02*
G03X964716Y308184I2015J1162D01*
G01X961450Y310135D02*
G02X962771Y309347I-44J-1575D01*
G01X961362Y310135D02*
X961450D01*
G01X960041Y309347D02*
G02X961362Y310135I1365J-787D01*
G01X958096Y308184D02*
G03X960041Y309347I-70J2325D01*
G01X958026Y308184D02*
X958096D01*
G01X956675Y307419D02*
G02X958026Y308184I1351J-810D01*
G01X956662Y307396D02*
X956675Y307419D01*
G01X954745Y306235D02*
G03X956662Y307396I-98J2325D01*
G01X954562Y306235D02*
X954745D01*
G01X952632Y307397D02*
G03X954562Y306235I2015J1163D01*
G01X951326Y308184D02*
G02X952632Y307397I-59J-1575D01*
G01X951208Y308184D02*
X951326D01*
G01X949902Y307397D02*
G02X951208Y308184I1365J-788D01*
G01X947972Y306235D02*
G03X949902Y307397I-85J2325D01*
G01X947802Y306235D02*
X947972D01*
G01X945872Y307397D02*
G03X947802Y306235I2015J1163D01*
G01X944566Y308184D02*
G02X945872Y307397I-59J-1575D01*
G01X944448Y308184D02*
X944566D01*
G01X943142Y307397D02*
G02X944448Y308184I1365J-788D01*
G01X941212Y306235D02*
G03X943142Y307397I-85J2325D01*
G01X941083Y306235D02*
X941212D01*
G01X939762Y305447D02*
G02X941083Y306235I1365J-787D01*
G01X935732Y305447D02*
G03X939762I2015J1162D01*
G01X934411Y306235D02*
G02X935732Y305447I-44J-1575D01*
G01X934323Y306235D02*
X934411D01*
G01X933002Y305447D02*
G02X934323Y306235I1365J-787D01*
G01X931057Y304284D02*
G03X933002Y305447I-70J2325D01*
G01X930917Y304284D02*
X931057D01*
G01X928972Y305447D02*
G03X930917Y304284I2015J1162D01*
G01X927651Y306235D02*
G02X928972Y305447I-44J-1575D01*
G01X927563Y306235D02*
X927651D01*
G01X926242Y305447D02*
G02X927563Y306235I1365J-787D01*
G01X924297Y304284D02*
G03X926242Y305447I-70J2325D01*
G01X923368Y304284D02*
X924297D01*
G01X922031Y305460D02*
G03X923368Y304284I2196J1149D01*
G01X921259Y306232D02*
X922031Y305460D01*
G01X918779Y306232D02*
X921259D01*
G01X917613Y307398D02*
X918779Y306232D01*
G01X912970Y326485D02*
X910466Y328989D01*
G01X914562Y326485D02*
X912970D01*
G01X914867Y326790D02*
X914562Y326485D01*
G01X915295Y327261D02*
X914867Y326790D01*
G01X916669Y328435D02*
G03X915295Y327261I798J-2325D01*
G01X917552Y328435D02*
X916669D01*
G01X919482Y327273D02*
G03X917552Y328435I-2015J-1163D01*
G01X920803Y326485D02*
G02X919482Y327273I44J1575D01*
G01X920932Y326485D02*
X920803D01*
G01X922862Y325323D02*
G03X920932Y326485I-2015J-1163D01*
G01X925592Y325323D02*
G02X922862I-1365J787D01*
G01X927522Y326485D02*
G03X925592Y325323I85J-2325D01*
G01X927651Y326485D02*
X927522D01*
G01X928972Y327273D02*
G02X927651Y326485I-1365J787D01*
G01X929037Y327387D02*
X928972Y327273D01*
G01X930987Y330009D02*
X929037Y327387D01*
G01X915083Y323429D02*
X910277D01*
G01X916188Y324534D02*
X915083Y323429D01*
G01X917539Y324534D02*
X916188D01*
G01X919482Y323372D02*
G03X917539Y324534I-2015J-1163D01*
G01X920788Y322585D02*
G02X919482Y323372I59J1575D01*
G01X920917Y322585D02*
X920788D01*
G01X922862Y321422D02*
G03X920917Y322585I-2015J-1162D01*
G01X925592Y321422D02*
G02X922862I-1365J787D01*
G01X927537Y322585D02*
G03X925592Y321422I70J-2325D01*
G01X927666Y322585D02*
X927537D01*
G01X928972Y323372D02*
G02X927666Y322585I-1365J788D01*
G01X930936Y324535D02*
G03X928972Y323372I51J-2326D01*
G01X931031Y324535D02*
X930936D01*
G01X932352Y325323D02*
G02X931031Y324535I-1365J787D01*
G01X932417Y325436D02*
X932352Y325323D01*
G01X934367Y328060D02*
X932417Y325436D01*
G01X959410Y340956D02*
G03X959391Y342497I-1384J754D01*
G01Y340922D02*
X959410Y340956D01*
G01X959366Y340880D02*
X959391Y340922D01*
G01Y338597D02*
G02X959366Y340880I2015J1164D01*
G01X959410Y337056D02*
G03X959391Y338597I-1384J754D01*
G01Y337022D02*
X959410Y337056D01*
G01X959366Y336980D02*
X959391Y337022D01*
G01Y334697D02*
G02X959366Y336980I2015J1164D01*
G01X959410Y333156D02*
G03X959391Y334697I-1384J754D01*
G01Y333122D02*
X959410Y333156D01*
G01X959366Y333080D02*
X959391Y333122D01*
G01Y330797D02*
G02X959366Y333080I2015J1164D01*
G01X959457Y330681D02*
X959391Y330797D01*
G01X961406Y328060D02*
X959457Y330681D01*
G01X963402Y340956D02*
G02X963421Y342497I1384J754D01*
G01Y340922D02*
X963402Y340956D01*
G01X963446Y340880D02*
X963421Y340922D01*
G01Y338597D02*
G03X963446Y340880I-2015J1164D01*
G01X963402Y337056D02*
G02X963421Y338597I1384J754D01*
G01X963489Y336905D02*
X963402Y337056D01*
G01X964786Y333909D02*
X963489Y336905D01*
G01X915396Y322681D02*
X910327D01*
G01X916499Y323784D02*
X915396Y322681D01*
G01X917526Y323784D02*
X916499D01*
G01X918832Y322997D02*
G03X917526Y323784I-1365J-788D01*
G01X920762Y321835D02*
G02X918832Y322997I85J2325D01*
G01X920891Y321835D02*
X920762D01*
G01X922212Y321047D02*
G03X920891Y321835I-1365J-787D01*
G01X924157Y319884D02*
G02X922212Y321047I70J2325D01*
G01X924297Y319884D02*
X924157D01*
G01X926242Y321047D02*
G02X924297Y319884I-2015J1162D01*
G01X927563Y321835D02*
G03X926242Y321047I44J-1575D01*
G01X927692Y321835D02*
X927563D01*
G01X929622Y322997D02*
G02X927692Y321835I-2015J1163D01*
G01X930928Y323784D02*
G03X929622Y322997I59J-1575D01*
G01X931038Y323784D02*
X930928D01*
G01X933002Y324947D02*
G02X931038Y323784I-2015J1163D01*
G01X934323Y325735D02*
G03X933002Y324947I44J-1575D01*
G01X934452Y325735D02*
X934323D01*
G01X936382Y326897D02*
G02X934452Y325735I-2015J1163D01*
G01X936447Y327009D02*
X936382Y326897D01*
G01X937747Y330009D02*
X936447Y327009D01*
G01X970162Y333156D02*
G02X970904Y335348I1384J753D01*
G01X970181Y333122D02*
X970162Y333156D01*
G01X970206Y333080D02*
X970181Y333122D01*
G01Y330797D02*
G03X970206Y333080I-2015J1164D01*
G01X970162Y329256D02*
G02X970181Y330797I1384J754D01*
G01Y329222D02*
X970162Y329256D01*
G01X970248Y329107D02*
X970181Y329222D01*
G01X971546Y326110D02*
X970248Y329107D01*
G01X971536Y335693D02*
X972709Y336672D01*
G01X970904Y335348D02*
X971536Y335693D01*
G01X962746Y340589D02*
G02X962771Y342872I2040J1119D01*
G01Y340547D02*
X962746Y340589D01*
G01X962790Y340513D02*
X962771Y340547D01*
G01Y338972D02*
G03X962790Y340513I-1365J787D01*
G01X962746Y336689D02*
G02X962771Y338972I2040J1119D01*
G01Y336647D02*
X962746Y336689D01*
G01X962790Y336613D02*
X962771Y336647D01*
G01Y335072D02*
G03X962790Y336613I-1365J787D01*
G01X962746Y332789D02*
G02X962771Y335072I2040J1119D01*
G01Y332747D02*
X962746Y332789D01*
G01X962790Y332713D02*
X962771Y332747D01*
G01Y331172D02*
G03X962790Y332713I-1365J787D01*
G01X962746Y328889D02*
G02X962771Y331172I2040J1119D01*
G01Y328847D02*
X962746Y328889D01*
G01X962837Y328731D02*
X962771Y328847D01*
G01X964786Y326110D02*
X962837Y328731D01*
G01X971546Y333909D02*
G03X973216Y336041I-6368J6708D01*
G01X971590Y312834D02*
G03X972911Y313622I-44J1575D01*
G01X971461Y312834D02*
X971590D01*
G01X969531Y311672D02*
G02X971461Y312834I2015J-1163D01*
G01X968225Y310885D02*
G03X969531Y311672I-59J1575D01*
G01X968107Y310885D02*
X968225D01*
G01X966801Y311672D02*
G03X968107Y310885I1365J788D01*
G01X964871Y312834D02*
G02X966801Y311672I-85J-2325D01*
G01X964742Y312834D02*
X964871D01*
G01X963421Y313622D02*
G03X964742Y312834I1365J787D01*
G01X961476Y314785D02*
G02X963421Y313622I-70J-2325D01*
G01X961336Y314785D02*
X961476D01*
G01X959391Y313622D02*
G02X961336Y314785I2015J-1162D01*
G01X958070Y312834D02*
G03X959391Y313622I-44J1575D01*
G01X957928Y312834D02*
X958070D01*
G01X956011Y311673D02*
G02X957928Y312834I2015J-1164D01*
G01X955998Y311650D02*
X956011Y311673D01*
G01X954647Y310885D02*
G03X955998Y311650I0J1575D01*
G01X954588Y310885D02*
X954647D01*
G01X953282Y311672D02*
G03X954588Y310885I1365J788D01*
G01X951352Y312834D02*
G02X953282Y311672I-85J-2325D01*
G01X951182Y312834D02*
X951352D01*
G01X949252Y311672D02*
G02X951182Y312834I2015J-1163D01*
G01X947946Y310885D02*
G03X949252Y311672I-59J1575D01*
G01X947828Y310885D02*
X947946D01*
G01X946522Y311672D02*
G03X947828Y310885I1365J788D01*
G01X944592Y312834D02*
G02X946522Y311672I-85J-2325D01*
G01X944422Y312834D02*
X944592D01*
G01X942492Y311672D02*
G02X944422Y312834I2015J-1163D01*
G01X941186Y310885D02*
G03X942492Y311672I-59J1575D01*
G01X941057Y310885D02*
X941186D01*
G01X939112Y309722D02*
G02X941057Y310885I2015J-1162D01*
G01X937791Y308934D02*
G03X939112Y309722I-44J1575D01*
G01X937703Y308934D02*
X937791D01*
G01X936382Y309722D02*
G03X937703Y308934I1365J787D01*
G01X934437Y310885D02*
G02X936382Y309722I-70J-2325D01*
G01X934297Y310885D02*
X934437D01*
G01X932352Y309722D02*
G02X934297Y310885I2015J-1162D01*
G01X931031Y308934D02*
G03X932352Y309722I-44J1575D01*
G01X930943Y308934D02*
X931031D01*
G01X929622Y309722D02*
G03X930943Y308934I1365J787D01*
G01X927677Y310885D02*
G02X929622Y309722I-70J-2325D01*
G01X927537Y310885D02*
X927677D01*
G01X925592Y309722D02*
G02X927537Y310885I2015J-1162D01*
G01X924271Y308934D02*
G03X925592Y309722I-44J1575D01*
G01X923518Y308934D02*
X924271D01*
G01X922499Y310510D02*
G03X923518Y308934I1728J0D01*
G01X922499Y312344D02*
Y310510D01*
G01X921242Y313601D02*
X922499Y312344D01*
G01X971590Y316734D02*
G03X972911Y317522I-44J1575D01*
G01X971461Y316734D02*
X971590D01*
G01X969531Y315572D02*
G02X971461Y316734I2015J-1163D01*
G01X968225Y314785D02*
G03X969531Y315572I-59J1575D01*
G01X968107Y314785D02*
X968225D01*
G01X966801Y315572D02*
G03X968107Y314785I1365J788D01*
G01X964871Y316734D02*
G02X966801Y315572I-85J-2325D01*
G01X964742Y316734D02*
X964871D01*
G01X963421Y317522D02*
G03X964742Y316734I1365J787D01*
G01X961476Y318685D02*
G02X963421Y317522I-70J-2325D01*
G01X961336Y318685D02*
X961476D01*
G01X959391Y317522D02*
G02X961336Y318685I2015J-1162D01*
G01X958070Y316734D02*
G03X959391Y317522I-44J1575D01*
G01X957928Y316734D02*
X958070D01*
G01X956011Y315573D02*
G02X957928Y316734I2015J-1164D01*
G01X955998Y315550D02*
X956011Y315573D01*
G01X954647Y314785D02*
G03X955998Y315550I0J1575D01*
G01X954588Y314785D02*
X954647D01*
G01X953282Y315572D02*
G03X954588Y314785I1365J788D01*
G01X949252Y315572D02*
G02X953282I2015J-1163D01*
G01X947946Y314785D02*
G03X949252Y315572I-59J1575D01*
G01X947828Y314785D02*
X947946D01*
G01X946522Y315572D02*
G03X947828Y314785I1365J788D01*
G01X944592Y316734D02*
G02X946522Y315572I-85J-2325D01*
G01X944422Y316734D02*
X944592D01*
G01X942492Y315572D02*
G02X944422Y316734I2015J-1163D01*
G01X941186Y314785D02*
G03X942492Y315572I-59J1575D01*
G01X941057Y314785D02*
X941186D01*
G01X939112Y313622D02*
G02X941057Y314785I2015J-1162D01*
G01X937791Y312834D02*
G03X939112Y313622I-44J1575D01*
G01X937703Y312834D02*
X937791D01*
G01X936382Y313622D02*
G03X937703Y312834I1365J787D01*
G01X934437Y314785D02*
G02X936382Y313622I-70J-2325D01*
G01X934297Y314785D02*
X934437D01*
G01X932352Y313622D02*
G02X934297Y314785I2015J-1162D01*
G01X931031Y312834D02*
G03X932352Y313622I-44J1575D01*
G01X930943Y312834D02*
X931031D01*
G01X929622Y313622D02*
G03X930943Y312834I1365J787D01*
G01X927677Y314785D02*
G02X929622Y313622I-70J-2325D01*
G01X927537Y314785D02*
X927677D01*
G01X925592Y313622D02*
G02X927537Y314785I2015J-1162D01*
G01X924271Y312834D02*
G03X925592Y313622I-44J1575D01*
G01X923458Y312834D02*
X924271D01*
G01X921770Y314522D02*
X923458Y312834D01*
G01X918234Y314522D02*
X921770D01*
G01X922862Y340922D02*
G03X920917Y342085I-2015J-1162D01*
G01X924183Y340134D02*
G02X922862Y340922I44J1575D01*
G01X924373Y340134D02*
X924183D01*
G01X927607Y339760D02*
X924373Y340134D01*
G01X912660Y325737D02*
X910156Y328241D01*
G01X914882Y325737D02*
X912660D01*
G01X915530Y326385D02*
X914882Y325737D01*
G01X916407Y327394D02*
X915530Y326385D01*
G01X916808Y327684D02*
G03X916407Y327394I420J-1004D01*
G01X917538Y327684D02*
X916808D01*
G01X918832Y326897D02*
G03X917538Y327684I-1365J-787D01*
G01X920762Y325735D02*
G02X918832Y326897I85J2325D01*
G01X920891Y325735D02*
X920762D01*
G01X922212Y324947D02*
G03X920891Y325735I-1365J-787D01*
G01X926242Y324947D02*
G02X922212I-2015J1163D01*
G01X927563Y325735D02*
G03X926242Y324947I44J-1575D01*
G01X927692Y325735D02*
X927563D01*
G01X929622Y326897D02*
G02X927692Y325735I-2015J1163D01*
G01X930916Y327684D02*
G03X929622Y326897I71J-1574D01*
G01X931057Y327684D02*
X930916D01*
G01X933002Y328847D02*
G02X931057Y327684I-2015J1162D01*
G01X934323Y329635D02*
G03X933002Y328847I44J-1575D01*
G01X934452Y329635D02*
X934323D01*
G01X936382Y330797D02*
G02X934452Y329635I-2015J1163D01*
G01X936448Y330910D02*
X936382Y330797D01*
G01X937747Y333909D02*
X936448Y330910D01*
G01X916102Y340922D02*
G03X914157Y342085I-2015J-1162D01*
G01X917423Y340134D02*
G02X916102Y340922I44J1575D01*
G01X917552Y340134D02*
X917423D01*
G01X919482Y338972D02*
G03X917552Y340134I-2015J-1163D01*
G01X920788Y338185D02*
G02X919482Y338972I59J1575D01*
G01X920917Y338185D02*
X920788D01*
G01X922862Y337022D02*
G03X920917Y338185I-2015J-1162D01*
G01X924183Y336234D02*
G02X922862Y337022I44J1575D01*
G01X924373Y336234D02*
X924183D01*
G01X927607Y335860D02*
X924373Y336234D01*
G01X971590Y308934D02*
G03X972911Y309722I-44J1575D01*
G01X971461Y308934D02*
X971590D01*
G01X969531Y307772D02*
G02X971461Y308934I2015J-1163D01*
G01X968225Y306985D02*
G03X969531Y307772I-59J1575D01*
G01X968107Y306985D02*
X968225D01*
G01X966801Y307772D02*
G03X968107Y306985I1365J788D01*
G01X964871Y308934D02*
G02X966801Y307772I-85J-2325D01*
G01X964742Y308934D02*
X964871D01*
G01X963421Y309722D02*
G03X964742Y308934I1365J787D01*
G01X961476Y310885D02*
G02X963421Y309722I-70J-2325D01*
G01X961336Y310885D02*
X961476D01*
G01X959391Y309722D02*
G02X961336Y310885I2015J-1162D01*
G01X958070Y308934D02*
G03X959391Y309722I-44J1575D01*
G01X957928Y308934D02*
X958070D01*
G01X956011Y307773D02*
G02X957928Y308934I2015J-1164D01*
G01X955998Y307750D02*
X956011Y307773D01*
G01X954647Y306985D02*
G03X955998Y307750I0J1575D01*
G01X954588Y306985D02*
X954647D01*
G01X953282Y307772D02*
G03X954588Y306985I1365J788D01*
G01X951352Y308934D02*
G02X953282Y307772I-85J-2325D01*
G01X951182Y308934D02*
X951352D01*
G01X949252Y307772D02*
G02X951182Y308934I2015J-1163D01*
G01X947946Y306985D02*
G03X949252Y307772I-59J1575D01*
G01X947828Y306985D02*
X947946D01*
G01X946522Y307772D02*
G03X947828Y306985I1365J788D01*
G01X944592Y308934D02*
G02X946522Y307772I-85J-2325D01*
G01X944422Y308934D02*
X944592D01*
G01X942492Y307772D02*
G02X944422Y308934I2015J-1163D01*
G01X941186Y306985D02*
G03X942492Y307772I-59J1575D01*
G01X941057Y306985D02*
X941186D01*
G01X939112Y305822D02*
G02X941057Y306985I2015J-1162D01*
G01X936382Y305822D02*
G03X939112I1365J787D01*
G01X934437Y306985D02*
G02X936382Y305822I-70J-2325D01*
G01X934297Y306985D02*
X934437D01*
G01X932352Y305822D02*
G02X934297Y306985I2015J-1162D01*
G01X931031Y305034D02*
G03X932352Y305822I-44J1575D01*
G01X930943Y305034D02*
X931031D01*
G01X929622Y305822D02*
G03X930943Y305034I1365J787D01*
G01X927677Y306985D02*
G02X929622Y305822I-70J-2325D01*
G01X927537Y306985D02*
X927677D01*
G01X925592Y305822D02*
G02X927537Y306985I2015J-1162D01*
G01X924271Y305034D02*
G03X925592Y305822I-44J1575D01*
G01X923519Y305034D02*
X924271D01*
G01X923518Y305033D02*
X923519Y305034D01*
G01X923515Y305033D02*
X923518D01*
G01X922695Y305807D02*
G03X923515Y305033I1532J802D01*
G01X922642Y305909D02*
X922695Y305807D01*
G01X921570Y306981D02*
X922642Y305909D01*
G01X919094Y306981D02*
X921570D01*
G01X918145Y307930D02*
X919094Y306981D01*
G01X923368Y308184D02*
G02X922031Y309360I859J2325D01*
G01X924297Y308184D02*
X923368D01*
G01X926242Y309347D02*
G02X924297Y308184I-2015J1162D01*
G01X927563Y310135D02*
G03X926242Y309347I44J-1575D01*
G01X927651Y310135D02*
X927563D01*
G01X928972Y309347D02*
G03X927651Y310135I-1365J-787D01*
G01X930917Y308184D02*
G02X928972Y309347I70J2325D01*
G01X931057Y308184D02*
X930917D01*
G01X933002Y309347D02*
G02X931057Y308184I-2015J1162D01*
G01X934323Y310135D02*
G03X933002Y309347I44J-1575D01*
G01X934411Y310135D02*
X934323D01*
G01X935732Y309347D02*
G03X934411Y310135I-1365J-787D01*
G01X937677Y308184D02*
G02X935732Y309347I70J2325D01*
G01X937817Y308184D02*
X937677D01*
G01X939762Y309347D02*
G02X937817Y308184I-2015J1162D01*
G01X941083Y310135D02*
G03X939762Y309347I44J-1575D01*
G01X941212Y310135D02*
X941083D01*
G01X943142Y311297D02*
G02X941212Y310135I-2015J1163D01*
G01X944448Y312084D02*
G03X943142Y311297I59J-1575D01*
G01X944566Y312084D02*
X944448D01*
G01X945872Y311297D02*
G03X944566Y312084I-1365J-788D01*
G01X947802Y310135D02*
G02X945872Y311297I85J2325D01*
G01X947972Y310135D02*
X947802D01*
G01X949902Y311297D02*
G02X947972Y310135I-2015J1163D01*
G01X951208Y312084D02*
G03X949902Y311297I59J-1575D01*
G01X951326Y312084D02*
X951208D01*
G01X952632Y311297D02*
G03X951326Y312084I-1365J-788D01*
G01X954562Y310135D02*
G02X952632Y311297I85J2325D01*
G01X954745Y310135D02*
X954562D01*
G01X956662Y311296D02*
G02X954745Y310135I-2015J1164D01*
G01X956675Y311319D02*
X956662Y311296D01*
G01X958026Y312084D02*
G03X956675Y311319I0J-1575D01*
G01X958096Y312084D02*
X958026D01*
G01X960041Y313247D02*
G02X958096Y312084I-2015J1162D01*
G01X961362Y314035D02*
G03X960041Y313247I44J-1575D01*
G01X961450Y314035D02*
X961362D01*
G01X962771Y313247D02*
G03X961450Y314035I-1365J-787D01*
G01X964716Y312084D02*
G02X962771Y313247I70J2325D01*
G01X964845Y312084D02*
X964716D01*
G01X966151Y311297D02*
G03X964845Y312084I-1365J-788D01*
G01X968081Y310135D02*
G02X966151Y311297I85J2325D01*
G01X968251Y310135D02*
X968081D01*
G01X970181Y311297D02*
G02X968251Y310135I-2015J1163D01*
G01X971487Y312084D02*
G03X970181Y311297I59J-1575D01*
G01X971616Y312084D02*
X971487D01*
G01X973561Y313247D02*
G02X971616Y312084I-2015J1162D01*
G01X921270Y317730D02*
X920226D01*
G01X923016Y315984D02*
X921270Y317730D01*
G01X924297Y315984D02*
X923016D01*
G01X926242Y317147D02*
G02X924297Y315984I-2015J1162D01*
G01X928972Y317147D02*
G03X926242I-1365J-787D01*
G01X930917Y315984D02*
G02X928972Y317147I70J2325D01*
G01X931057Y315984D02*
X930917D01*
G01X933002Y317147D02*
G02X931057Y315984I-2015J1162D01*
G01X935732Y317147D02*
G03X933002I-1365J-787D01*
G01X937677Y315984D02*
G02X935732Y317147I70J2325D01*
G01X937817Y315984D02*
X937677D01*
G01X939762Y317147D02*
G02X937817Y315984I-2015J1162D01*
G01X941083Y317935D02*
G03X939762Y317147I44J-1575D01*
G01X941212Y317935D02*
X941083D01*
G01X943142Y319097D02*
G02X941212Y317935I-2015J1163D01*
G01X944448Y319884D02*
G03X943142Y319097I59J-1575D01*
G01X944566Y319884D02*
X944448D01*
G01X945872Y319097D02*
G03X944566Y319884I-1365J-788D01*
G01X947802Y317935D02*
G02X945872Y319097I85J2325D01*
G01X947972Y317935D02*
X947802D01*
G01X949902Y319097D02*
G02X947972Y317935I-2015J1163D01*
G01X951208Y319884D02*
G03X949902Y319097I59J-1575D01*
G01X951326Y319884D02*
X951208D01*
G01X952632Y319097D02*
G03X951326Y319884I-1365J-788D01*
G01X954562Y317935D02*
G02X952632Y319097I85J2325D01*
G01X954745Y317935D02*
X954562D01*
G01X956662Y319096D02*
G02X954745Y317935I-2015J1164D01*
G01X956675Y319119D02*
X956662Y319096D01*
G01X958026Y319884D02*
G03X956675Y319119I0J-1575D01*
G01X958096Y319884D02*
X958026D01*
G01X960041Y321047D02*
G02X958096Y319884I-2015J1162D01*
G01X962771Y321047D02*
G03X960041I-1365J-787D01*
G01X964716Y319884D02*
G02X962771Y321047I70J2325D01*
G01X964845Y319884D02*
X964716D01*
G01X966151Y319097D02*
G03X964845Y319884I-1365J-788D01*
G01X968081Y317935D02*
G02X966151Y319097I85J2325D01*
G01X968251Y317935D02*
X968081D01*
G01X970181Y319097D02*
G02X968251Y317935I-2015J1163D01*
G01X971487Y319884D02*
G03X970181Y319097I59J-1575D01*
G01X971616Y319884D02*
X971487D01*
G01X973561Y321047D02*
G02X971616Y319884I-2015J1162D01*
G01X955704Y399383D02*
X956633Y400312D01*
G01X955704Y396951D02*
Y399383D01*
G01X957103Y395552D02*
X955704Y396951D01*
G01X957103Y392980D02*
Y395552D01*
G01X960349Y389734D02*
X957103Y392980D01*
G01X960349Y387868D02*
Y389734D01*
G01X960066Y387392D02*
X960349Y387868D01*
G01X960022Y387313D02*
X960066Y387392D01*
G01X960041Y385772D02*
G02X960022Y387313I1365J787D01*
G01X960066Y383489D02*
G03X960041Y385772I-2040J1119D01*
G01Y383447D02*
X960066Y383489D01*
G01X960022Y383413D02*
X960041Y383447D01*
G01Y381872D02*
G02X960022Y383413I1365J787D01*
G01X960066Y379589D02*
G03X960041Y381872I-2040J1119D01*
G01Y379547D02*
X960066Y379589D01*
G01X960022Y379513D02*
X960041Y379547D01*
G01Y377972D02*
G02X960022Y379513I1365J787D01*
G01X960066Y375689D02*
G03X960041Y377972I-2040J1119D01*
G01Y375647D02*
X960066Y375689D01*
G01X960022Y375613D02*
X960041Y375647D01*
G01Y374072D02*
G02X960022Y375613I1365J787D01*
G01X960041Y371746D02*
G03Y374072I-2015J1163D01*
G01Y370172D02*
G02Y371746I1365J787D01*
G01X960066Y370130D02*
X960041Y370172D01*
G01Y367847D02*
G03X960066Y370130I-2015J1164D01*
G01X960022Y367813D02*
X960041Y367847D01*
G01Y366272D02*
G02X960022Y367813I1365J787D01*
G01X960066Y363989D02*
G03X960041Y366272I-2040J1119D01*
G01Y363947D02*
X960066Y363989D01*
G01X960022Y363913D02*
X960041Y363947D01*
G01Y362372D02*
G02X960022Y363913I1365J787D01*
G01X960066Y360089D02*
G03X960041Y362372I-2040J1119D01*
G01Y360047D02*
X960066Y360089D01*
G01X960022Y360013D02*
X960041Y360047D01*
G01Y358472D02*
G02X960022Y360013I1365J787D01*
G01X960066Y356189D02*
G03X960041Y358472I-2040J1119D01*
G01Y356147D02*
X960066Y356189D01*
G01X960022Y356113D02*
X960041Y356147D01*
G01Y354572D02*
G02X960022Y356113I1365J787D01*
G01X960066Y352289D02*
G03X960041Y354572I-2040J1119D01*
G01Y352247D02*
X960066Y352289D01*
G01X960022Y352213D02*
X960041Y352247D01*
G01Y350672D02*
G02X960022Y352213I1365J787D01*
G01X960066Y348389D02*
G03X960041Y350672I-2040J1119D01*
G01Y348347D02*
X960066Y348389D01*
G01X960022Y348313D02*
X960041Y348347D01*
G01Y346772D02*
G02X960022Y348313I1365J787D01*
G01X960066Y344489D02*
G03X960041Y346772I-2040J1119D01*
G01Y344447D02*
X960066Y344489D01*
G01X960022Y344413D02*
X960041Y344447D01*
G01Y342872D02*
G02X960022Y344413I1365J787D01*
G01X914566Y380989D02*
Y382652D01*
G01X920321Y375234D02*
X914566Y380989D01*
G01X924312Y375234D02*
X920321D01*
G01X926242Y374072D02*
G03X924312Y375234I-2015J-1163D01*
G01X927548Y373285D02*
G02X926242Y374072I59J1575D01*
G01X927658Y373285D02*
X927548D01*
G01X929647Y369839D02*
G03X927658Y373285I-2040J1120D01*
G01X929622Y369797D02*
X929647Y369839D01*
G01X929622Y368223D02*
G02Y369797I1365J787D01*
G01Y365897D02*
G03Y368223I-2015J1163D01*
G01X929603Y364356D02*
G02X929622Y365897I1384J754D01*
G01X929690Y364205D02*
X929603Y364356D01*
G01X930987Y361209D02*
X929690Y364205D01*
G01X912762Y341335D02*
X912356Y341741D01*
G01X914131Y341335D02*
X912762D01*
G01X912262Y345235D02*
X910456Y347041D01*
G01X914131Y345235D02*
X912262D01*
G01X915452Y344447D02*
G03X914131Y345235I-1365J-787D01*
G01X917397Y343284D02*
G02X915452Y344447I70J2325D01*
G01X917526Y343284D02*
X917397D01*
G01X918832Y342497D02*
G03X917526Y343284I-1365J-788D01*
G01X920762Y341335D02*
G02X918832Y342497I85J2325D01*
G01X920891Y341335D02*
X920762D01*
G01X932836Y345411D02*
X934367Y347560D01*
G01X932352Y344822D02*
G02X932836Y345411I2015J-1162D01*
G01X931031Y344034D02*
G03X932352Y344822I-44J1575D01*
G01X930902Y344034D02*
X931031D01*
G01X928972Y342872D02*
G02X930902Y344034I2015J-1163D01*
G01X927666Y342085D02*
G03X928972Y342872I-59J1575D01*
G01X927548Y342085D02*
X927666D01*
G01X926242Y342872D02*
G03X927548Y342085I1365J788D01*
G01X924312Y344034D02*
G02X926242Y342872I-85J-2325D01*
G01X924183Y344034D02*
X924312D01*
G01X922862Y344822D02*
G03X924183Y344034I1365J787D01*
G01X920917Y345985D02*
G02X922862Y344822I-70J-2325D01*
G01X920788Y345985D02*
X920917D01*
G01X919482Y346772D02*
G03X920788Y345985I1365J788D01*
G01X917552Y347934D02*
G02X919482Y346772I-85J-2325D01*
G01X917423Y347934D02*
X917552D01*
G01X916102Y348722D02*
G03X917423Y347934I1365J787D01*
G01X914157Y349885D02*
G02X916102Y348722I-70J-2325D01*
G01X912809Y349885D02*
X914157D01*
G01X911604Y351090D02*
X912809Y349885D01*
G01X911604Y352451D02*
Y351090D01*
G01X929622Y360422D02*
X928972Y361550D01*
G01X930943Y359634D02*
G02X929622Y360422I44J1575D01*
G01X931133Y359634D02*
X930943D01*
G01X934367Y359260D02*
X931133Y359634D01*
G01X913624Y380873D02*
X912787D01*
G01X920013Y374484D02*
X913624Y380873D01*
G01X924286Y374484D02*
X920013D01*
G01X925592Y373697D02*
G03X924286Y374484I-1365J-788D01*
G01X927556Y372534D02*
G02X925592Y373697I51J2326D01*
G01X927651Y372534D02*
X927556D01*
G01X928972Y370172D02*
G03X927651Y372534I-1365J787D01*
G01X928947Y370130D02*
X928972Y370172D01*
G01Y367847D02*
G02X928947Y370130I2015J1164D01*
G01X928991Y367813D02*
X928972Y367847D01*
G01Y366272D02*
G03X928991Y367813I-1365J787D01*
G01X928947Y363989D02*
G02X928972Y366272I2040J1119D01*
G01Y363947D02*
X928947Y363989D01*
G01X928991Y363913D02*
X928972Y363947D01*
G01Y362372D02*
G03X928991Y363913I-1365J787D01*
G01X928972Y361550D02*
G02Y362372I712J411D01*
G01X947152Y400175D02*
Y403703D01*
G01X946503Y399013D02*
X947152Y400175D01*
G01X946522Y397472D02*
G02X946503Y399013I1365J787D01*
G01X946522Y395146D02*
G03Y397472I-2015J1163D01*
G01X946457Y395032D02*
X946522Y395146D01*
G01X944507Y392410D02*
X946457Y395032D01*
G01X954956Y399339D02*
X954133Y400162D01*
G01X954956Y396641D02*
Y399339D01*
G01X956355Y395242D02*
X954956Y396641D01*
G01X956355Y392670D02*
Y395242D01*
G01X959601Y389424D02*
X956355Y392670D01*
G01X959601Y388075D02*
Y389424D01*
G01X959366Y387680D02*
X959601Y388075D01*
G01X959391Y385397D02*
G02X959366Y387680I2015J1164D01*
G01X959410Y383856D02*
G03X959391Y385397I-1384J754D01*
G01Y383822D02*
X959410Y383856D01*
G01X959366Y383780D02*
X959391Y383822D01*
G01Y381497D02*
G02X959366Y383780I2015J1164D01*
G01X959410Y379956D02*
G03X959391Y381497I-1384J754D01*
G01Y379922D02*
X959410Y379956D01*
G01X959366Y379880D02*
X959391Y379922D01*
G01Y377597D02*
G02X959366Y379880I2015J1164D01*
G01X959410Y376056D02*
G03X959391Y377597I-1384J754D01*
G01Y376022D02*
X959410Y376056D01*
G01X959366Y375980D02*
X959391Y376022D01*
G01Y373697D02*
G02X959366Y375980I2015J1164D01*
G01X959410Y372156D02*
G03X959391Y373697I-1384J754D01*
G01Y372122D02*
X959410Y372156D01*
G01X959366Y369839D02*
G02X959391Y372122I2040J1119D01*
G01Y369797D02*
X959366Y369839D01*
G01X959391Y368223D02*
G03Y369797I-1365J787D01*
G01Y365897D02*
G02Y368223I2015J1163D01*
G01X959410Y364356D02*
G03X959391Y365897I-1384J754D01*
G01Y364322D02*
X959410Y364356D01*
G01X959366Y364280D02*
X959391Y364322D01*
G01Y361997D02*
G02X959366Y364280I2015J1164D01*
G01X959410Y360456D02*
G03X959391Y361997I-1384J754D01*
G01Y360422D02*
X959410Y360456D01*
G01X959366Y360380D02*
X959391Y360422D01*
G01Y358097D02*
G02X959366Y360380I2015J1164D01*
G01X959410Y356556D02*
G03X959391Y358097I-1384J754D01*
G01Y356522D02*
X959410Y356556D01*
G01X959366Y356480D02*
X959391Y356522D01*
G01Y354197D02*
G02X959366Y356480I2015J1164D01*
G01X959410Y352656D02*
G03X959391Y354197I-1384J754D01*
G01Y352622D02*
X959410Y352656D01*
G01X959366Y352580D02*
X959391Y352622D01*
G01Y350297D02*
G02X959366Y352580I2015J1164D01*
G01X959410Y348756D02*
G03X959391Y350297I-1384J754D01*
G01Y348722D02*
X959410Y348756D01*
G01X959366Y348680D02*
X959391Y348722D01*
G01Y346397D02*
G02X959366Y348680I2015J1164D01*
G01X959410Y344856D02*
G03X959391Y346397I-1384J754D01*
G01Y344822D02*
X959410Y344856D01*
G01X959366Y344780D02*
X959391Y344822D01*
G01Y342497D02*
G02X959366Y344780I2015J1164D01*
G01X922636Y399809D02*
X918356Y404089D01*
G01X922860Y399421D02*
X922636Y399809D01*
G01X924170Y398632D02*
G02X922860Y399421I57J1577D01*
G01X924183Y398632D02*
X924170D01*
G01X924185Y398634D02*
X924183Y398632D01*
G01X924312Y398634D02*
X924185D01*
G01X926242Y397472D02*
G03X924312Y398634I-2015J-1163D01*
G01X927548Y396685D02*
G02X926242Y397472I59J1575D01*
G01X927658Y396685D02*
X927548D01*
G01X929622Y395522D02*
G03X927658Y396685I-2015J-1163D01*
G01X930916Y394735D02*
G02X929622Y395522I71J1574D01*
G01X931129Y394735D02*
X930916D01*
G01X934367Y394359D02*
X931129Y394735D01*
G01X961104Y399483D02*
X961933Y400312D01*
G01X961104Y395951D02*
Y399483D01*
G01X962772Y394283D02*
X961104Y395951D01*
G01X962772Y388879D02*
Y394283D01*
G01X963446Y387680D02*
X962772Y388879D01*
G01X963421Y385397D02*
G03X963446Y387680I-2015J1164D01*
G01X963402Y383856D02*
G02X963421Y385397I1384J754D01*
G01Y383822D02*
X963402Y383856D01*
G01X963446Y383780D02*
X963421Y383822D01*
G01Y381497D02*
G03X963446Y383780I-2015J1164D01*
G01X963402Y379956D02*
G02X963421Y381497I1384J754D01*
G01Y379922D02*
X963402Y379956D01*
G01X963446Y379880D02*
X963421Y379922D01*
G01Y377597D02*
G03X963446Y379880I-2015J1164D01*
G01X963402Y376056D02*
G02X963421Y377597I1384J754D01*
G01Y376022D02*
X963402Y376056D01*
G01X963446Y375980D02*
X963421Y376022D01*
G01Y373697D02*
G03X963446Y375980I-2015J1164D01*
G01X963402Y372156D02*
G02X963421Y373697I1384J754D01*
G01Y372122D02*
X963402Y372156D01*
G01X963446Y369839D02*
G03X963421Y372122I-2040J1119D01*
G01Y369797D02*
X963446Y369839D01*
G01X963421Y368223D02*
G02Y369797I1365J787D01*
G01Y365897D02*
G03Y368223I-2015J1163D01*
G01X963402Y364356D02*
G02X963421Y365897I1384J754D01*
G01Y364322D02*
X963402Y364356D01*
G01X963446Y364280D02*
X963421Y364322D01*
G01Y361997D02*
G03X963446Y364280I-2015J1164D01*
G01X963402Y360456D02*
G02X963421Y361997I1384J754D01*
G01Y360422D02*
X963402Y360456D01*
G01X963446Y360380D02*
X963421Y360422D01*
G01Y358097D02*
G03X963446Y360380I-2015J1164D01*
G01X963402Y356556D02*
G02X963421Y358097I1384J754D01*
G01Y356522D02*
X963402Y356556D01*
G01X963446Y356480D02*
X963421Y356522D01*
G01Y354197D02*
G03X963446Y356480I-2015J1164D01*
G01X963402Y352656D02*
G02X963421Y354197I1384J754D01*
G01Y352622D02*
X963402Y352656D01*
G01X963446Y352580D02*
X963421Y352622D01*
G01Y350297D02*
G03X963446Y352580I-2015J1164D01*
G01X963402Y348756D02*
G02X963421Y350297I1384J754D01*
G01Y348722D02*
X963402Y348756D01*
G01X963446Y348680D02*
X963421Y348722D01*
G01Y346397D02*
G03X963446Y348680I-2015J1164D01*
G01X963402Y344856D02*
G02X963421Y346397I1384J754D01*
G01Y344822D02*
X963402Y344856D01*
G01X963446Y344780D02*
X963421Y344822D01*
G01Y342497D02*
G03X963446Y344780I-2015J1164D01*
G01X942911Y399831D02*
X939451Y403291D01*
G01X943100Y399493D02*
X942911Y399831D01*
G01X943167Y399380D02*
X943100Y399493D01*
G01X943142Y397097D02*
G03X943167Y399380I-2015J1164D01*
G01X943076Y396982D02*
X943142Y397097D01*
G01X942386Y396021D02*
G03X943076Y396982I-4364J3861D01*
G01X941127Y394359D02*
G02X942386Y396021I11539J-7434D01*
G01X971556Y400841D02*
X973540Y402825D01*
G01X971556Y397041D02*
Y400841D01*
G01X972556Y396041D02*
X971556Y397041D01*
G01X946404Y400370D02*
Y403393D01*
G01X945913Y399492D02*
X946404Y400370D01*
G01X945847Y399380D02*
X945913Y399492D01*
G01X945872Y397097D02*
G02X945847Y399380I2015J1164D01*
G01X944578Y394735D02*
G03X945872Y397097I-71J1574D01*
G01X944437Y394735D02*
X944578D01*
G01X942492Y391247D02*
G02X944437Y394735I2015J1163D01*
G01X942557Y391134D02*
X942492Y391247D01*
G01X944507Y388509D02*
X942557Y391134D01*
G01X922037Y399350D02*
X918152Y403235D01*
G01X922212Y399047D02*
X922037Y399350D01*
G01X924157Y397884D02*
G02X922212Y399047I70J2325D01*
G01X924286Y397884D02*
X924157D01*
G01X925592Y397097D02*
G03X924286Y397884I-1365J-788D01*
G01X927556Y395934D02*
G02X925592Y397097I51J2326D01*
G01X927651Y395934D02*
X927556D01*
G01X928972Y395146D02*
G03X927651Y395934I-1365J-787D01*
G01X930902Y393984D02*
G02X928972Y395146I85J2325D01*
G01X931058Y393984D02*
X930902D01*
G01X932352Y391623D02*
G03X931058Y393984I-1365J787D01*
G01X932352Y389297D02*
G02Y391623I2015J1163D01*
G01X932418Y389181D02*
X932352Y389297D01*
G01X934367Y386560D02*
X932418Y389181D01*
G01X960356Y399541D02*
X959433Y400464D01*
G01X960356Y395641D02*
Y399541D01*
G01X962024Y393973D02*
X960356Y395641D01*
G01X962024Y388684D02*
Y393973D01*
G01X962790Y387313D02*
X962024Y388684D01*
G01X962771Y385772D02*
G03X962790Y387313I-1365J787D01*
G01X962746Y383489D02*
G02X962771Y385772I2040J1119D01*
G01Y383447D02*
X962746Y383489D01*
G01X962790Y383413D02*
X962771Y383447D01*
G01Y381872D02*
G03X962790Y383413I-1365J787D01*
G01X962746Y379589D02*
G02X962771Y381872I2040J1119D01*
G01Y379547D02*
X962746Y379589D01*
G01X962790Y379513D02*
X962771Y379547D01*
G01Y377972D02*
G03X962790Y379513I-1365J787D01*
G01X962746Y375689D02*
G02X962771Y377972I2040J1119D01*
G01Y375647D02*
X962746Y375689D01*
G01X962790Y375613D02*
X962771Y375647D01*
G01Y374072D02*
G03X962790Y375613I-1365J787D01*
G01X962771Y371746D02*
G02Y374072I2015J1163D01*
G01Y370172D02*
G03Y371746I-1365J787D01*
G01X962746Y370130D02*
X962771Y370172D01*
G01Y367847D02*
G02X962746Y370130I2015J1164D01*
G01X962790Y367813D02*
X962771Y367847D01*
G01Y366272D02*
G03X962790Y367813I-1365J787D01*
G01X962746Y363989D02*
G02X962771Y366272I2040J1119D01*
G01Y363947D02*
X962746Y363989D01*
G01X962790Y363913D02*
X962771Y363947D01*
G01Y362372D02*
G03X962790Y363913I-1365J787D01*
G01X962746Y360089D02*
G02X962771Y362372I2040J1119D01*
G01Y360047D02*
X962746Y360089D01*
G01X962790Y360013D02*
X962771Y360047D01*
G01Y358472D02*
G03X962790Y360013I-1365J787D01*
G01X962746Y356189D02*
G02X962771Y358472I2040J1119D01*
G01Y356147D02*
X962746Y356189D01*
G01X962790Y356113D02*
X962771Y356147D01*
G01Y354572D02*
G03X962790Y356113I-1365J787D01*
G01X962746Y352289D02*
G02X962771Y354572I2040J1119D01*
G01Y352247D02*
X962746Y352289D01*
G01X962790Y352213D02*
X962771Y352247D01*
G01Y350672D02*
G03X962790Y352213I-1365J787D01*
G01X962746Y348389D02*
G02X962771Y350672I2040J1119D01*
G01Y348347D02*
X962746Y348389D01*
G01X962790Y348313D02*
X962771Y348347D01*
G01Y346772D02*
G03X962790Y348313I-1365J787D01*
G01X962746Y344489D02*
G02X962771Y346772I2040J1119D01*
G01Y344447D02*
X962746Y344489D01*
G01X962790Y344413D02*
X962771Y344447D01*
G01Y342872D02*
G03X962790Y344413I-1365J787D01*
G01X917757Y372141D02*
X915756D01*
G01X923214Y366684D02*
X917757Y372141D01*
G01X924286Y366684D02*
X923214D01*
G01X925611Y364356D02*
G03X924286Y366684I-1384J753D01*
G01X925592Y364322D02*
X925611Y364356D01*
G01X925567Y364280D02*
X925592Y364322D01*
G01Y361997D02*
G02X925567Y364280I2015J1164D01*
G01X926093Y361129D02*
X925592Y361997D01*
G01X926158Y359880D02*
G03X926093Y361129I-1305J558D01*
G01X926242Y358472D02*
G02X926158Y359880I1365J788D01*
G01X926308Y358359D02*
X926242Y358472D01*
G01X927607Y355360D02*
X926308Y358359D01*
G01X913153Y398644D02*
X911958D01*
G01X915863Y395934D02*
X913153Y398644D01*
G01X920891Y395934D02*
X915863D01*
G01X922212Y395146D02*
G03X920891Y395934I-1365J-787D01*
G01X924142Y393984D02*
G02X922212Y395146I85J2325D01*
G01X924298Y393984D02*
X924142D01*
G01X925592Y393197D02*
G03X924298Y393984I-1365J-787D01*
G01X927537Y392034D02*
G02X925592Y393197I70J2325D01*
G01X927678Y392034D02*
X927537D01*
G01X928972Y391247D02*
G03X927678Y392034I-1365J-787D01*
G01X929037Y391134D02*
X928972Y391247D01*
G01X930987Y388509D02*
X929037Y391134D01*
G01X936154Y402543D02*
X931813Y406884D01*
G01X939140Y402543D02*
X936154D01*
G01X942309Y399374D02*
X939140Y402543D01*
G01X942511Y399013D02*
X942309Y399374D01*
G01X942492Y397472D02*
G03X942511Y399013I-1365J787D01*
G01X940551Y395826D02*
G03X942492Y397472I-1439J3664D01*
G01X939762Y393572D02*
G02X940551Y395826I1365J787D01*
G01X939787Y393530D02*
X939762Y393572D01*
G01Y391247D02*
G03X939787Y393530I-2015J1164D01*
G01X939743Y391213D02*
X939762Y391247D01*
G01Y389672D02*
G02X939743Y391213I1365J787D01*
G01X939828Y389559D02*
X939762Y389672D01*
G01X941127Y386560D02*
X939828Y389559D01*
G01X912570Y345985D02*
X910766Y347789D01*
G01X914141Y345985D02*
X912570D01*
G01X916102Y344822D02*
G03X914141Y345985I-2015J-1162D01*
G01X917423Y344034D02*
G02X916102Y344822I44J1575D01*
G01X917552Y344034D02*
X917423D01*
G01X919482Y342872D02*
G03X917552Y344034I-2015J-1163D01*
G01X920788Y342085D02*
G02X919482Y342872I59J1575D01*
G01X920917Y342085D02*
X920788D01*
G01X914766Y358989D02*
X912266D01*
G01X916442Y357313D02*
X914766Y358989D01*
G01X916442Y355119D02*
Y357313D01*
G01X915959Y354208D02*
X916442Y355119D01*
G01X916812Y351834D02*
G02X915959Y354208I655J1575D01*
G01X917552Y351834D02*
X916812D01*
G01X919482Y350672D02*
G03X917552Y351834I-2015J-1163D01*
G01X920788Y349885D02*
G02X919482Y350672I59J1575D01*
G01X920917Y349885D02*
X920788D01*
G01X922862Y348722D02*
G03X920917Y349885I-2015J-1162D01*
G01X924183Y347934D02*
G02X922862Y348722I44J1575D01*
G01X924312Y347934D02*
X924183D01*
G01X926242Y346772D02*
G03X924312Y347934I-2015J-1163D01*
G01X927548Y345985D02*
G02X926242Y346772I59J1575D01*
G01X927666Y345985D02*
X927548D01*
G01X928972Y346772D02*
G02X927666Y345985I-1365J788D01*
G01X929038Y346888D02*
X928972Y346772D01*
G01X930987Y349509D02*
X929038Y346888D01*
G01X910856Y350780D02*
Y352141D01*
G01X912501Y349135D02*
X910856Y350780D01*
G01X914131Y349135D02*
X912501D01*
G01X915452Y348347D02*
G03X914131Y349135I-1365J-787D01*
G01X917397Y347184D02*
G02X915452Y348347I70J2325D01*
G01X917526Y347184D02*
X917397D01*
G01X918832Y346397D02*
G03X917526Y347184I-1365J-788D01*
G01X920762Y345235D02*
G02X918832Y346397I85J2325D01*
G01X920891Y345235D02*
X920762D01*
G01X922212Y344447D02*
G03X920891Y345235I-1365J-787D01*
G01X924157Y343284D02*
G02X922212Y344447I70J2325D01*
G01X924286Y343284D02*
X924157D01*
G01X925592Y342497D02*
G03X924286Y343284I-1365J-788D01*
G01X927522Y341335D02*
G02X925592Y342497I85J2325D01*
G01X927692Y341335D02*
X927522D01*
G01X929622Y342497D02*
G02X927692Y341335I-2015J1163D01*
G01X930928Y343284D02*
G03X929622Y342497I59J-1575D01*
G01X931057Y343284D02*
X930928D01*
G01X933002Y344447D02*
G02X931057Y343284I-2015J1162D01*
G01X934323Y345235D02*
G03X933002Y344447I44J-1575D01*
G01X934452Y345235D02*
X934323D01*
G01X936382Y346397D02*
G02X934452Y345235I-2015J1163D01*
G01X937747Y349509D02*
X936382Y346397D01*
G01X913073Y342085D02*
X912669Y342489D01*
G01X914157Y342085D02*
X913073D01*
G01X918067Y372889D02*
X916066D01*
G01X922437Y368519D02*
X918067Y372889D01*
G01X922441Y368519D02*
X922437D01*
G01X923525Y367435D02*
X922441Y368519D01*
G01X924278Y367435D02*
X923525D01*
G01X926267Y363989D02*
G03X924278Y367435I-2040J1120D01*
G01X926242Y363947D02*
X926267Y363989D01*
G01X926223Y363913D02*
X926242Y363947D01*
G01Y362372D02*
G02X926223Y363913I1365J787D01*
G01X926743Y361504D02*
X926242Y362372D01*
G01X927607Y359260D02*
G03X926743Y361504I-7568J-1626D01*
G01X913826Y399034D02*
Y400312D01*
G01X916175Y396685D02*
X913826Y399034D01*
G01X920898Y396685D02*
X916175D01*
G01X922862Y395522D02*
G03X920898Y396685I-2015J-1163D01*
G01X924156Y394735D02*
G02X922862Y395522I71J1574D01*
G01X924297Y394735D02*
X924156D01*
G01X926242Y393572D02*
G03X924297Y394735I-2015J-1162D01*
G01X927536Y392785D02*
G02X926242Y393572I71J1574D01*
G01X927751Y392785D02*
X927536D01*
G01X930987Y392410D02*
X927751Y392785D01*
G01X914456Y358241D02*
X911956D01*
G01X915694Y357003D02*
X914456Y358241D01*
G01X915694Y355307D02*
Y357003D01*
G01X915295Y354561D02*
X915694Y355307D01*
G01X916669Y351084D02*
G02X915295Y354561I798J2325D01*
G01X917526Y351084D02*
X916669D01*
G01X918832Y350297D02*
G03X917526Y351084I-1365J-788D01*
G01X920762Y349135D02*
G02X918832Y350297I85J2325D01*
G01X920891Y349135D02*
X920762D01*
G01X922212Y348347D02*
G03X920891Y349135I-1365J-787D01*
G01X924157Y347184D02*
G02X922212Y348347I70J2325D01*
G01X924286Y347184D02*
X924157D01*
G01X925592Y346397D02*
G03X924286Y347184I-1365J-788D01*
G01X927522Y345235D02*
G02X925592Y346397I85J2325D01*
G01X927692Y345235D02*
X927522D01*
G01X929622Y346397D02*
G02X927692Y345235I-2015J1163D01*
G01X930928Y347184D02*
G03X929622Y346397I59J-1575D01*
G01X930987Y347184D02*
X930928D01*
G01X931704Y347598D02*
G02X930987Y347184I-717J414D01*
G01X932352Y348722D02*
X931704Y347598D01*
G01X934297Y349885D02*
G03X932352Y348722I70J-2325D01*
G01X934426Y349885D02*
X934297D01*
G01X935732Y350672D02*
G02X934426Y349885I-1365J788D01*
G01X935798Y350788D02*
X935732Y350672D01*
G01X937747Y353409D02*
X935798Y350788D01*
G01X944781Y406074D02*
Y407266D01*
G01X947152Y403703D02*
X944781Y406074D01*
G01X918356Y404089D02*
Y404948D01*
G01X932561Y407194D02*
Y409796D01*
G01X936464Y403291D02*
X932561Y407194D01*
G01X939451Y403291D02*
X936464D01*
G01X944415Y405382D02*
X943315D01*
G01X946404Y403393D02*
X944415Y405382D01*
G01X918152Y403235D02*
X916533D01*
G01X931566Y408201D02*
X930606D01*
G01X931813Y407954D02*
X931566Y408201D01*
G01X931813Y406884D02*
Y407954D01*
G01X1010740Y209898D02*
X1012105Y213009D01*
G01X1010529Y209099D02*
G02X1010740Y209898I1576J11D01*
G01X1010529Y204500D02*
Y209099D01*
G01X1011500Y203529D02*
X1010529Y204500D01*
G01X1011500Y200000D02*
Y203529D01*
G01X1017700Y193800D02*
X1011500Y200000D01*
G01X1017700Y192974D02*
Y193800D01*
G01X1033100Y205500D02*
X1037104Y201496D01*
G01X1031285Y207864D02*
G03X1033100Y205500I9909J5729D01*
G01X1030911Y208511D02*
X1031285Y207864D01*
G01X1030454Y209300D02*
X1030911Y208511D01*
G01X1029553Y210853D02*
X1030454Y209300D01*
G01X1027640Y214172D02*
X1029553Y210853D01*
G01X1027621Y215713D02*
G03X1027640Y214172I1384J-754D01*
G01Y215747D02*
X1027621Y215713D01*
G01X1027665Y215789D02*
X1027640Y215747D01*
G01Y218072D02*
G02X1027665Y215789I-2015J-1164D01*
G01X972526Y210123D02*
Y219361D01*
G01X976202Y206447D02*
X972526Y210123D01*
G01X976202Y200695D02*
Y206447D01*
G01X978556Y198341D02*
X976202Y200695D01*
G01X978556Y198091D02*
Y198341D01*
G01X977756Y197291D02*
X978556Y198091D01*
G01X1003961Y216156D02*
G02X1005286Y218484I1384J753D01*
G01X1003980Y216122D02*
X1003961Y216156D01*
G01X1004005Y216080D02*
X1003980Y216122D01*
G01Y213797D02*
G03X1004005Y216080I-2015J1164D01*
G01X1003961Y212256D02*
G02X1003980Y213797I1384J754D01*
G01Y212222D02*
X1003961Y212256D01*
G01X1004005Y212180D02*
X1003980Y212222D01*
G01Y209897D02*
G03X1004005Y212180I-2015J1164D01*
G01X1003700Y208853D02*
G02X1003980Y209897I2088J0D01*
G01X1003700Y204301D02*
Y208853D01*
G01X1007500Y200501D02*
X1003700Y204301D01*
G01X1007500Y196200D02*
Y200501D01*
G01X1009700Y194000D02*
X1007500Y196200D01*
G01X1009700Y192853D02*
Y194000D01*
G01X1032122Y196948D02*
Y195289D01*
G01X1027206Y201864D02*
X1032122Y196948D01*
G01X1027206Y211441D02*
Y201864D01*
G01X1025638Y213009D02*
X1027206Y211441D01*
G01X1025625Y213009D02*
X1025638D01*
G01X993510Y216682D02*
G02X995059Y218713I8321J-4740D01*
G01X993191Y216122D02*
X993510Y216682D01*
G01X993166Y216080D02*
X993191Y216122D01*
G01Y213797D02*
G02X993166Y216080I2015J1164D01*
G01X993210Y212256D02*
G03X993191Y213797I-1384J754D01*
G01Y212222D02*
X993210Y212256D01*
G01X993166Y212180D02*
X993191Y212222D01*
G01Y209897D02*
G02X993166Y212180I2015J1164D01*
G01X993210Y208356D02*
G03X993191Y209897I-1384J754D01*
G01Y208322D02*
X993210Y208356D01*
G01X993166Y206039D02*
G02X993191Y208322I2040J1119D01*
G01Y205997D02*
X993166Y206039D01*
G01X993191Y204423D02*
G03Y205997I-1365J787D01*
G01X992856Y203841D02*
X993191Y204423D01*
G01X992856Y202082D02*
Y203841D01*
G01X994645Y200293D02*
X992856Y202082D01*
G01X994645Y198346D02*
Y200293D01*
G01X973450Y197385D02*
X972756Y196691D01*
G01X973450Y198201D02*
Y197385D01*
G01X971967Y206444D02*
Y202801D01*
G01X991268Y200250D02*
Y197909D01*
G01X990109Y201409D02*
X991268Y200250D01*
G01X990109Y203002D02*
Y201409D01*
G01X989830Y204012D02*
G02X990109Y203002I-1802J-1041D01*
G01X989811Y204046D02*
X989830Y204012D01*
G01X989776Y206312D02*
G03X989811Y204046I2050J-1102D01*
G01X989838Y206420D02*
X989776Y206312D01*
G01X989811Y207946D02*
G02X989838Y206420I-1365J-787D01*
G01X989786Y210229D02*
G03X989811Y207946I2040J-1119D01*
G01Y210271D02*
X989786Y210229D01*
G01X989830Y210305D02*
X989811Y210271D01*
G01Y211846D02*
G02X989830Y210305I-1365J-787D01*
G01X988446Y214960D02*
X989811Y211846D01*
G01X989709Y199391D02*
Y197885D01*
G01X986860Y202240D02*
X989709Y199391D01*
G01X986860Y214580D02*
Y202240D01*
G01X986871Y215001D02*
X986860Y214580D01*
G01X987081Y215747D02*
G03X986871Y215001I1365J-787D01*
G01X987106Y215789D02*
X987081Y215747D01*
G01Y218072D02*
G02X987106Y215789I-2015J-1164D01*
G01X1000636Y215807D02*
G03X1000601Y218073I-2050J1102D01*
G01Y215747D02*
X1000636Y215807D01*
G01X1000601Y214173D02*
G02Y215747I1364J787D01*
G01X1000636Y211907D02*
G03X1000601Y214173I-2050J1102D01*
G01Y211847D02*
X1000636Y211907D01*
G01X1000601Y210273D02*
G02Y211847I1364J787D01*
G01X1001100Y208410D02*
G03X1000601Y210273I-3728J0D01*
G01X1001100Y202800D02*
Y208410D01*
G01X1003796Y200104D02*
X1001100Y202800D01*
G01X1003796Y198734D02*
Y200104D01*
G01X1029005Y202275D02*
Y207159D01*
G01X1033744Y197536D02*
X1029005Y202275D01*
G01X993094Y199951D02*
Y198703D01*
G01X990963Y202082D02*
X993094Y199951D01*
G01X990963Y202545D02*
Y202082D01*
G01X990461Y204422D02*
G02X990963Y202545I-3257J-1877D01*
G01X990434Y205948D02*
G03X990461Y204422I1392J-739D01*
G01Y205996D02*
X990434Y205948D01*
G01X990486Y206038D02*
X990461Y205996D01*
G01Y208321D02*
G02X990486Y206038I-2015J-1164D01*
G01X990442Y209862D02*
G03X990461Y208321I1384J-754D01*
G01X990529Y210013D02*
X990442Y209862D01*
G01X991826Y213009D02*
X990529Y210013D01*
G01X997796Y200203D02*
Y198224D01*
G01X996806Y201193D02*
X997796Y200203D01*
G01X996806Y203641D02*
Y201193D01*
G01X996571Y204048D02*
X996806Y203641D01*
G01X996571Y206374D02*
G03Y204048I2015J-1163D01*
G01Y207948D02*
G02Y206374I-1364J-787D01*
G01Y210274D02*
G03Y207948I2015J-1163D01*
G01Y211848D02*
G02Y210274I-1364J-787D01*
G01Y214174D02*
G03Y211848I2015J-1163D01*
G01X996775Y214812D02*
G02X996571Y214174I-1569J150D01*
G01X996766Y216254D02*
G02X996775Y214812I-7071J-765D01*
G01X997221Y217698D02*
G03X996766Y216254I3028J-1748D01*
G01X997221Y220024D02*
G02Y217698I-2015J-1163D01*
G01X999950Y217696D02*
G02X999915Y219962I2015J1164D01*
G01X999950Y216122D02*
G03Y217696I-1364J787D01*
G01X999915Y216062D02*
X999950Y216122D01*
G01Y213796D02*
G02X999915Y216062I2015J1164D01*
G01X999950Y212222D02*
G03Y213796I-1364J787D01*
G01X999915Y212162D02*
X999950Y212222D01*
G01Y209896D02*
G02X999915Y212162I2015J1164D01*
G01X1000200Y208964D02*
G03X999950Y209896I-1864J0D01*
G01X1000200Y208100D02*
Y208964D01*
G01X1000206Y208094D02*
X1000200Y208100D01*
G01X1000206Y201794D02*
Y208094D01*
G01X1001796Y200204D02*
X1000206Y201794D01*
G01X1001796Y199049D02*
Y200204D01*
G01X1011700Y193900D02*
Y192853D01*
G01X1008500Y197100D02*
X1011700Y193900D01*
G01X1008500Y201965D02*
Y197100D01*
G01X1007171Y203294D02*
X1008500Y201965D01*
G01X1007171Y208177D02*
Y203294D01*
G01X1006710Y209897D02*
G02X1007171Y208177I-2977J-1720D01*
G01X1006685Y212180D02*
G03X1006710Y209897I2040J-1119D01*
G01Y212222D02*
X1006685Y212180D01*
G01X1006729Y212256D02*
X1006710Y212222D01*
G01Y213797D02*
G02X1006729Y212256I-1365J-787D01*
G01X1006644Y213910D02*
X1006710Y213797D01*
G01X1005345Y216909D02*
X1006644Y213910D01*
G01X1015700Y193800D02*
Y192683D01*
G01X1010486Y199014D02*
X1015700Y193800D01*
G01X1010486Y203014D02*
Y199014D01*
G01X1009500Y204000D02*
X1010486Y203014D01*
G01X1009500Y209062D02*
Y204000D01*
G01X1008725Y211060D02*
X1009500Y209062D01*
G01X1013700Y193800D02*
Y192561D01*
G01X1009500Y198000D02*
X1013700Y193800D01*
G01X1009500Y202398D02*
Y198000D01*
G01X1008398Y203500D02*
X1009500Y202398D01*
G01X1008398Y207400D02*
Y203500D01*
G01X1007863Y209400D02*
G02X1008398Y207400I-3469J-2000D01*
G01X1007360Y210272D02*
X1007863Y209400D01*
G01X1007341Y211813D02*
G03X1007360Y210272I1384J-754D01*
G01Y211847D02*
X1007341Y211813D01*
G01X1007385Y211889D02*
X1007360Y211847D01*
G01Y214172D02*
G02X1007385Y211889I-2015J-1164D01*
G01X1007341Y215713D02*
G03X1007360Y214172I1384J-754D01*
G01X1007428Y215864D02*
X1007341Y215713D01*
G01X1008725Y218860D02*
X1007428Y215864D01*
G01X999796Y200204D02*
Y198928D01*
G01X997600Y202400D02*
X999796Y200204D01*
G01X997600Y203948D02*
Y202400D01*
G01X997353Y204195D02*
X997600Y203948D01*
G01X997221Y204424D02*
X997353Y204195D01*
G01X997221Y205998D02*
G03Y204424I1365J-787D01*
G01Y208324D02*
G02Y205998I-2015J-1163D01*
G01Y209898D02*
G03Y208324I1365J-787D01*
G01Y212224D02*
G02Y209898I-2015J-1163D01*
G01Y213798D02*
G03Y212224I1365J-787D01*
G01X997454Y214361D02*
G02X997221Y213798I-2248J601D01*
G01X998586Y216909D02*
X997454Y214361D01*
G01X1026990Y217697D02*
G02X1026965Y219980I2015J1164D01*
G01X1027009Y216156D02*
G03X1026990Y217697I-1384J754D01*
G01Y216122D02*
X1027009Y216156D01*
G01X1026965Y216080D02*
X1026990Y216122D01*
G01Y213797D02*
G02X1026965Y216080I2015J1164D01*
G01X1028500Y211177D02*
X1026990Y213797D01*
G01X1029088Y209954D02*
X1028500Y211177D01*
G01X1030047Y208340D02*
X1029088Y209954D01*
G01X1030370Y207946D02*
G03X1030047Y208340I-1364J-789D01*
G01X1031093Y206696D02*
X1030370Y207946D01*
G01X1032050Y205450D02*
G02X1031093Y206696I4269J4270D01*
G01X1035327Y202173D02*
X1032050Y205450D01*
G01X996184Y199816D02*
Y198054D01*
G01X993606Y202394D02*
X996184Y199816D01*
G01X993606Y203165D02*
Y202394D01*
G01X993842Y204048D02*
G03X993606Y203165I1535J-883D01*
G01X994073Y204607D02*
G02X993842Y204048I-2247J601D01*
G01X993866Y206330D02*
G02X994073Y204607I-2040J-1119D01*
G01X993841Y206372D02*
X993866Y206330D01*
G01X993841Y207946D02*
G03Y206372I1365J-787D01*
G01Y210272D02*
G02Y207946I-2015J-1163D01*
G01X993822Y211813D02*
G03X993841Y210272I1384J-754D01*
G01Y211847D02*
X993822Y211813D01*
G01X993866Y211889D02*
X993841Y211847D01*
G01Y214172D02*
G02X993866Y211889I-2015J-1164D01*
G01X993822Y215713D02*
G03X993841Y214172I1384J-754D01*
G01X994580Y216433D02*
G03X993822Y215713I736J-1534D01*
G01X995252Y216909D02*
G02X994580Y216433I-1731J1732D01*
G01X995299Y216956D02*
X995252Y216909D01*
G01X995889Y217441D02*
G03X995299Y216956I697J-1449D01*
G01X995842Y220303D02*
G02X995889Y217441I-636J-1442D01*
G01X1032394Y213000D02*
X1035988D01*
G01X1032385Y213009D02*
X1032394Y213000D01*
G01X1033350Y210550D02*
X1034106Y209794D01*
G01X1031700Y211400D02*
X1033350Y210550D01*
G01X1030700Y212400D02*
X1031700Y211400D01*
G01X1030700Y220900D02*
Y212400D01*
G01X972717Y202569D02*
Y206784D01*
G01X972194Y201656D02*
X972717Y202569D01*
G01X972194Y200551D02*
Y201656D01*
G01X974266Y198479D02*
X972194Y200551D01*
G01X974266Y197641D02*
Y198479D01*
G01X975256Y196651D02*
X974266Y197641D01*
G01X1005796Y200204D02*
Y198807D01*
G01X1002900Y203100D02*
X1005796Y200204D01*
G01X1002900Y208665D02*
Y203100D01*
G01X1003330Y210272D02*
G03X1002900Y208665I2787J-1607D01*
G01X1003349Y211813D02*
G02X1003330Y210272I-1384J-754D01*
G01Y211847D02*
X1003349Y211813D01*
G01X1003305Y211889D02*
X1003330Y211847D01*
G01Y214172D02*
G03X1003305Y211889I2015J-1164D01*
G01X1003349Y215713D02*
G02X1003330Y214172I-1384J-754D01*
G01Y215747D02*
X1003349Y215713D01*
G01X1003305Y215789D02*
X1003330Y215747D01*
G01Y218072D02*
G03X1003305Y215789I2015J-1164D01*
G01X973277Y210474D02*
Y218978D01*
G01X976952Y206799D02*
X973277Y210474D01*
G01X976952Y201047D02*
Y206799D01*
G01X979306Y198693D02*
X976952Y201047D01*
G01X979306Y198241D02*
Y198693D01*
G01X980256Y197291D02*
X979306Y198241D01*
G01X1027621Y219613D02*
G03X1027640Y218072I1384J-754D01*
G01Y219647D02*
X1027621Y219613D01*
G01X1027665Y219689D02*
X1027640Y219647D01*
G01X1028100Y221385D02*
G02X1027665Y219689I-3524J0D01*
G01X1028100Y221855D02*
Y221385D01*
G01X1029005Y222760D02*
X1028100Y221855D01*
G01X972911Y264497D02*
X972845Y264610D01*
G01X972930Y262956D02*
G03X972911Y264497I-1384J754D01*
G01Y262922D02*
X972930Y262956D01*
G01X972886Y262880D02*
X972911Y262922D01*
G01Y260597D02*
G02X972886Y262880I2015J1164D01*
G01X972930Y259056D02*
G03X972911Y260597I-1384J754D01*
G01Y259022D02*
X972930Y259056D01*
G01X972886Y258980D02*
X972911Y259022D01*
G01Y256697D02*
G02X972886Y258980I2015J1164D01*
G01X972930Y255156D02*
G03X972911Y256697I-1384J754D01*
G01Y255122D02*
X972930Y255156D01*
G01X972886Y255080D02*
X972911Y255122D01*
G01Y252797D02*
G02X972886Y255080I2015J1164D01*
G01X972930Y251256D02*
G03X972911Y252797I-1384J754D01*
G01Y251222D02*
X972930Y251256D01*
G01X972886Y251180D02*
X972911Y251222D01*
G01Y248897D02*
G02X972886Y251180I2015J1164D01*
G01X972930Y247356D02*
G03X972911Y248897I-1384J754D01*
G01Y247322D02*
X972930Y247356D01*
G01X972886Y247280D02*
X972911Y247322D01*
G01Y244997D02*
G02X972886Y247280I2015J1164D01*
G01X972930Y243456D02*
G03X972911Y244997I-1384J754D01*
G01Y243422D02*
X972930Y243456D01*
G01X972886Y243380D02*
X972911Y243422D01*
G01Y241097D02*
G02X972886Y243380I2015J1164D01*
G01X972930Y239556D02*
G03X972911Y241097I-1384J754D01*
G01Y239522D02*
X972930Y239556D01*
G01X972886Y239480D02*
X972911Y239522D01*
G01Y237197D02*
G02X972886Y239480I2015J1164D01*
G01X972930Y235656D02*
G03X972911Y237197I-1384J754D01*
G01Y235622D02*
X972930Y235656D01*
G01X972886Y235580D02*
X972911Y235622D01*
G01Y233297D02*
G02X972886Y235580I2015J1164D01*
G01X972930Y231756D02*
G03X972911Y233297I-1384J754D01*
G01Y231722D02*
X972930Y231756D01*
G01X972886Y229439D02*
G02X972911Y231722I2040J1119D01*
G01Y229397D02*
X972886Y229439D01*
G01X972911Y227823D02*
G03Y229397I-1365J787D01*
G01Y225497D02*
G02Y227823I2015J1163D01*
G01X972930Y223956D02*
G03X972911Y225497I-1384J754D01*
G01Y223922D02*
X972930Y223956D01*
G01X972886Y223880D02*
X972911Y223922D01*
G01Y221597D02*
G02X972886Y223880I2015J1164D01*
G01X973122Y220809D02*
G03X972911Y221597I-1577J0D01*
G01X973122Y219957D02*
Y220809D01*
G01X972526Y219361D02*
X973122Y219957D01*
G01X1007428Y219764D02*
X1008725Y222760D01*
G01X1007360Y219647D02*
X1007428Y219764D01*
G01X1005415Y218484D02*
G03X1007360Y219647I-70J2325D01*
G01X1005286Y218484D02*
X1005415D01*
G01X995059Y218713D02*
X995206Y218860D01*
G01X987062Y219613D02*
G03X987081Y218072I1384J-754D01*
G01X987149Y219764D02*
X987062Y219613D01*
G01X988446Y222760D02*
X987149Y219764D01*
G01X1001591Y229163D02*
G03X1001965Y230559I-2419J1396D01*
G01X1000601Y227447D02*
X1001591Y229163D01*
G01X1000601Y225873D02*
G02Y227447I1364J787D01*
G01X1000636Y223607D02*
G03X1000601Y225873I-2050J1102D01*
G01Y223547D02*
X1000636Y223607D01*
G01X1000601Y221973D02*
G02Y223547I1364J787D01*
G01X1000636Y219707D02*
G03X1000601Y221973I-2050J1102D01*
G01Y219647D02*
X1000636Y219707D01*
G01X1000601Y218073D02*
G02Y219647I1364J787D01*
G01X997221Y221598D02*
G03Y220024I1365J-787D01*
G01Y223924D02*
G02Y221598I-2015J-1163D01*
G01Y225498D02*
G03Y223924I1365J-787D01*
G01Y227824D02*
G02Y225498I-2015J-1163D01*
G01X997156Y227937D02*
X997221Y227824D01*
G01X995206Y230559D02*
X997156Y227937D01*
G01X999887Y225603D02*
X998586Y228610D01*
G01X999950Y225496D02*
X999887Y225603D01*
G01X999950Y223922D02*
G03Y225496I-1364J787D01*
G01X999915Y223862D02*
X999950Y223922D01*
G01Y221596D02*
G02X999915Y223862I2015J1164D01*
G01X999950Y220022D02*
G03Y221596I-1364J787D01*
G01X999915Y219962D02*
X999950Y220022D01*
G01X1026924Y221710D02*
X1025625Y224709D01*
G01X1026990Y221597D02*
X1026924Y221710D01*
G01X1027009Y220056D02*
G03X1026990Y221597I-1384J754D01*
G01Y220022D02*
X1027009Y220056D01*
G01X1026965Y219980D02*
X1026990Y220022D01*
G01X993969Y221255D02*
X995842Y220303D01*
G01X991826Y224709D02*
X993969Y221255D01*
G01X1032385Y224709D02*
X1030700Y220900D01*
G01X1003349Y219613D02*
G02X1003330Y218072I-1384J-754D01*
G01Y219647D02*
X1003349Y219613D01*
G01X1003305Y219689D02*
X1003330Y219647D01*
G01Y221972D02*
G03X1003305Y219689I2015J-1164D01*
G01X1003591Y222423D02*
X1003330Y221972D01*
G01X1005345Y224709D02*
G03X1003591Y222423I7812J-7810D01*
G01X973352Y268321D02*
X972811Y268862D01*
G01X973352Y265638D02*
Y268321D01*
G01X973561Y264872D02*
G02X973352Y265638I1377J787D01*
G01X973586Y262589D02*
G03X973561Y264872I-2040J1119D01*
G01Y262547D02*
X973586Y262589D01*
G01X973542Y262513D02*
X973561Y262547D01*
G01Y260972D02*
G02X973542Y262513I1365J787D01*
G01X973586Y258689D02*
G03X973561Y260972I-2040J1119D01*
G01Y258647D02*
X973586Y258689D01*
G01X973542Y258613D02*
X973561Y258647D01*
G01Y257072D02*
G02X973542Y258613I1365J787D01*
G01X973586Y254789D02*
G03X973561Y257072I-2040J1119D01*
G01Y254747D02*
X973586Y254789D01*
G01X973542Y254713D02*
X973561Y254747D01*
G01Y253172D02*
G02X973542Y254713I1365J787D01*
G01X973586Y250889D02*
G03X973561Y253172I-2040J1119D01*
G01Y250847D02*
X973586Y250889D01*
G01X973542Y250813D02*
X973561Y250847D01*
G01Y249272D02*
G02X973542Y250813I1365J787D01*
G01X973586Y246989D02*
G03X973561Y249272I-2040J1119D01*
G01Y246947D02*
X973586Y246989D01*
G01X973542Y246913D02*
X973561Y246947D01*
G01Y245372D02*
G02X973542Y246913I1365J787D01*
G01X973586Y243089D02*
G03X973561Y245372I-2040J1119D01*
G01Y243047D02*
X973586Y243089D01*
G01X973542Y243013D02*
X973561Y243047D01*
G01Y241472D02*
G02X973542Y243013I1365J787D01*
G01X973586Y239189D02*
G03X973561Y241472I-2040J1119D01*
G01Y239147D02*
X973586Y239189D01*
G01X973542Y239113D02*
X973561Y239147D01*
G01Y237572D02*
G02X973542Y239113I1365J787D01*
G01X973586Y235289D02*
G03X973561Y237572I-2040J1119D01*
G01Y235247D02*
X973586Y235289D01*
G01X973542Y235213D02*
X973561Y235247D01*
G01Y233672D02*
G02X973542Y235213I1365J787D01*
G01X973561Y231346D02*
G03Y233672I-2015J1163D01*
G01Y229772D02*
G02Y231346I1365J787D01*
G01X973586Y229730D02*
X973561Y229772D01*
G01Y227447D02*
G03X973586Y229730I-2015J1164D01*
G01X973542Y227413D02*
X973561Y227447D01*
G01Y225872D02*
G02X973542Y227413I1365J787D01*
G01X973586Y223589D02*
G03X973561Y225872I-2040J1119D01*
G01Y223547D02*
X973586Y223589D01*
G01X973542Y223513D02*
X973561Y223547D01*
G01Y221972D02*
G02X973542Y223513I1365J787D01*
G01X973873Y220809D02*
G03X973561Y221972I-2327J-1D01*
G01X973873Y219574D02*
Y220809D01*
G01X973277Y218978D02*
X973873Y219574D01*
G01X974856Y322585D02*
G03X972911Y321422I70J-2325D01*
G01X974985Y322585D02*
X974856D01*
G01X976291Y323372D02*
G02X974985Y322585I-1365J788D01*
G01X978255Y324535D02*
G03X976291Y323372I51J-2326D01*
G01X978350Y324535D02*
X978255D01*
G01X979671Y325323D02*
G02X978350Y324535I-1365J787D01*
G01X981601Y326485D02*
G03X979671Y325323I85J-2325D01*
G01X981730Y326485D02*
X981601D01*
G01X983051Y327273D02*
G02X981730Y326485I-1365J787D01*
G01X984981Y328435D02*
G03X983051Y327273I85J-2325D01*
G01X985137Y328435D02*
X984981D01*
G01X986431Y329222D02*
G02X985137Y328435I-1365J787D01*
G01X986450Y329256D02*
X986431Y329222D01*
G01Y330797D02*
G02X986450Y329256I-1365J-787D01*
G01X986406Y333080D02*
G03X986431Y330797I2040J-1119D01*
G01Y333122D02*
X986406Y333080D01*
G01X986450Y333156D02*
X986431Y333122D01*
G01Y334697D02*
G02X986450Y333156I-1365J-787D01*
G01X986406Y336980D02*
G03X986431Y334697I2040J-1119D01*
G01Y337022D02*
X986406Y336980D01*
G01X986450Y337056D02*
X986431Y337022D01*
G01Y338597D02*
G02X986450Y337056I-1365J-787D01*
G01X986406Y340880D02*
G03X986431Y338597I2040J-1119D01*
G01Y340922D02*
X986406Y340880D01*
G01X988376Y342085D02*
G03X986431Y340922I70J-2325D01*
G01X976922Y340956D02*
G02X976941Y342497I1384J754D01*
G01Y340922D02*
X976922Y340956D01*
G01X976966Y340880D02*
X976941Y340922D01*
G01Y338597D02*
G03X976966Y340880I-2015J1164D01*
G01X976922Y337056D02*
G02X976941Y338597I1384J754D01*
G01Y337022D02*
X976922Y337056D01*
G01X976966Y336980D02*
X976941Y337022D01*
G01Y334697D02*
G03X976966Y336980I-2015J1164D01*
G01X976567Y334040D02*
X976941Y334697D01*
G01X975032Y331976D02*
X976567Y334040D01*
G01X974926Y331960D02*
X975032Y331976D01*
G01X1007360Y340547D02*
G03X1008725Y343660I-13429J7744D01*
G01X1005415Y339384D02*
G03X1007360Y340547I-70J2325D01*
G01X1005286Y339384D02*
X1005415D01*
G01X1003980Y338597D02*
G02X1005286Y339384I1365J-788D01*
G01X1002050Y337435D02*
G03X1003980Y338597I-85J2325D01*
G01X1001965Y337435D02*
X1002050D01*
G01X1000614Y336670D02*
G02X1001965Y337435I1351J-810D01*
G01X1000601Y336647D02*
X1000614Y336670D01*
G01X998656Y335484D02*
G03X1000601Y336647I-70J2325D01*
G01X998527Y335484D02*
X998656D01*
G01X997221Y334697D02*
G02X998527Y335484I1365J-788D01*
G01X997202Y333156D02*
G02X997221Y334697I1384J754D01*
G01Y333122D02*
X997202Y333156D01*
G01X997246Y333080D02*
X997221Y333122D01*
G01Y330797D02*
G03X997246Y333080I-2015J1164D01*
G01X997202Y329256D02*
G02X997221Y330797I1384J754D01*
G01Y329222D02*
X997202Y329256D01*
G01X997246Y329180D02*
X997221Y329222D01*
G01Y326897D02*
G03X997246Y329180I-2015J1164D01*
G01X997221Y325323D02*
G02Y326897I1365J787D01*
G01Y322997D02*
G03Y325323I-2015J1163D01*
G01X995291Y321835D02*
G03X997221Y322997I-85J2325D01*
G01X995162Y321835D02*
X995291D01*
G01X993841Y321047D02*
G02X995162Y321835I1365J-787D01*
G01X991896Y319884D02*
G03X993841Y321047I-70J2325D01*
G01X991767Y319884D02*
X991896D01*
G01X990461Y319097D02*
G02X991767Y319884I1365J-788D01*
G01X988531Y317935D02*
G03X990461Y319097I-85J2325D01*
G01X988402Y317935D02*
X988531D01*
G01X987081Y317147D02*
G02X988402Y317935I1365J-787D01*
G01X985136Y315984D02*
G03X987081Y317147I-70J2325D01*
G01X985007Y315984D02*
X985136D01*
G01X983701Y315197D02*
G02X985007Y315984I1365J-788D01*
G01X981771Y314035D02*
G03X983701Y315197I-85J2325D01*
G01X981642Y314035D02*
X981771D01*
G01X980321Y313247D02*
G02X981642Y314035I1365J-787D01*
G01X978376Y312084D02*
G03X980321Y313247I-70J2325D01*
G01X978247Y312084D02*
X978376D01*
G01X976941Y311297D02*
G02X978247Y312084I1365J-788D01*
G01X975011Y310135D02*
G03X976941Y311297I-85J2325D01*
G01X974882Y310135D02*
X975011D01*
G01X973561Y309347D02*
G02X974882Y310135I1365J-787D01*
G01X972930Y340956D02*
G03X972911Y342497I-1384J754D01*
G01Y340922D02*
X972930Y340956D01*
G01X972886Y340880D02*
X972911Y340922D01*
G01Y338597D02*
G02X972886Y340880I2015J1164D01*
G01X972930Y337056D02*
G03X972911Y338597I-1384J754D01*
G01X972709Y336672D02*
X972930Y337056D01*
G01X973586Y340589D02*
G03X973561Y342872I-2040J1119D01*
G01Y340547D02*
X973586Y340589D01*
G01X973542Y340513D02*
X973561Y340547D01*
G01Y338972D02*
G02X973542Y340513I1365J787D01*
G01X973586Y336689D02*
G03X973561Y338972I-2040J1119D01*
G01Y336647D02*
X973586Y336689D01*
G01X973216Y336041D02*
X973561Y336647D01*
G01X999950Y340922D02*
G02X1001895Y342085I2015J-1162D01*
G01X999937Y340899D02*
X999950Y340922D01*
G01X998586Y340134D02*
G03X999937Y340899I0J1575D01*
G01X998501Y340134D02*
X998586D01*
G01X996571Y338972D02*
G02X998501Y340134I2015J-1163D01*
G01X995265Y338185D02*
G03X996571Y338972I-59J1575D01*
G01X995136Y338185D02*
X995265D01*
G01X993191Y337022D02*
G02X995136Y338185I2015J-1162D01*
G01X993166Y336980D02*
X993191Y337022D01*
G01Y334697D02*
G02X993166Y336980I2015J1164D01*
G01X993210Y333156D02*
G03X993191Y334697I-1384J754D01*
G01Y333122D02*
X993210Y333156D01*
G01X993166Y333080D02*
X993191Y333122D01*
G01Y330797D02*
G02X993166Y333080I2015J1164D01*
G01X993210Y329256D02*
G03X993191Y330797I-1384J754D01*
G01Y329222D02*
X993210Y329256D01*
G01X993166Y329180D02*
X993191Y329222D01*
G01Y326897D02*
G02X993166Y329180I2015J1164D01*
G01X993191Y325323D02*
G03Y326897I-1365J787D01*
G01X991870Y324535D02*
G03X993191Y325323I-44J1575D01*
G01X991775Y324535D02*
X991870D01*
G01X989811Y323372D02*
G02X991775Y324535I2015J-1163D01*
G01X988505Y322585D02*
G03X989811Y323372I-59J1575D01*
G01X988376Y322585D02*
X988505D01*
G01X986431Y321422D02*
G02X988376Y322585I2015J-1162D01*
G01X985110Y320634D02*
G03X986431Y321422I-44J1575D01*
G01X984981Y320634D02*
X985110D01*
G01X983051Y319472D02*
G02X984981Y320634I2015J-1163D01*
G01X981745Y318685D02*
G03X983051Y319472I-59J1575D01*
G01X981616Y318685D02*
X981745D01*
G01X979671Y317522D02*
G02X981616Y318685I2015J-1162D01*
G01X978350Y316734D02*
G03X979671Y317522I-44J1575D01*
G01X978221Y316734D02*
X978350D01*
G01X976291Y315572D02*
G02X978221Y316734I2015J-1163D01*
G01X974985Y314785D02*
G03X976291Y315572I-59J1575D01*
G01X974856Y314785D02*
X974985D01*
G01X972911Y313622D02*
G02X974856Y314785I2015J-1162D01*
G01X993191Y340922D02*
G02X995136Y342085I2015J-1162D01*
G01X991870Y340134D02*
G03X993191Y340922I-44J1575D01*
G01X991741Y340134D02*
X991870D01*
G01X989811Y338972D02*
G02X991741Y340134I2015J-1163D01*
G01X989786Y336689D02*
G02X989811Y338972I2040J1119D01*
G01Y336647D02*
X989786Y336689D01*
G01X989830Y336613D02*
X989811Y336647D01*
G01Y335072D02*
G03X989830Y336613I-1365J787D01*
G01X989786Y332789D02*
G02X989811Y335072I2040J1119D01*
G01Y332747D02*
X989786Y332789D01*
G01X989830Y332713D02*
X989811Y332747D01*
G01Y331172D02*
G03X989830Y332713I-1365J787D01*
G01X989786Y328889D02*
G02X989811Y331172I2040J1119D01*
G01Y328847D02*
X989786Y328889D01*
G01X989811Y327273D02*
G03Y328847I-1365J787D01*
G01X988490Y326485D02*
G03X989811Y327273I-44J1575D01*
G01X988361Y326485D02*
X988490D01*
G01X986431Y325323D02*
G02X988361Y326485I2015J-1163D01*
G01X985110Y324535D02*
G03X986431Y325323I-44J1575D01*
G01X985015Y324535D02*
X985110D01*
G01X983051Y323372D02*
G02X985015Y324535I2015J-1163D01*
G01X981745Y322585D02*
G03X983051Y323372I-59J1575D01*
G01X981616Y322585D02*
X981745D01*
G01X979671Y321422D02*
G02X981616Y322585I2015J-1162D01*
G01X978350Y320634D02*
G03X979671Y321422I-44J1575D01*
G01X978221Y320634D02*
X978350D01*
G01X976291Y319472D02*
G02X978221Y320634I2015J-1163D01*
G01X974985Y318685D02*
G03X976291Y319472I-59J1575D01*
G01X974856Y318685D02*
X974985D01*
G01X972911Y317522D02*
G02X974856Y318685I2015J-1162D01*
G01X1006710Y340922D02*
G03X1007164Y343442I-3282J1892D01*
G01X1005389Y340134D02*
G03X1006710Y340922I-44J1575D01*
G01X1005260Y340134D02*
X1005389D01*
G01X1003330Y338972D02*
G02X1005260Y340134I2015J-1163D01*
G01X1002024Y338185D02*
G03X1003330Y338972I-59J1575D01*
G01X1001895Y338185D02*
X1002024D01*
G01X999950Y337022D02*
G02X1001895Y338185I2015J-1162D01*
G01X999937Y336999D02*
X999950Y337022D01*
G01X998586Y336234D02*
G03X999937Y336999I0J1575D01*
G01X998501Y336234D02*
X998586D01*
G01X996571Y335072D02*
G02X998501Y336234I2015J-1163D01*
G01X996546Y332789D02*
G02X996571Y335072I2040J1119D01*
G01Y332747D02*
X996546Y332789D01*
G01X996590Y332713D02*
X996571Y332747D01*
G01Y331172D02*
G03X996590Y332713I-1365J787D01*
G01X996546Y328889D02*
G02X996571Y331172I2040J1119D01*
G01Y328847D02*
X996546Y328889D01*
G01X996571Y327273D02*
G03Y328847I-1365J787D01*
G01Y324947D02*
G02Y327273I2015J1163D01*
G01X996590Y324913D02*
X996571Y324947D01*
G01Y323372D02*
G03X996590Y324913I-1365J787D01*
G01X995265Y322585D02*
G03X996571Y323372I-59J1575D01*
G01X995136Y322585D02*
X995265D01*
G01X993191Y321422D02*
G02X995136Y322585I2015J-1162D01*
G01X991870Y320634D02*
G03X993191Y321422I-44J1575D01*
G01X991741Y320634D02*
X991870D01*
G01X989811Y319472D02*
G02X991741Y320634I2015J-1163D01*
G01X988505Y318685D02*
G03X989811Y319472I-59J1575D01*
G01X988376Y318685D02*
X988505D01*
G01X986431Y317522D02*
G02X988376Y318685I2015J-1162D01*
G01X985110Y316734D02*
G03X986431Y317522I-44J1575D01*
G01X984981Y316734D02*
X985110D01*
G01X983051Y315572D02*
G02X984981Y316734I2015J-1163D01*
G01X981745Y314785D02*
G03X983051Y315572I-59J1575D01*
G01X981616Y314785D02*
X981745D01*
G01X979671Y313622D02*
G02X981616Y314785I2015J-1162D01*
G01X978350Y312834D02*
G03X979671Y313622I-44J1575D01*
G01X978221Y312834D02*
X978350D01*
G01X976291Y311672D02*
G02X978221Y312834I2015J-1163D01*
G01X974985Y310885D02*
G03X976291Y311672I-59J1575D01*
G01X974856Y310885D02*
X974985D01*
G01X972911Y309722D02*
G02X974856Y310885I2015J-1162D01*
G01X974882Y314035D02*
G03X973561Y313247I44J-1575D01*
G01X975011Y314035D02*
X974882D01*
G01X976941Y315197D02*
G02X975011Y314035I-2015J1163D01*
G01X978247Y315984D02*
G03X976941Y315197I59J-1575D01*
G01X978376Y315984D02*
X978247D01*
G01X980321Y317147D02*
G02X978376Y315984I-2015J1162D01*
G01X981642Y317935D02*
G03X980321Y317147I44J-1575D01*
G01X981771Y317935D02*
X981642D01*
G01X983701Y319097D02*
G02X981771Y317935I-2015J1163D01*
G01X985007Y319884D02*
G03X983701Y319097I59J-1575D01*
G01X985136Y319884D02*
X985007D01*
G01X987081Y321047D02*
G02X985136Y319884I-2015J1162D01*
G01X988402Y321835D02*
G03X987081Y321047I44J-1575D01*
G01X988531Y321835D02*
X988402D01*
G01X990461Y322997D02*
G02X988531Y321835I-2015J1163D01*
G01X991767Y323784D02*
G03X990461Y322997I59J-1575D01*
G01X991877Y323784D02*
X991767D01*
G01X993841Y324947D02*
G02X991877Y323784I-2015J1163D01*
G01X993841Y327273D02*
G02Y324947I-2015J-1163D01*
G01Y328847D02*
G03Y327273I1365J-787D01*
G01X993866Y328889D02*
X993841Y328847D01*
G01Y331172D02*
G02X993866Y328889I-2015J-1164D01*
G01X993822Y332713D02*
G03X993841Y331172I1384J-754D01*
G01Y332747D02*
X993822Y332713D01*
G01X993866Y332789D02*
X993841Y332747D01*
G01Y335072D02*
G02X993866Y332789I-2015J-1164D01*
G01X993822Y336613D02*
G03X993841Y335072I1384J-754D01*
G01Y336647D02*
X993822Y336613D01*
G01X995162Y337435D02*
G03X993841Y336647I44J-1575D01*
G01X995291Y337435D02*
X995162D01*
G01X997221Y338597D02*
G02X995291Y337435I-2015J1163D01*
G01X998527Y339384D02*
G03X997221Y338597I59J-1575D01*
G01X998656Y339384D02*
X998527D01*
G01X1000601Y340547D02*
G02X998656Y339384I-2015J1162D01*
G01X1000614Y340570D02*
X1000601Y340547D01*
G01X1001965Y341335D02*
G03X1000614Y340570I0J-1575D01*
G01X974882Y321835D02*
G03X973561Y321047I44J-1575D01*
G01X975011Y321835D02*
X974882D01*
G01X976941Y322997D02*
G02X975011Y321835I-2015J1163D01*
G01X978247Y323784D02*
G03X976941Y322997I59J-1575D01*
G01X978357Y323784D02*
X978247D01*
G01X980321Y324947D02*
G02X978357Y323784I-2015J1163D01*
G01X981642Y325735D02*
G03X980321Y324947I44J-1575D01*
G01X981771Y325735D02*
X981642D01*
G01X983701Y326897D02*
G02X981771Y325735I-2015J1163D01*
G01X984995Y327684D02*
G03X983701Y326897I71J-1574D01*
G01X985136Y327684D02*
X984995D01*
G01X987081Y328847D02*
G02X985136Y327684I-2015J1162D01*
G01X987106Y328889D02*
X987081Y328847D01*
G01Y331172D02*
G02X987106Y328889I-2015J-1164D01*
G01X987062Y332713D02*
G03X987081Y331172I1384J-754D01*
G01Y332747D02*
X987062Y332713D01*
G01X987106Y332789D02*
X987081Y332747D01*
G01Y335072D02*
G02X987106Y332789I-2015J-1164D01*
G01X987062Y336613D02*
G03X987081Y335072I1384J-754D01*
G01Y336647D02*
X987062Y336613D01*
G01X987106Y336689D02*
X987081Y336647D01*
G01Y338972D02*
G02X987106Y336689I-2015J-1164D01*
G01X987062Y340513D02*
G03X987081Y338972I1384J-754D01*
G01Y340547D02*
X987062Y340513D01*
G01X988402Y341335D02*
G03X987081Y340547I44J-1575D01*
G01X976266Y340589D02*
G02X976291Y342872I2040J1119D01*
G01Y340547D02*
X976266Y340589D01*
G01X976310Y340513D02*
X976291Y340547D01*
G01Y338972D02*
G03X976310Y340513I-1365J787D01*
G01X976266Y336689D02*
G02X976291Y338972I2040J1119D01*
G01Y336647D02*
X976266Y336689D01*
G01X976310Y336613D02*
X976291Y336647D01*
G01Y335072D02*
G03X976310Y336613I-1365J787D01*
G01X976126Y334787D02*
X976291Y335072D01*
G01X975791Y334377D02*
X976126Y334787D01*
G01X975564Y334173D02*
X975791Y334377D01*
G01X974544Y333489D02*
X975564Y334173D01*
G01X973561Y331172D02*
G02X974544Y333489I1365J788D01*
G01X973627Y331059D02*
X973561Y331172D01*
G01X974926Y328060D02*
X973627Y331059D01*
G01X1005271Y397271D02*
Y406071D01*
G01X1002576Y394576D02*
X1005271Y397271D01*
G01X1002576Y388695D02*
Y394576D01*
G01X1003349Y387313D02*
X1002576Y388695D01*
G01X1003330Y385772D02*
G03X1003349Y387313I-1365J787D01*
G01X1003305Y383489D02*
G02X1003330Y385772I2040J1119D01*
G01Y383447D02*
X1003305Y383489D01*
G01X1003349Y383413D02*
X1003330Y383447D01*
G01Y381872D02*
G03X1003349Y383413I-1365J787D01*
G01X1005275Y378384D02*
G02X1003330Y381872I70J2325D01*
G01X1005404Y378384D02*
X1005275D01*
G01X1006729Y376056D02*
G03X1005404Y378384I-1384J753D01*
G01X1006710Y376022D02*
X1006729Y376056D01*
G01X1006685Y375980D02*
X1006710Y376022D01*
G01X1006533Y375642D02*
G02X1006685Y375980I2191J-782D01*
G01X1005345Y372909D02*
X1006533Y375642D01*
G01X988505Y342085D02*
X988376D01*
G01X989811Y342872D02*
G02X988505Y342085I-1365J788D01*
G01X991741Y344034D02*
G03X989811Y342872I85J-2325D01*
G01X991870Y344034D02*
X991741D01*
G01X993191Y344822D02*
G02X991870Y344034I-1365J787D01*
G01X995136Y345985D02*
G03X993191Y344822I70J-2325D01*
G01X995265Y345985D02*
X995136D01*
G01X996571Y346772D02*
G02X995265Y345985I-1365J788D01*
G01X998501Y347934D02*
G03X996571Y346772I85J-2325D01*
G01X998586Y347934D02*
X998501D01*
G01X999937Y348699D02*
G02X998586Y347934I-1351J810D01*
G01X999950Y348722D02*
X999937Y348699D01*
G01X1001895Y349885D02*
G03X999950Y348722I70J-2325D01*
G01X1002024Y349885D02*
X1001895D01*
G01X1003330Y350672D02*
G02X1002024Y349885I-1365J788D01*
G01X1005260Y351834D02*
G03X1003330Y350672I85J-2325D01*
G01X1005389Y351834D02*
X1005260D01*
G01X1006710Y352622D02*
G02X1005389Y351834I-1365J787D01*
G01X1008655Y353785D02*
G03X1006710Y352622I70J-2325D01*
G01X1008795Y353785D02*
X1008655D01*
G01X1010740Y352622D02*
G03X1008795Y353785I-2015J-1162D01*
G01X1012061Y351834D02*
G02X1010740Y352622I44J1575D01*
G01X1012190Y351834D02*
X1012061D01*
G01X1014120Y350672D02*
G03X1012190Y351834I-2015J-1163D01*
G01X1015426Y349885D02*
G02X1014120Y350672I59J1575D01*
G01X1015544Y349885D02*
X1015426D01*
G01X1016850Y350672D02*
G02X1015544Y349885I-1365J788D01*
G01X1018780Y351834D02*
G03X1016850Y350672I85J-2325D01*
G01X1018909Y351834D02*
X1018780D01*
G01X1020230Y352622D02*
G02X1018909Y351834I-1365J787D01*
G01X1022175Y353785D02*
G03X1020230Y352622I70J-2325D01*
G01X1022304Y353785D02*
X1022175D01*
G01X1023610Y354572D02*
G02X1022304Y353785I-1365J788D01*
G01X1025540Y355734D02*
G03X1023610Y354572I85J-2325D01*
G01X1025669Y355734D02*
X1025540D01*
G01X1026990Y356522D02*
G02X1025669Y355734I-1365J787D01*
G01X1028935Y357685D02*
G03X1026990Y356522I70J-2325D01*
G01X1029064Y357685D02*
X1028935D01*
G01X1030370Y358472D02*
G02X1029064Y357685I-1365J788D01*
G01X1032300Y359634D02*
G03X1030370Y358472I85J-2325D01*
G01X1032470Y359634D02*
X1032300D01*
G01X1034400Y358472D02*
G03X1032470Y359634I-2015J-1163D01*
G01X988354Y388694D02*
Y400454D01*
G01X986872Y387212D02*
X988354Y388694D01*
G01X986872Y386276D02*
Y387212D01*
G01X987145Y385617D02*
G02X986872Y386276I659J659D01*
G01X987179Y385583D02*
X987145Y385617D01*
G01X987106Y383489D02*
G03X987179Y385583I-2040J1119D01*
G01X987081Y383447D02*
X987106Y383489D01*
G01X987062Y383413D02*
X987081Y383447D01*
G01Y381872D02*
G02X987062Y383413I1365J787D01*
G01X987147Y381759D02*
X987081Y381872D01*
G01X988446Y378760D02*
X987147Y381759D01*
G01X979604Y382209D02*
Y405013D01*
G01X976940Y377599D02*
X979604Y382209D01*
G01X976941Y377597D02*
X976940Y377599D01*
G01X976922Y376056D02*
G02X976941Y377597I1384J754D01*
G01Y376022D02*
X976922Y376056D01*
G01X976966Y375980D02*
X976941Y376022D01*
G01Y373697D02*
G03X976966Y375980I-2015J1164D01*
G01X976922Y372156D02*
G02X976941Y373697I1384J754D01*
G01Y372122D02*
X976922Y372156D01*
G01X976966Y369839D02*
G03X976941Y372122I-2040J1119D01*
G01Y369797D02*
X976966Y369839D01*
G01X976941Y368223D02*
G02Y369797I1365J787D01*
G01Y365897D02*
G03Y368223I-2015J1163D01*
G01X976922Y364356D02*
G02X976941Y365897I1384J754D01*
G01Y364322D02*
X976922Y364356D01*
G01X976966Y364280D02*
X976941Y364322D01*
G01Y361997D02*
G03X976966Y364280I-2015J1164D01*
G01X976922Y360456D02*
G02X976941Y361997I1384J754D01*
G01Y360422D02*
X976922Y360456D01*
G01X976966Y360380D02*
X976941Y360422D01*
G01Y358097D02*
G03X976966Y360380I-2015J1164D01*
G01X976922Y356556D02*
G02X976941Y358097I1384J754D01*
G01Y356522D02*
X976922Y356556D01*
G01X976966Y356480D02*
X976941Y356522D01*
G01Y354197D02*
G03X976966Y356480I-2015J1164D01*
G01X976922Y352656D02*
G02X976941Y354197I1384J754D01*
G01Y352622D02*
X976922Y352656D01*
G01X976966Y352580D02*
X976941Y352622D01*
G01Y350297D02*
G03X976966Y352580I-2015J1164D01*
G01X976922Y348756D02*
G02X976941Y350297I1384J754D01*
G01Y348722D02*
X976922Y348756D01*
G01X976966Y348680D02*
X976941Y348722D01*
G01Y346397D02*
G03X976966Y348680I-2015J1164D01*
G01X976922Y344856D02*
G02X976941Y346397I1384J754D01*
G01Y344822D02*
X976922Y344856D01*
G01X976966Y344780D02*
X976941Y344822D01*
G01Y342497D02*
G03X976966Y344780I-2015J1164D01*
G01X1032385Y372909D02*
X1033682Y375905D01*
G01X1012826Y397026D02*
Y404227D01*
G01X1010526Y394726D02*
X1012826Y397026D01*
G01X1010526Y388040D02*
Y394726D01*
G01X1012105Y384609D02*
X1010526Y388040D01*
G01X1002500Y398814D02*
Y404000D01*
G01X996996Y393310D02*
X1002500Y398814D01*
G01X996996Y392013D02*
Y393310D01*
G01X997221Y391623D02*
X996996Y392013D01*
G01X997221Y389297D02*
G03Y391623I-2015J1163D01*
G01Y387723D02*
G02Y389297I1365J787D01*
G01Y385397D02*
G03Y387723I-2015J1163D01*
G01X997202Y383856D02*
G02X997221Y385397I1384J754D01*
G01X997289Y383705D02*
X997202Y383856D01*
G01X998586Y380709D02*
X997289Y383705D01*
G01X1003500Y398500D02*
Y405250D01*
G01X1000372Y395372D02*
X1003500Y398500D01*
G01X1000372Y388570D02*
Y395372D01*
G01X999950Y387722D02*
G03X1000372Y388570I-6161J3595D01*
G01X999915Y387662D02*
X999950Y387722D01*
G01Y385396D02*
G02X999915Y387662I2015J1164D01*
G01X999950Y383822D02*
G03Y385396I-1364J787D01*
G01X999915Y383762D02*
X999950Y383822D01*
G01Y381496D02*
G02X999915Y383762I2015J1164D01*
G01X999950Y379922D02*
G03Y381496I-1364J787D01*
G01X999915Y379862D02*
X999950Y379922D01*
G01Y377596D02*
G02X999915Y379862I2015J1164D01*
G01X999950Y376022D02*
G03Y377596I-1364J787D01*
G01X999915Y375962D02*
X999950Y376022D01*
G01Y373696D02*
G02X999915Y375962I2015J1164D01*
G01X999950Y372122D02*
G03Y373696I-1364J787D01*
G01X999726Y371593D02*
G02X999950Y372122I2238J-636D01*
G01X998586Y369010D02*
G02X999726Y371593I3496J0D01*
G01X1027600Y399864D02*
X1031800Y404064D01*
G01X1027600Y393900D02*
Y399864D01*
G01X1026990Y391623D02*
G03X1027600Y393900I-3945J2277D01*
G01X1026990Y389297D02*
G02Y391623I2015J1163D01*
G01X1027009Y387756D02*
G03X1026990Y389297I-1384J754D01*
G01X1026922Y387605D02*
X1027009Y387756D01*
G01X1025625Y384609D02*
X1026922Y387605D01*
G01X994398Y395584D02*
Y396937D01*
G01X993458Y394644D02*
X994398Y395584D01*
G01X993458Y392089D02*
Y394644D01*
G01X993012Y391317D02*
X993458Y392089D01*
G01X993026Y391271D02*
G02X993012Y391317I2219J701D01*
G01X993191Y389297D02*
G02X993026Y391271I2015J1162D01*
G01X993210Y387756D02*
G03X993191Y389297I-1384J754D01*
G01Y387722D02*
X993210Y387756D01*
G01X993166Y387680D02*
X993191Y387722D01*
G01Y385397D02*
G02X993166Y387680I2015J1164D01*
G01X993210Y383856D02*
G03X993191Y385397I-1384J754D01*
G01Y383822D02*
X993210Y383856D01*
G01X993166Y383780D02*
X993191Y383822D01*
G01Y381497D02*
G02X993166Y383780I2015J1164D01*
G01X993210Y379956D02*
G03X993191Y381497I-1384J754D01*
G01Y379922D02*
X993210Y379956D01*
G01X993166Y379880D02*
X993191Y379922D01*
G01Y377597D02*
G02X993166Y379880I2015J1164D01*
G01X993210Y376056D02*
G03X993191Y377597I-1384J754D01*
G01X993123Y375905D02*
X993210Y376056D01*
G01X991826Y372909D02*
X993123Y375905D01*
G01X1010426Y398526D02*
Y405327D01*
G01X1008200Y396300D02*
X1010426Y398526D01*
G01X1008200Y388600D02*
Y396300D01*
G01X1007666Y387727D02*
G03X1008200Y388600I-1223J1348D01*
G01X1007360Y385772D02*
G02X1007666Y387727I1365J788D01*
G01X1007385Y383489D02*
G03X1007360Y385772I-2040J1119D01*
G01Y383447D02*
X1007385Y383489D01*
G01X1007341Y383413D02*
X1007360Y383447D01*
G01Y381872D02*
G02X1007341Y383413I1365J787D01*
G01X1007426Y381759D02*
X1007360Y381872D01*
G01X1008725Y378760D02*
X1007426Y381759D01*
G01X996398Y395698D02*
Y397118D01*
G01X994576Y393876D02*
X996398Y395698D01*
G01X994576Y392522D02*
Y393876D01*
G01X994574Y392520D02*
X994576Y392522D01*
G01X993840Y391249D02*
X994574Y392520D01*
G01X993841Y391247D02*
G02X993840Y391249I1405J704D01*
G01Y391248D02*
X993841Y391247D01*
G01X993822Y391213D02*
X993840Y391248D01*
G01X993841Y389672D02*
G02X993822Y391213I1365J787D01*
G01X993866Y387389D02*
G03X993841Y389672I-2040J1119D01*
G01Y387347D02*
X993866Y387389D01*
G01X993822Y387313D02*
X993841Y387347D01*
G01Y385772D02*
G02X993822Y387313I1365J787D01*
G01X993866Y383489D02*
G03X993841Y385772I-2040J1119D01*
G01Y383447D02*
X993866Y383489D01*
G01X993822Y383413D02*
X993841Y383447D01*
G01Y381872D02*
G02X993822Y383413I1365J787D01*
G01X993907Y381759D02*
X993841Y381872D01*
G01X995206Y378760D02*
X993907Y381759D01*
G01X1031700Y398400D02*
X1037120Y403820D01*
G01X1031700Y390400D02*
Y398400D01*
G01X1031020Y389297D02*
G02X1031700Y390400I19055J-10986D01*
G01X1031001Y387756D02*
G02X1031020Y389297I1384J754D01*
G01Y387722D02*
X1031001Y387756D01*
G01X1031045Y387680D02*
X1031020Y387722D01*
G01Y385397D02*
G03X1031045Y387680I-2015J1164D01*
G01X1031001Y383856D02*
G02X1031020Y385397I1384J754D01*
G01Y383822D02*
X1031001Y383856D01*
G01X1031045Y383780D02*
X1031020Y383822D01*
G01Y381497D02*
G03X1031045Y383780I-2015J1164D01*
G01X1031001Y379956D02*
G02X1031020Y381497I1384J754D01*
G01Y379922D02*
X1031001Y379956D01*
G01X1031045Y379880D02*
X1031020Y379922D01*
G01Y377597D02*
G03X1031045Y379880I-2015J1164D01*
G01X1030812Y376905D02*
G02X1031020Y377597I1573J-96D01*
G01X1029005Y374860D02*
G03X1030812Y376905I-254J2045D01*
G01X990354Y399790D02*
Y401003D01*
G01X989150Y398586D02*
X990354Y399790D01*
G01X989150Y388250D02*
Y398586D01*
G01X989260Y388140D02*
X989150Y388250D01*
G01X989639Y387714D02*
X989260Y388140D01*
G01X989786Y387389D02*
G02X989639Y387714I2040J1119D01*
G01X989811Y387347D02*
X989786Y387389D01*
G01X989830Y387313D02*
X989811Y387347D01*
G01Y385772D02*
G03X989830Y387313I-1365J787D01*
G01X989786Y383489D02*
G02X989811Y385772I2040J1119D01*
G01Y383447D02*
X989786Y383489D01*
G01X989830Y383413D02*
X989811Y383447D01*
G01Y381872D02*
G03X989830Y383413I-1365J787D01*
G01X989786Y379589D02*
G02X989811Y381872I2040J1119D01*
G01Y379547D02*
X989786Y379589D01*
G01X989830Y379513D02*
X989811Y379547D01*
G01Y377972D02*
G03X989830Y379513I-1365J787D01*
G01X989745Y377859D02*
X989811Y377972D01*
G01X988446Y374860D02*
X989745Y377859D01*
G01X973540Y402825D02*
Y403096D01*
G01X972556Y385441D02*
Y396041D01*
G01X973301Y384696D02*
X972556Y385441D01*
G01X973301Y380617D02*
Y384696D01*
G01X972886Y379880D02*
X973301Y380617D01*
G01X972911Y377597D02*
G02X972886Y379880I2015J1164D01*
G01X972930Y376056D02*
G03X972911Y377597I-1384J754D01*
G01Y376022D02*
X972930Y376056D01*
G01X972886Y375980D02*
X972911Y376022D01*
G01Y373697D02*
G02X972886Y375980I2015J1164D01*
G01X972930Y372156D02*
G03X972911Y373697I-1384J754D01*
G01Y372122D02*
X972930Y372156D01*
G01X972886Y369839D02*
G02X972911Y372122I2040J1119D01*
G01Y369797D02*
X972886Y369839D01*
G01X972911Y368223D02*
G03Y369797I-1365J787D01*
G01Y365897D02*
G02Y368223I2015J1163D01*
G01X972930Y364356D02*
G03X972911Y365897I-1384J754D01*
G01Y364322D02*
X972930Y364356D01*
G01X972886Y364280D02*
X972911Y364322D01*
G01Y361997D02*
G02X972886Y364280I2015J1164D01*
G01X972930Y360456D02*
G03X972911Y361997I-1384J754D01*
G01Y360422D02*
X972930Y360456D01*
G01X972886Y360380D02*
X972911Y360422D01*
G01Y358097D02*
G02X972886Y360380I2015J1164D01*
G01X972930Y356556D02*
G03X972911Y358097I-1384J754D01*
G01Y356522D02*
X972930Y356556D01*
G01X972886Y356480D02*
X972911Y356522D01*
G01Y354197D02*
G02X972886Y356480I2015J1164D01*
G01X972930Y352656D02*
G03X972911Y354197I-1384J754D01*
G01Y352622D02*
X972930Y352656D01*
G01X972886Y352580D02*
X972911Y352622D01*
G01Y350297D02*
G02X972886Y352580I2015J1164D01*
G01X972930Y348756D02*
G03X972911Y350297I-1384J754D01*
G01Y348722D02*
X972930Y348756D01*
G01X972886Y348680D02*
X972911Y348722D01*
G01Y346397D02*
G02X972886Y348680I2015J1164D01*
G01X972930Y344856D02*
G03X972911Y346397I-1384J754D01*
G01Y344822D02*
X972930Y344856D01*
G01X972886Y344780D02*
X972911Y344822D01*
G01Y342497D02*
G02X972886Y344780I2015J1164D01*
G01X1030700Y399404D02*
X1035400Y404104D01*
G01X1030700Y391000D02*
Y399404D01*
G01X1030370Y389672D02*
G03X1030700Y391000I-2142J1237D01*
G01X1030345Y387389D02*
G02X1030370Y389672I2040J1119D01*
G01Y387347D02*
X1030345Y387389D01*
G01X1030389Y387313D02*
X1030370Y387347D01*
G01Y385772D02*
G03X1030389Y387313I-1365J787D01*
G01X1030345Y383489D02*
G02X1030370Y385772I2040J1119D01*
G01Y383447D02*
X1030345Y383489D01*
G01X1030389Y383413D02*
X1030370Y383447D01*
G01Y381872D02*
G03X1030389Y383413I-1365J787D01*
G01X1030345Y379589D02*
G02X1030370Y381872I2040J1119D01*
G01Y379547D02*
X1030345Y379589D01*
G01X1030389Y379513D02*
X1030370Y379547D01*
G01X1029064Y377185D02*
G03X1030389Y379513I-59J1575D01*
G01X1028935Y377185D02*
X1029064D01*
G01X1026990Y376022D02*
G02X1028935Y377185I2015J-1162D01*
G01X1026922Y375905D02*
X1026990Y376022D01*
G01X1025625Y372909D02*
X1026922Y375905D01*
G01X974288Y402938D02*
X975212Y403862D01*
G01X974288Y402515D02*
Y402938D01*
G01X972304Y400531D02*
X974288Y402515D01*
G01X972304Y397351D02*
Y400531D01*
G01X973304Y396351D02*
X972304Y397351D01*
G01X973304Y385751D02*
Y396351D01*
G01X974049Y385006D02*
X973304Y385751D01*
G01X974049Y380420D02*
Y385006D01*
G01X973542Y379513D02*
X974049Y380420D01*
G01X973561Y377972D02*
G02X973542Y379513I1365J787D01*
G01X973586Y375689D02*
G03X973561Y377972I-2040J1119D01*
G01Y375647D02*
X973586Y375689D01*
G01X973542Y375613D02*
X973561Y375647D01*
G01Y374072D02*
G02X973542Y375613I1365J787D01*
G01X973561Y371746D02*
G03Y374072I-2015J1163D01*
G01Y370172D02*
G02Y371746I1365J787D01*
G01X973586Y370130D02*
X973561Y370172D01*
G01Y367847D02*
G03X973586Y370130I-2015J1164D01*
G01X973542Y367813D02*
X973561Y367847D01*
G01Y366272D02*
G02X973542Y367813I1365J787D01*
G01X973586Y363989D02*
G03X973561Y366272I-2040J1119D01*
G01Y363947D02*
X973586Y363989D01*
G01X973542Y363913D02*
X973561Y363947D01*
G01Y362372D02*
G02X973542Y363913I1365J787D01*
G01X973586Y360089D02*
G03X973561Y362372I-2040J1119D01*
G01Y360047D02*
X973586Y360089D01*
G01X973542Y360013D02*
X973561Y360047D01*
G01Y358472D02*
G02X973542Y360013I1365J787D01*
G01X973586Y356189D02*
G03X973561Y358472I-2040J1119D01*
G01Y356147D02*
X973586Y356189D01*
G01X973542Y356113D02*
X973561Y356147D01*
G01Y354572D02*
G02X973542Y356113I1365J787D01*
G01X973586Y352289D02*
G03X973561Y354572I-2040J1119D01*
G01Y352247D02*
X973586Y352289D01*
G01X973542Y352213D02*
X973561Y352247D01*
G01Y350672D02*
G02X973542Y352213I1365J787D01*
G01X973586Y348389D02*
G03X973561Y350672I-2040J1119D01*
G01Y348347D02*
X973586Y348389D01*
G01X973542Y348313D02*
X973561Y348347D01*
G01Y346772D02*
G02X973542Y348313I1365J787D01*
G01X973586Y344489D02*
G03X973561Y346772I-2040J1119D01*
G01Y344447D02*
X973586Y344489D01*
G01X973542Y344413D02*
X973561Y344447D01*
G01Y342872D02*
G02X973542Y344413I1365J787D01*
G01X1006710Y344822D02*
G02X1008725Y347560I13242J-7634D01*
G01X1005389Y344034D02*
G03X1006710Y344822I-44J1575D01*
G01X1005260Y344034D02*
X1005389D01*
G01X1003330Y342872D02*
G02X1005260Y344034I2015J-1163D01*
G01X1002024Y342085D02*
G03X1003330Y342872I-59J1575D01*
G01X1001895Y342085D02*
X1002024D01*
G01X1006021Y396521D02*
Y405321D01*
G01X1003771Y394271D02*
X1006021Y396521D01*
G01X1003771Y388096D02*
Y394271D01*
G01X1003980Y387722D02*
X1003771Y388096D01*
G01X1004005Y387680D02*
X1003980Y387722D01*
G01Y385397D02*
G03X1004005Y387680I-2015J1164D01*
G01X1003961Y383856D02*
G02X1003980Y385397I1384J754D01*
G01Y383822D02*
X1003961Y383856D01*
G01X1004005Y383780D02*
X1003980Y383822D01*
G01Y381497D02*
G03X1004005Y383780I-2015J1164D01*
G01X1005301Y379134D02*
G02X1003980Y381497I44J1575D01*
G01X1005430Y379134D02*
X1005301D01*
G01X1007360Y377972D02*
G03X1005430Y379134I-2015J-1163D01*
G01X1007426Y377859D02*
X1007360Y377972D01*
G01X1008725Y374860D02*
X1007426Y377859D01*
G01X1012469Y347560D02*
X1015485D01*
G01X1010947Y348330D02*
G03X1012469Y347560I1523J1120D01*
G01X1010436Y349025D02*
X1010947Y348330D01*
G01X1008795Y349885D02*
G02X1010436Y349025I-62J-2115D01*
G01X1008655Y349885D02*
X1008795D01*
G01X1006710Y348722D02*
G02X1008655Y349885I2015J-1162D01*
G01X1005389Y347934D02*
G03X1006710Y348722I-44J1575D01*
G01X1005260Y347934D02*
X1005389D01*
G01X1003330Y346772D02*
G02X1005260Y347934I2015J-1163D01*
G01X1002024Y345985D02*
G03X1003330Y346772I-59J1575D01*
G01X1001895Y345985D02*
X1002024D01*
G01X999950Y344822D02*
G02X1001895Y345985I2015J-1162D01*
G01X999937Y344799D02*
X999950Y344822D01*
G01X998586Y344034D02*
G03X999937Y344799I0J1575D01*
G01X998501Y344034D02*
X998586D01*
G01X996571Y342872D02*
G02X998501Y344034I2015J-1163D01*
G01X995265Y342085D02*
G03X996571Y342872I-59J1575D01*
G01X995136Y342085D02*
X995265D01*
G01X1009226Y399426D02*
Y406326D01*
G01X1007200Y397400D02*
X1009226Y399426D01*
G01X1007200Y388700D02*
Y397400D01*
G01X1007039Y388163D02*
G03X1007200Y388700I-450J427D01*
G01X1006710Y385397D02*
G02X1007039Y388163I2015J1163D01*
G01X1006729Y383856D02*
G03X1006710Y385397I-1384J754D01*
G01X1006642Y383705D02*
X1006729Y383856D01*
G01X1005345Y380709D02*
X1006642Y383705D01*
G01X1004398Y397898D02*
Y407727D01*
G01X1001500Y395000D02*
X1004398Y397898D01*
G01X1001500Y389200D02*
Y395000D01*
G01X1001000Y388000D02*
G03X1001500Y389200I-3068J1983D01*
G01X1000601Y387347D02*
G02X1001000Y388000I13170J-7599D01*
G01X1000601Y385773D02*
G02Y387347I1364J787D01*
G01X1000636Y383507D02*
G03X1000601Y385773I-2050J1102D01*
G01Y383447D02*
X1000636Y383507D01*
G01X1000601Y381873D02*
G02Y383447I1364J787D01*
G01X1000636Y379607D02*
G03X1000601Y381873I-2050J1102D01*
G01Y379547D02*
X1000636Y379607D01*
G01X1000601Y377973D02*
G02Y379547I1364J787D01*
G01X1000636Y375707D02*
G03X1000601Y377973I-2050J1102D01*
G01Y375647D02*
X1000636Y375707D01*
G01X1000601Y374073D02*
G02Y375647I1364J787D01*
G01X1000626Y371788D02*
G03X1000601Y374073I-2040J1120D01*
G01Y371746D02*
X1000626Y371788D01*
G01X1000601Y370172D02*
G02Y371746I1364J787D01*
G01X1000666Y370060D02*
X1000601Y370172D01*
G01X1001965Y367060D02*
X1000666Y370060D01*
G01X1028800Y399304D02*
X1033800Y404304D01*
G01X1028800Y394211D02*
Y399304D01*
G01X1028500Y392900D02*
G03X1028800Y394211I-2715J1311D01*
G01X1027640Y391247D02*
G03X1028500Y392900I-27238J15221D01*
G01X1027621Y391213D02*
X1027640Y391247D01*
G01Y389672D02*
G02X1027621Y391213I1365J787D01*
G01X1027883Y389071D02*
G03X1027640Y389672I-2258J-563D01*
G01X1027935Y388792D02*
G03X1027883Y389071I-2309J-286D01*
G01X1027952Y388500D02*
G03X1027935Y388792I-2327J11D01*
G01X1029005Y386560D02*
G02X1027952Y388500I1261J1940D01*
G01X1008681Y345235D02*
G03X1012105Y345609I0J15860D01*
G01X1007360Y344447D02*
G02X1008681Y345235I1365J-787D01*
G01X1007341Y344413D02*
X1007360Y344447D01*
G01X1007164Y343442D02*
G02X1007341Y344413I1561J217D01*
G01X998398Y395998D02*
Y397365D01*
G01X996100Y393700D02*
X998398Y395998D01*
G01X996100Y392064D02*
Y393700D01*
G01X996571Y391247D02*
X996100Y392064D01*
G01X996571Y389673D02*
G03Y391247I-1365J787D01*
G01Y387347D02*
G02Y389673I2015J1163D01*
G01X996590Y387313D02*
X996571Y387347D01*
G01Y385772D02*
G03X996590Y387313I-1365J787D01*
G01X996546Y383489D02*
G02X996571Y385772I2040J1119D01*
G01Y383447D02*
X996546Y383489D01*
G01X996590Y383413D02*
X996571Y383447D01*
G01X996780Y382592D02*
G03X996590Y383413I-1574J68D01*
G01X996780Y370953D02*
Y382592D01*
G01X996571Y370172D02*
G03X996780Y370953I-1354J781D01*
G01X996504Y370057D02*
X996571Y370172D01*
G01X995206Y367060D02*
X996504Y370057D01*
G01X1011626Y397926D02*
Y404625D01*
G01X1009326Y395626D02*
X1011626Y397926D01*
G01X1009326Y388481D02*
Y395626D01*
G01X1008725Y387880D02*
X1009326Y388481D01*
G01X1008725Y386560D02*
Y387880D01*
G01X1032385Y384609D02*
X1034100Y386324D01*
G01X1002050Y341335D02*
X1001965D01*
G01X1003980Y342497D02*
G02X1002050Y341335I-2015J1163D01*
G01X1005345Y341709D02*
G03X1003980Y342497I-682J394D01*
G01X992354Y399854D02*
Y400788D01*
G01X989900Y397400D02*
X992354Y399854D01*
G01X989900Y389321D02*
Y397400D01*
G01X990261Y388320D02*
X989900Y389321D01*
G01X990442Y387756D02*
G02X990261Y388320I1384J755D01*
G01X990461Y387722D02*
X990442Y387756D01*
G01X990486Y387680D02*
X990461Y387722D01*
G01Y385397D02*
G03X990486Y387680I-2015J1164D01*
G01X990442Y383856D02*
G02X990461Y385397I1384J754D01*
G01Y383822D02*
X990442Y383856D01*
G01X990486Y383780D02*
X990461Y383822D01*
G01Y381497D02*
G03X990486Y383780I-2015J1164D01*
G01X990442Y379956D02*
G02X990461Y381497I1384J754D01*
G01Y379922D02*
X990442Y379956D01*
G01X990486Y379880D02*
X990461Y379922D01*
G01Y377597D02*
G03X990486Y379880I-2015J1164D01*
G01X990442Y376056D02*
G02X990461Y377597I1384J754D01*
G01Y376022D02*
X990442Y376056D01*
G01X990486Y375980D02*
X990461Y376022D01*
G01Y373697D02*
G03X990486Y375980I-2015J1164D01*
G01X990395Y373582D02*
X990461Y373697D01*
G01X988446Y370959D02*
X990395Y373582D01*
G01X988531Y341335D02*
X988402D01*
G01X990461Y342497D02*
G02X988531Y341335I-2015J1163D01*
G01X991767Y343284D02*
G03X990461Y342497I59J-1575D01*
G01X991896Y343284D02*
X991767D01*
G01X993841Y344447D02*
G02X991896Y343284I-2015J1162D01*
G01X995162Y345235D02*
G03X993841Y344447I44J-1575D01*
G01X995291Y345235D02*
X995162D01*
G01X997221Y346397D02*
G02X995291Y345235I-2015J1163D01*
G01X998527Y347184D02*
G03X997221Y346397I59J-1575D01*
G01X998656Y347184D02*
X998527D01*
G01X1000601Y348347D02*
G02X998656Y347184I-2015J1162D01*
G01X1000614Y348370D02*
X1000601Y348347D01*
G01X1001965Y349135D02*
G03X1000614Y348370I0J-1575D01*
G01X1002050Y349135D02*
X1001965D01*
G01X1003980Y350297D02*
G02X1002050Y349135I-2015J1163D01*
G01X1005286Y351084D02*
G03X1003980Y350297I59J-1575D01*
G01X1005415Y351084D02*
X1005286D01*
G01X1007360Y352247D02*
G02X1005415Y351084I-2015J1162D01*
G01X1008681Y353035D02*
G03X1007360Y352247I44J-1575D01*
G01X1008769Y353035D02*
X1008681D01*
G01X1010090Y352247D02*
G03X1008769Y353035I-1365J-787D01*
G01X1012035Y351084D02*
G02X1010090Y352247I70J2325D01*
G01X1012164Y351084D02*
X1012035D01*
G01X1013470Y350297D02*
G03X1012164Y351084I-1365J-788D01*
G01X1015400Y349135D02*
G02X1013470Y350297I85J2325D01*
G01X1015570Y349135D02*
X1015400D01*
G01X1017500Y350297D02*
G02X1015570Y349135I-2015J1163D01*
G01X1018806Y351084D02*
G03X1017500Y350297I59J-1575D01*
G01X1018935Y351084D02*
X1018806D01*
G01X1020880Y352247D02*
G02X1018935Y351084I-2015J1162D01*
G01X1022201Y353035D02*
G03X1020880Y352247I44J-1575D01*
G01X1022330Y353035D02*
X1022201D01*
G01X1024260Y354197D02*
G02X1022330Y353035I-2015J1163D01*
G01X1025566Y354984D02*
G03X1024260Y354197I59J-1575D01*
G01X1025695Y354984D02*
X1025566D01*
G01X1027640Y356147D02*
G02X1025695Y354984I-2015J1162D01*
G01X1028961Y356935D02*
G03X1027640Y356147I44J-1575D01*
G01X1029090Y356935D02*
X1028961D01*
G01X1031020Y358097D02*
G02X1029090Y356935I-2015J1163D01*
G01X1032326Y358884D02*
G03X1031020Y358097I59J-1575D01*
G01X1032444Y358884D02*
X1032326D01*
G01X1033750Y358097D02*
G03X1032444Y358884I-1365J-788D01*
G01X978856Y382412D02*
Y405077D01*
G01X976291Y377972D02*
X978856Y382412D01*
G01X976266Y375689D02*
G02X976291Y377972I2040J1119D01*
G01Y375647D02*
X976266Y375689D01*
G01X976310Y375613D02*
X976291Y375647D01*
G01Y374072D02*
G03X976310Y375613I-1365J787D01*
G01X976291Y371746D02*
G02Y374072I2015J1163D01*
G01Y370172D02*
G03Y371746I-1365J787D01*
G01X976266Y370130D02*
X976291Y370172D01*
G01Y367847D02*
G02X976266Y370130I2015J1164D01*
G01X976310Y367813D02*
X976291Y367847D01*
G01Y366272D02*
G03X976310Y367813I-1365J787D01*
G01X976266Y363989D02*
G02X976291Y366272I2040J1119D01*
G01Y363947D02*
X976266Y363989D01*
G01X976310Y363913D02*
X976291Y363947D01*
G01Y362372D02*
G03X976310Y363913I-1365J787D01*
G01X976266Y360089D02*
G02X976291Y362372I2040J1119D01*
G01Y360047D02*
X976266Y360089D01*
G01X976310Y360013D02*
X976291Y360047D01*
G01Y358472D02*
G03X976310Y360013I-1365J787D01*
G01X976266Y356189D02*
G02X976291Y358472I2040J1119D01*
G01Y356147D02*
X976266Y356189D01*
G01X976310Y356113D02*
X976291Y356147D01*
G01Y354572D02*
G03X976310Y356113I-1365J787D01*
G01X976266Y352289D02*
G02X976291Y354572I2040J1119D01*
G01Y352247D02*
X976266Y352289D01*
G01X976310Y352213D02*
X976291Y352247D01*
G01Y350672D02*
G03X976310Y352213I-1365J787D01*
G01X976266Y348389D02*
G02X976291Y350672I2040J1119D01*
G01Y348347D02*
X976266Y348389D01*
G01X976310Y348313D02*
X976291Y348347D01*
G01Y346772D02*
G03X976310Y348313I-1365J787D01*
G01X976266Y344489D02*
G02X976291Y346772I2040J1119D01*
G01Y344447D02*
X976266Y344489D01*
G01X976310Y344413D02*
X976291Y344447D01*
G01Y342872D02*
G03X976310Y344413I-1365J787D01*
G01X1006398Y407198D02*
Y407982D01*
G01X1005271Y406071D02*
X1006398Y407198D01*
G01X979604Y405013D02*
X980512Y405921D01*
G01X1016398Y407799D02*
Y408694D01*
G01X1012826Y404227D02*
X1016398Y407799D01*
G01X1000398Y406102D02*
Y407015D01*
G01X1002500Y404000D02*
X1000398Y406102D01*
G01X1002398Y406352D02*
Y407700D01*
G01X1003500Y405250D02*
X1002398Y406352D01*
G01X1031800Y404064D02*
Y407043D01*
G01X1012398Y407299D02*
Y408331D01*
G01X1010426Y405327D02*
X1012398Y407299D01*
G01X973540Y403096D02*
X972712Y403924D01*
G01X1008398Y407698D02*
Y408586D01*
G01X1006021Y405321D02*
X1008398Y407698D01*
G01X1010398Y407498D02*
Y408385D01*
G01X1009226Y406326D02*
X1010398Y407498D01*
G01X1014398Y407397D02*
Y408465D01*
G01X1011626Y404625D02*
X1014398Y407397D01*
G01X978856Y405077D02*
X978216Y405717D01*
G01X1059000Y217526D02*
X1058026Y218500D01*
G01X1059000Y216500D02*
Y217526D01*
G01X1055500Y209500D02*
X1059000Y216500D01*
G01X1055500Y204000D02*
Y209500D01*
G01X1057500Y202000D02*
X1055500Y204000D01*
G01X1057500Y197000D02*
Y202000D01*
G01X1058763Y195737D02*
X1057500Y197000D01*
G01X1058763Y194050D02*
Y195737D01*
G01X1091116Y216984D02*
G03X1091141Y219267I-2015J1164D01*
G01X1091097Y215443D02*
G02X1091116Y216984I1384J754D01*
G01Y215409D02*
X1091097Y215443D01*
G01X1091141Y213126D02*
G03X1091116Y215409I-2040J1119D01*
G01Y213084D02*
X1091141Y213126D01*
G01X1091097Y213050D02*
X1091116Y213084D01*
G01Y211509D02*
G02X1091097Y213050I1365J787D01*
G01X1091141Y209226D02*
G03X1091116Y211509I-2040J1119D01*
G01X1090605Y208268D02*
X1091141Y209226D01*
G01X1090600Y208263D02*
X1090605Y208268D01*
G01X1090600Y205001D02*
Y208263D01*
G01X1097200Y198401D02*
X1090600Y205001D01*
G01X1091184Y180697D02*
X1090318Y179831D01*
G01X1091184Y182277D02*
Y180697D01*
G01X1083048Y190413D02*
X1091184Y182277D01*
G01X1083048Y194489D02*
Y190413D01*
G01X1081936Y195601D02*
X1083048Y194489D01*
G01X1081936Y204892D02*
Y195601D01*
G01X1080537Y206291D02*
X1081936Y204892D01*
G01X1080537Y212717D02*
Y206291D01*
G01X1080326Y213082D02*
X1080537Y212717D01*
G01X1080284Y215336D02*
G03X1080326Y213082I2057J-1089D01*
G01Y215409D02*
X1080284Y215336D01*
G01X1080326Y216983D02*
G02Y215409I-1364J-787D01*
G01X1080291Y219249D02*
G03X1080326Y216983I2050J-1102D01*
G01X1045357Y195628D02*
Y192972D01*
G01X1044302Y196683D02*
X1045357Y195628D01*
G01X1044302Y198820D02*
Y196683D01*
G01X1045300Y199818D02*
X1044302Y198820D01*
G01X1045300Y204401D02*
Y199818D01*
G01X1043550Y206151D02*
X1045300Y204401D01*
G01X1043549Y206151D02*
X1043550D01*
G01X1041700Y208000D02*
X1043549Y206151D01*
G01X1041700Y209284D02*
Y208000D01*
G01X1041160Y210273D02*
X1041700Y209284D01*
G01X1041160Y211847D02*
G03Y210273I1364J-787D01*
G01X1041195Y211907D02*
X1041160Y211847D01*
G01Y214173D02*
G02X1041195Y211907I-2015J-1164D01*
G01X1040845Y214730D02*
X1041160Y214173D01*
G01X1040040Y215813D02*
X1040845Y214730D01*
G01X1039145Y216909D02*
X1040040Y215813D01*
G01X1068654Y179345D02*
X1069498Y178501D01*
G01X1068654Y190015D02*
Y179345D01*
G01X1067535Y191134D02*
X1068654Y190015D01*
G01X1067535Y196572D02*
Y191134D01*
G01X1067533Y196572D02*
X1067535D01*
G01X1064552Y199552D02*
X1067533Y196572D01*
G01X1064547Y199558D02*
X1064552Y199552D01*
G01X1064547Y202758D02*
Y199558D01*
G01X1061554Y205751D02*
X1064547Y202758D01*
G01X1061556Y205753D02*
X1061554Y205751D01*
G01X1061556Y223143D02*
Y205753D01*
G01X1050858Y211731D02*
Y195652D01*
G01X1049954Y212635D02*
X1050858Y211731D01*
G01X1049199Y212635D02*
X1049954D01*
G01X1047244Y216080D02*
G03X1049199Y212635I2040J-1120D01*
G01X1047269Y216122D02*
X1047244Y216080D01*
G01X1047288Y216156D02*
X1047269Y216122D01*
G01Y217697D02*
G02X1047288Y216156I-1365J-787D01*
G01X1046621Y218820D02*
X1047269Y217697D01*
G01X1037104Y201496D02*
Y199996D01*
G01X1094496Y217359D02*
G02X1094477Y218900I1365J787D01*
G01X1094521Y215076D02*
G03X1094496Y217359I-2040J1119D01*
G01X1094502Y213535D02*
G02X1094521Y215076I1384J754D01*
G01Y213501D02*
X1094502Y213535D01*
G01X1094546Y213459D02*
X1094521Y213501D01*
G01Y211176D02*
G03X1094546Y213459I-2015J1164D01*
G01X1094051Y210336D02*
X1094521Y211176D01*
G01X1094051Y205910D02*
Y210336D01*
G01X1100350Y199611D02*
X1094051Y205910D01*
G01X1093846Y216984D02*
G02X1093821Y219267I2015J1164D01*
G01X1093865Y215443D02*
G03X1093846Y216984I-1384J754D01*
G01X1093840Y213160D02*
G02X1093865Y215443I2040J1119D01*
G01Y213118D02*
X1093840Y213160D01*
G01X1093884Y213084D02*
X1093865Y213118D01*
G01Y211543D02*
G03X1093884Y213084I-1365J787D01*
G01X1093301Y210532D02*
X1093865Y211543D01*
G01X1093301Y205599D02*
Y210532D01*
G01X1099600Y199300D02*
X1093301Y205599D01*
G01X1043556Y193802D02*
Y192984D01*
G01X1044216Y194462D02*
X1043556Y193802D01*
G01X1044216Y195629D02*
Y194462D01*
G01X1043537Y196308D02*
X1044216Y195629D01*
G01X1043537Y199341D02*
Y196308D01*
G01X1044216Y200020D02*
X1043537Y199341D01*
G01X1044216Y203984D02*
Y200020D01*
G01X1040719Y207481D02*
X1044216Y203984D01*
G01X1040719Y209191D02*
Y207481D01*
G01X1040541Y209840D02*
G02X1040719Y209191I-1396J-732D01*
G01X1040509Y209896D02*
X1040541Y209840D01*
G01X1040474Y212162D02*
G03X1040509Y209896I2050J-1102D01*
G01Y212222D02*
X1040474Y212162D01*
G01X1039145Y214584D02*
G02X1040509Y212222I0J-1575D01*
G01X1039075Y214584D02*
X1039145D01*
G01X1037130Y215747D02*
G03X1039075Y214584I2015J1162D01*
G01X1037062Y215864D02*
X1037130Y215747D01*
G01X1035765Y218860D02*
X1037062Y215864D01*
G01X1047522Y200102D02*
Y195410D01*
G01X1046300Y201324D02*
X1047522Y200102D01*
G01X1046300Y204599D02*
Y201324D01*
G01X1043854Y207044D02*
X1046300Y204599D01*
G01X1043500Y207900D02*
G03X1043854Y207044I1210J-1D01*
G01X1043500Y208819D02*
Y207900D01*
G01X1043889Y210272D02*
G03X1043500Y208819I2521J-1453D01*
G01X1043908Y211813D02*
G02X1043889Y210272I-1384J-754D01*
G01Y211847D02*
X1043908Y211813D01*
G01X1043864Y211889D02*
X1043889Y211847D01*
G01Y214172D02*
G03X1043864Y211889I2015J-1164D01*
G01X1042568Y216535D02*
G02X1043889Y214172I-44J-1575D01*
G01X1042426Y216535D02*
X1042568D01*
G01X1040509Y217696D02*
G03X1042426Y216535I2015J1164D01*
G01X1040496Y217719D02*
X1040509Y217696D01*
G01X1039145Y218484D02*
G02X1040496Y217719I0J-1575D01*
G01X1033744Y195798D02*
Y197536D01*
G01X1086026Y180551D02*
X1085306Y179831D01*
G01X1086026Y183167D02*
Y180551D01*
G01X1080030Y189163D02*
X1086026Y183167D01*
G01X1080030Y194279D02*
Y189163D01*
G01X1078916Y195393D02*
X1080030Y194279D01*
G01X1078916Y203881D02*
Y195393D01*
G01X1077527Y205270D02*
X1078916Y203881D01*
G01X1077527Y210125D02*
Y205270D01*
G01X1076947Y211131D02*
X1077527Y210125D01*
G01X1076947Y213457D02*
G03Y211131I2015J-1163D01*
G01Y215033D02*
G02Y213457I-1365J-788D01*
G01Y217359D02*
G03Y215033I2015J-1163D01*
G01X1075626Y219722D02*
G02X1076947Y217359I-44J-1575D01*
G01X1072666Y179166D02*
X1071998Y178498D01*
G01X1072666Y180511D02*
Y179166D01*
G01X1070924Y182253D02*
X1072666Y180511D01*
G01X1070924Y191251D02*
Y182253D01*
G01X1069805Y192370D02*
X1070924Y191251D01*
G01X1069805Y197511D02*
Y192370D01*
G01X1066817Y200499D02*
X1069805Y197511D01*
G01X1066817Y208940D02*
Y200499D01*
G01X1066678Y209190D02*
X1066817Y208940D01*
G01X1066654Y211460D02*
G03X1066678Y209190I2118J-1113D01*
G01X1066697Y211537D02*
X1066654Y211460D01*
G01X1066678Y213090D02*
G02X1066697Y211537I-1436J-794D01*
G01X1065702Y213871D02*
G02X1066678Y213090I-460J-1575D01*
G01X1065242Y213871D02*
X1065702D01*
G01X1063290Y214934D02*
G03X1065242Y213871I1952J1261D01*
G01X1063232Y215033D02*
X1063290Y214934D01*
G01X1063207Y215075D02*
X1063232Y215033D01*
G01Y217360D02*
G03X1063207Y215075I2010J-1165D01*
G01X1063284Y217450D02*
X1063232Y217360D01*
G01X1064984Y218507D02*
G03X1063284Y217450I258J-2311D01*
G01X1049145Y199541D02*
Y195507D01*
G01X1047200Y201486D02*
X1049145Y199541D01*
G01X1047200Y205200D02*
Y201486D01*
G01X1044497Y207902D02*
X1047200Y205200D01*
G01X1044250Y208500D02*
G03X1044497Y207902I845J-1D01*
G01X1044250Y208818D02*
Y208500D01*
G01X1044539Y209897D02*
G03X1044250Y208818I1871J-1079D01*
G01X1044564Y212180D02*
G02X1044539Y209897I-2040J-1119D01*
G01Y212222D02*
X1044564Y212180D01*
G01X1044520Y212256D02*
X1044539Y212222D01*
G01Y213797D02*
G03X1044520Y212256I1365J-787D01*
G01X1042594Y217285D02*
G02X1044539Y213797I-70J-2325D01*
G01X1042524Y217285D02*
X1042594D01*
G01X1041160Y219647D02*
G03X1042524Y217285I1364J-787D01*
G01X1067906Y179406D02*
X1067274Y178774D01*
G01X1067906Y189705D02*
Y179406D01*
G01X1066786Y190825D02*
X1067906Y189705D01*
G01X1066786Y196215D02*
Y190825D01*
G01X1063799Y199202D02*
X1066786Y196215D01*
G01X1063799Y202448D02*
Y199202D01*
G01X1060806Y205441D02*
X1063799Y202448D01*
G01X1060806Y223460D02*
Y205441D01*
G01X1086774Y180875D02*
X1087818Y179831D01*
G01X1086774Y183477D02*
Y180875D01*
G01X1080778Y189473D02*
X1086774Y183477D01*
G01X1080778Y194589D02*
Y189473D01*
G01X1079666Y195701D02*
X1080778Y194589D01*
G01X1079666Y204192D02*
Y195701D01*
G01X1078277Y205581D02*
X1079666Y204192D01*
G01X1078277Y210327D02*
Y205581D01*
G01X1077597Y211506D02*
X1078277Y210327D01*
G01X1077597Y213082D02*
G03Y211506I1365J-788D01*
G01Y215408D02*
G02Y213082I-2015J-1163D01*
G01Y216984D02*
G03Y215408I1365J-788D01*
G01X1075652Y220472D02*
G02X1077597Y216984I-70J-2325D01*
G01X1065242Y217527D02*
Y216196D01*
G01X1065015Y217754D02*
X1065242Y217527D01*
G01X1063936Y217076D02*
G02X1065015Y217754I1306J-881D01*
G01X1063882Y216983D02*
X1063936Y217076D01*
G01X1063863Y215444D02*
G02X1063882Y216983I1379J753D01*
G01X1063939Y215311D02*
X1063863Y215444D01*
G01X1065242Y214621D02*
G02X1063939Y215311I0J1575D01*
G01X1065806Y214621D02*
X1065242D01*
G01X1066364Y214409D02*
G03X1065806Y214621I-1122J-2112D01*
G01X1066616Y214254D02*
G03X1066364Y214409I-1353J-1917D01*
G01X1067360Y211183D02*
G03X1066616Y214254I-2118J1113D01*
G01X1067336Y211140D02*
X1067360Y211183D01*
G01X1067336Y209554D02*
G02Y211140I1436J793D01*
G01X1067565Y209141D02*
X1067336Y209554D01*
G01X1067565Y200813D02*
Y209141D01*
G01X1070554Y197824D02*
X1067565Y200813D01*
G01X1070554Y192681D02*
Y197824D01*
G01X1070556Y192679D02*
X1070554Y192681D01*
G01X1070556Y192677D02*
Y192679D01*
G01X1071672Y191561D02*
X1070556Y192677D01*
G01X1071672Y182563D02*
Y191561D01*
G01X1073414Y180821D02*
X1071672Y182563D01*
G01X1073414Y179585D02*
Y180821D01*
G01X1074498Y178501D02*
X1073414Y179585D01*
G01X1035327Y200166D02*
Y202173D01*
G01X1052414Y196677D02*
Y195555D01*
G01X1051608Y197483D02*
X1052414Y196677D01*
G01X1051608Y212092D02*
Y197483D01*
G01X1050315Y213385D02*
X1051608Y212092D01*
G01X1049225Y213385D02*
X1050315D01*
G01X1047900Y215713D02*
G03X1049225Y213385I1384J-753D01*
G01X1047919Y215747D02*
X1047900Y215713D01*
G01X1047944Y215789D02*
X1047919Y215747D01*
G01Y218072D02*
G02X1047944Y215789I-2015J-1164D01*
G01X1055600Y200401D02*
Y194366D01*
G01X1053108Y202893D02*
X1055600Y200401D01*
G01X1053108Y217492D02*
Y202893D01*
G01X1049415Y221185D02*
X1053108Y217492D01*
G01X1041634Y193504D02*
Y192547D01*
G01X1040892Y194246D02*
X1041634Y193504D01*
G01X1040892Y197108D02*
Y194246D01*
G01X1041790Y198006D02*
X1040892Y197108D01*
G01X1041790Y201510D02*
Y198006D01*
G01X1038300Y205000D02*
X1041790Y201510D01*
G01X1038300Y207502D02*
Y205000D01*
G01X1037780Y208322D02*
X1038300Y207502D01*
G01X1037761Y208356D02*
X1037780Y208322D01*
G01Y209897D02*
G03X1037761Y208356I1365J-787D01*
G01X1035988Y213000D02*
G02X1037780Y209897I0J-2069D01*
G01X1038614Y201986D02*
Y191891D01*
G01X1034106Y206494D02*
X1038614Y201986D01*
G01X1034106Y209794D02*
Y206494D01*
G01X1053961Y196755D02*
Y195531D01*
G01X1052358Y198358D02*
X1053961Y196755D01*
G01X1052358Y215786D02*
Y198358D01*
G01X1049284Y218860D02*
X1052358Y215786D01*
G01X1090466Y217359D02*
G03X1090485Y218900I-1365J787D01*
G01X1090441Y215076D02*
G02X1090466Y217359I2040J1119D01*
G01Y215034D02*
X1090441Y215076D01*
G01X1090485Y213493D02*
G03X1090466Y215034I-1384J754D01*
G01Y213459D02*
X1090485Y213493D01*
G01X1090441Y213417D02*
X1090466Y213459D01*
G01Y211134D02*
G02X1090441Y213417I2015J1164D01*
G01X1090484Y209590D02*
G03X1090466Y211134I-1383J756D01*
G01X1089800Y208410D02*
X1090484Y209590D01*
G01X1089800Y204740D02*
Y208410D01*
G01X1096450Y198090D02*
X1089800Y204740D01*
G01X1091932Y180717D02*
X1092818Y179831D01*
G01X1091932Y182587D02*
Y180717D01*
G01X1083796Y190723D02*
X1091932Y182587D01*
G01X1083796Y194799D02*
Y190723D01*
G01X1082686Y195909D02*
X1083796Y194799D01*
G01X1082686Y205203D02*
Y195909D01*
G01X1081285Y206604D02*
X1082686Y205203D01*
G01X1081285Y212925D02*
Y206604D01*
G01X1080977Y213459D02*
X1081285Y212925D01*
G01X1080958Y215000D02*
G03X1080977Y213459I1383J-754D01*
G01Y215034D02*
X1080958Y215000D01*
G01X1081012Y215094D02*
X1080977Y215034D01*
G01Y217360D02*
G02X1081012Y215094I-2015J-1164D01*
G01X1080977Y218934D02*
G03Y217360I1364J-787D01*
G01X1040124Y193177D02*
Y192316D01*
G01X1039800Y193501D02*
X1040124Y193177D01*
G01X1039800Y202001D02*
Y193501D01*
G01X1037346Y204455D02*
X1039800Y202001D01*
G01X1037346Y207573D02*
Y204455D01*
G01X1037064Y208060D02*
X1037346Y207573D01*
G01X1035765Y211060D02*
X1037064Y208060D01*
G01X1054910Y216909D02*
X1057314D01*
G01X1054500Y216499D02*
X1054910Y216909D01*
G01X1054500Y203500D02*
Y216499D01*
G01X1056500Y201500D02*
X1054500Y203500D01*
G01X1056500Y196000D02*
Y201500D01*
G01X1057225Y195275D02*
X1056500Y196000D01*
G01X1057225Y194172D02*
Y195275D01*
G01X1058026Y218500D02*
X1049284Y222760D01*
G01X1093780Y236597D02*
X1092481Y239596D01*
G01X1093846Y236484D02*
X1093780Y236597D01*
G01X1093560Y234314D02*
G03X1093846Y236484I-1272J1271D01*
G01X1093492Y234246D02*
X1093560Y234314D01*
G01X1092792Y233956D02*
G03X1093492Y234246I0J990D01*
G01X1091725Y233420D02*
G02X1092792Y233956I1067J-794D01*
G01X1091162Y232664D02*
X1091725Y233420D01*
G01X1091116Y232584D02*
X1091162Y232664D01*
G01X1091116Y231010D02*
G02Y232584I1365J787D01*
G01Y228684D02*
G03Y231010I-2015J1163D01*
G01X1091097Y227143D02*
G02X1091116Y228684I1384J754D01*
G01Y227109D02*
X1091097Y227143D01*
G01X1091141Y227067D02*
X1091116Y227109D01*
G01Y224784D02*
G03X1091141Y227067I-2015J1164D01*
G01X1091097Y223243D02*
G02X1091116Y224784I1384J754D01*
G01Y223209D02*
X1091097Y223243D01*
G01X1091141Y223167D02*
X1091116Y223209D01*
G01Y220884D02*
G03X1091141Y223167I-2015J1164D01*
G01X1091097Y219343D02*
G02X1091116Y220884I1384J754D01*
G01Y219309D02*
X1091097Y219343D01*
G01X1091141Y219267D02*
X1091116Y219309D01*
G01X1080326D02*
X1080291Y219249D01*
G01X1078962Y221671D02*
G02X1080326Y219309I0J-1575D01*
G01X1078892Y221671D02*
X1078962D01*
G01X1076947Y222834D02*
G03X1078892Y221671I2015J1162D01*
G01X1075810Y223606D02*
G02X1076947Y222834I-228J-1559D01*
G01X1075582Y223378D02*
X1075810Y223606D01*
G01X1075582Y222047D02*
Y223378D01*
G01X1064074Y225661D02*
X1061556Y223143D01*
G01X1065308Y225661D02*
X1064074D01*
G01X1066757Y227110D02*
X1065308Y225661D01*
G01X1066757Y228684D02*
G02Y227110I-1365J-787D01*
G01X1065242Y231797D02*
G03X1066757Y228684I22931J9235D01*
G01X1045904Y219234D02*
G02X1046621Y218820I0J-828D01*
G01X1045860Y219234D02*
X1045904D01*
G01X1044539Y220022D02*
G03X1045860Y219234I1365J787D01*
G01X1044473Y220138D02*
X1044539Y220022D01*
G01X1042524Y222760D02*
X1044473Y220138D01*
G01X1094564Y238551D02*
X1095861Y241547D01*
G01X1094477Y238400D02*
X1094564Y238551D01*
G01X1095802Y236072D02*
G02X1094477Y238400I59J1575D01*
G01X1094496Y229059D02*
G02X1095349Y231337I1365J788D01*
G01X1094562Y228946D02*
X1094496Y229059D01*
G01X1094707Y228573D02*
G03X1094562Y228946I-2551J-777D01*
G01X1094521Y226776D02*
G03X1094707Y228573I-2040J1119D01*
G01X1094496Y226734D02*
X1094521Y226776D01*
G01X1094477Y226700D02*
X1094496Y226734D01*
G01Y225159D02*
G02X1094477Y226700I1365J787D01*
G01X1094521Y222876D02*
G03X1094496Y225159I-2040J1119D01*
G01Y222834D02*
X1094521Y222876D01*
G01X1094477Y222800D02*
X1094496Y222834D01*
G01Y221259D02*
G02X1094477Y222800I1365J787D01*
G01X1094521Y218976D02*
G03X1094496Y221259I-2040J1119D01*
G01Y218934D02*
X1094521Y218976D01*
G01X1094477Y218900D02*
X1094496Y218934D01*
G01X1093911Y231124D02*
X1095861Y233746D01*
G01X1093846Y231010D02*
X1093911Y231124D01*
G01X1093846Y228684D02*
G02Y231010I2015J1163D01*
G01X1093865Y227143D02*
G03X1093846Y228684I-1384J754D01*
G01Y227109D02*
X1093865Y227143D01*
G01X1093821Y227067D02*
X1093846Y227109D01*
G01Y224784D02*
G02X1093821Y227067I2015J1164D01*
G01X1093865Y223243D02*
G03X1093846Y224784I-1384J754D01*
G01Y223209D02*
X1093865Y223243D01*
G01X1093821Y223167D02*
X1093846Y223209D01*
G01Y220884D02*
G02X1093821Y223167I2015J1164D01*
G01X1093865Y219343D02*
G03X1093846Y220884I-1384J754D01*
G01Y219309D02*
X1093865Y219343D01*
G01X1093821Y219267D02*
X1093846Y219309D01*
G01X1039075Y218484D02*
X1039145D01*
G01X1037130Y219647D02*
G03X1039075Y218484I2015J1162D01*
G01X1037062Y219764D02*
X1037130Y219647D01*
G01X1035765Y222760D02*
X1037062Y219764D01*
G01X1075497Y219722D02*
X1075626D01*
G01X1073567Y220884D02*
G03X1075497Y219722I2015J1163D01*
G01X1072430Y221655D02*
G02X1073567Y220884I-228J-1560D01*
G01X1072202Y221427D02*
X1072430Y221655D01*
G01X1072202Y220096D02*
Y221427D01*
G01X1065242Y218765D02*
X1064984Y218507D01*
G01X1065242Y220096D02*
Y218765D01*
G01X1041195Y219707D02*
X1041160Y219647D01*
G01Y221973D02*
G02X1041195Y219707I-2015J-1164D01*
G01X1041099Y222081D02*
X1041160Y221973D01*
G01X1039145Y224709D02*
X1041099Y222081D01*
G01X1065242Y227896D02*
X1060806Y223460D01*
G01X1075523Y220472D02*
X1075652D01*
G01X1074217Y222834D02*
G03X1075523Y220472I1364J-788D01*
G01X1074217Y225160D02*
G02Y222834I-2015J-1163D01*
G01X1074152Y225273D02*
X1074217Y225160D01*
G01X1072202Y227897D02*
X1074152Y225273D01*
G01X1072202Y227896D02*
Y227897D01*
G01X1047269Y219198D02*
X1047919Y218072D01*
G01X1047269Y220022D02*
G03Y219198I714J-412D01*
G01X1047288Y220056D02*
X1047269Y220022D01*
G01Y221597D02*
G02X1047288Y220056I-1365J-787D01*
G01X1047203Y221710D02*
X1047269Y221597D01*
G01X1045904Y224709D02*
X1047203Y221710D01*
G01X1049225Y221185D02*
X1049415D01*
G01X1047900Y223513D02*
G03X1049225Y221185I1384J-753D01*
G01X1047919Y223547D02*
X1047900Y223513D01*
G01X1047944Y223589D02*
X1047919Y223547D01*
G01Y225872D02*
G02X1047944Y223589I-2015J-1164D01*
G01X1047853Y225987D02*
X1047919Y225872D01*
G01X1045904Y228610D02*
X1047853Y225987D01*
G01X1090532Y233075D02*
X1092481Y235696D01*
G01X1090466Y232959D02*
X1090532Y233075D01*
G01X1090441Y232917D02*
X1090466Y232959D01*
G01Y230634D02*
G02X1090441Y232917I2015J1164D01*
G01X1090485Y230600D02*
X1090466Y230634D01*
G01Y229059D02*
G03X1090485Y230600I-1365J787D01*
G01X1090441Y226776D02*
G02X1090466Y229059I2040J1119D01*
G01Y226734D02*
X1090441Y226776D01*
G01X1090485Y226700D02*
X1090466Y226734D01*
G01Y225159D02*
G03X1090485Y226700I-1365J787D01*
G01X1090441Y222876D02*
G02X1090466Y225159I2040J1119D01*
G01Y222834D02*
X1090441Y222876D01*
G01X1090485Y222800D02*
X1090466Y222834D01*
G01Y221259D02*
G03X1090485Y222800I-1365J787D01*
G01X1090441Y218976D02*
G02X1090466Y221259I2040J1119D01*
G01Y218934D02*
X1090441Y218976D01*
G01X1090485Y218900D02*
X1090466Y218934D01*
G01X1081012Y218994D02*
X1080977Y218934D01*
G01X1079060Y222421D02*
G02X1081012Y218994I-98J-2325D01*
G01X1078918Y222421D02*
X1079060D01*
G01X1077597Y223209D02*
G03X1078918Y222421I1365J787D01*
G01X1075839Y224359D02*
G02X1077597Y223209I-257J-2312D01*
G01X1075582Y224616D02*
X1075839Y224359D01*
G01X1075582Y225947D02*
Y224616D01*
G01X1037130Y358472D02*
G02X1034400I-1365J788D01*
G01X1039060Y359634D02*
G03X1037130Y358472I85J-2325D01*
G01X1039243Y359634D02*
X1039060D01*
G01X1041160Y358473D02*
G03X1039243Y359634I-2015J-1164D01*
G01X1041173Y358450D02*
X1041160Y358473D01*
G01X1042524Y357685D02*
G02X1041173Y358450I0J1575D01*
G01X1042583Y357685D02*
X1042524D01*
G01X1043889Y358472D02*
G02X1042583Y357685I-1365J788D01*
G01X1045819Y359634D02*
G03X1043889Y358472I85J-2325D01*
G01X1045989Y359634D02*
X1045819D01*
G01X1047919Y358472D02*
G03X1045989Y359634I-2015J-1163D01*
G01X1049225Y357685D02*
G02X1047919Y358472I59J1575D01*
G01X1049343Y357685D02*
X1049225D01*
G01X1050649Y358472D02*
G02X1049343Y357685I-1365J788D01*
G01X1052666Y359637D02*
G03X1050649Y358472I0J-2328D01*
G01X1054619Y359637D02*
X1052666D01*
G01X1056529Y357727D02*
X1054619Y359637D01*
G01X1062631Y357727D02*
X1056529D01*
G01X1063386Y356972D02*
X1062631Y357727D01*
G01X1073392Y356972D02*
X1063386D01*
G01X1075337Y355809D02*
G03X1073392Y356972I-2015J-1162D01*
G01X1076658Y355021D02*
G02X1075337Y355809I44J1575D01*
G01X1076746Y355021D02*
X1076658D01*
G01X1078067Y355809D02*
G02X1076746Y355021I-1365J787D01*
G01X1080012Y356972D02*
G03X1078067Y355809I70J-2325D01*
G01X1080152Y356972D02*
X1080012D01*
G01X1082097Y355809D02*
G03X1080152Y356972I-2015J-1162D01*
G01X1083418Y355021D02*
G02X1082097Y355809I44J1575D01*
G01X1083462Y355021D02*
X1083418D01*
G01X1084813Y355786D02*
G02X1083462Y355021I-1351J810D01*
G01X1084826Y355809D02*
X1084813Y355786D01*
G01X1086771Y356972D02*
G03X1084826Y355809I70J-2325D01*
G01X1086911Y356972D02*
X1086771D01*
G01X1088856Y355809D02*
G03X1086911Y356972I-2015J-1162D01*
G01X1090177Y355021D02*
G02X1088856Y355809I44J1575D01*
G01X1090265Y355021D02*
X1090177D01*
G01X1091586Y355809D02*
G02X1090265Y355021I-1365J787D01*
G01X1093531Y356972D02*
G03X1091586Y355809I70J-2325D01*
G01X1093671Y356972D02*
X1093531D01*
G01X1095616Y355809D02*
G03X1093671Y356972I-2015J-1162D01*
G01X1068147Y388370D02*
Y404512D01*
G01X1070999Y385518D02*
X1068147Y388370D01*
G01X1070999Y378594D02*
Y385518D01*
G01X1071546Y378047D02*
X1070999Y378594D01*
G01X1073322Y378047D02*
X1071546D01*
G01X1063200Y400300D02*
Y405292D01*
G01X1059100Y396200D02*
X1063200Y400300D01*
G01X1059100Y383388D02*
Y396200D01*
G01X1057500Y381788D02*
X1059100Y383388D01*
G01X1057500Y374200D02*
Y381788D01*
G01X1054300Y371000D02*
X1057500Y374200D01*
G01X1052000Y371000D02*
X1054300D01*
G01X1050010Y369010D02*
X1052000Y371000D01*
G01X1045904Y369010D02*
X1050010D01*
G01X1071747Y393970D02*
Y403026D01*
G01X1072070Y393647D02*
X1071747Y393970D01*
G01X1073322Y393647D02*
X1072070D01*
G01X1043100Y401900D02*
Y405000D01*
G01X1038350Y397150D02*
X1043100Y401900D01*
G01X1038350Y390050D02*
Y397150D01*
G01X1037340Y389040D02*
X1038350Y390050D01*
G01X1037340Y386596D02*
Y389040D01*
G01X1035824Y384985D02*
G03X1037340Y386596I-59J1575D01*
G01X1035695Y384985D02*
X1035824D01*
G01X1033750Y381497D02*
G02X1035695Y384985I2015J1163D01*
G01X1033769Y379956D02*
G03X1033750Y381497I-1384J754D01*
G01Y379922D02*
X1033769Y379956D01*
G01X1033725Y379880D02*
X1033750Y379922D01*
G01Y377597D02*
G02X1033725Y379880I2015J1164D01*
G01X1033769Y376056D02*
G03X1033750Y377597I-1384J754D01*
G01X1033682Y375905D02*
X1033769Y376056D01*
G01X1058300Y401800D02*
Y403716D01*
G01X1055600Y399100D02*
X1058300Y401800D01*
G01X1055600Y386200D02*
Y399100D01*
G01X1050500Y381100D02*
X1055600Y386200D01*
G01X1050500Y379976D02*
Y381100D01*
G01X1049284Y378760D02*
X1050500Y379976D01*
G01X1088646Y395169D02*
Y403447D01*
G01X1088881Y394767D02*
X1088646Y395169D01*
G01X1086926Y391322D02*
G03X1088881Y394767I-85J2325D01*
G01X1086841Y391322D02*
X1086926D01*
G01X1085490Y390557D02*
G02X1086841Y391322I1351J-810D01*
G01X1085477Y390534D02*
X1085490Y390557D01*
G01X1084646Y389694D02*
G03X1085477Y390534I-1184J2002D01*
G01X1083462Y387796D02*
G02X1084493Y389604I2100J0D01*
G01D02*
X1084646Y389694D01*
G01X1037130Y381872D02*
X1035765Y378760D01*
G01X1039060Y383034D02*
G03X1037130Y381872I85J-2325D01*
G01X1039145Y383034D02*
X1039060D01*
G01X1040509Y385396D02*
G02X1039145Y383034I-1364J-787D01*
G01X1040474Y387662D02*
G03X1040509Y385396I2050J-1102D01*
G01Y387722D02*
X1040474Y387662D01*
G01X1040509Y389296D02*
G02Y387722I-1364J-787D01*
G01X1040161Y389763D02*
G02X1040509Y389296I-1832J-1728D01*
G01X1040000Y389924D02*
X1040161Y389763D01*
G01X1040000Y391800D02*
Y389924D01*
G01X1044200Y396000D02*
X1040000Y391800D01*
G01X1044200Y404614D02*
Y396000D01*
G01X1084880Y394911D02*
Y405008D01*
G01X1084813Y394786D02*
X1084880Y394911D01*
G01X1083462Y394021D02*
G03X1084813Y394786I0J1575D01*
G01X1083377Y394021D02*
X1083462D01*
G01X1081447Y392859D02*
G02X1083377Y394021I2015J-1163D01*
G01X1080502Y392128D02*
G03X1081447Y392859I-420J1519D01*
G01X1079874Y391762D02*
G02X1080502Y392128I1008J-1007D01*
G01X1079046Y390934D02*
X1079874Y391762D01*
G01X1078717Y388959D02*
G02X1079046Y390934I1365J788D01*
G01X1078742Y386676D02*
G03X1078717Y388959I-2040J1119D01*
G01Y386634D02*
X1078742Y386676D01*
G01X1078698Y386600D02*
X1078717Y386634D01*
G01Y385059D02*
G02X1078698Y386600I1365J787D01*
G01X1078783Y384946D02*
X1078717Y385059D01*
G01X1080082Y381947D02*
X1078783Y384946D01*
G01X1070997Y390160D02*
Y403334D01*
G01X1071410Y389747D02*
X1070997Y390160D01*
G01X1073322Y389747D02*
X1071410D01*
G01X1039700Y402400D02*
Y403700D01*
G01X1037250Y399950D02*
X1039700Y402400D01*
G01X1037250Y390750D02*
Y399950D01*
G01X1035765Y389265D02*
X1037250Y390750D01*
G01X1035765Y386560D02*
Y389265D01*
G01X1087898Y396543D02*
Y403757D01*
G01X1087896Y396541D02*
X1087898Y396543D01*
G01X1087896Y394968D02*
Y396541D01*
G01X1088233Y394385D02*
X1087896Y394968D01*
G01X1086900Y392072D02*
G03X1088233Y394385I-59J1575D01*
G01X1086771Y392072D02*
X1086900D01*
G01X1084826Y390909D02*
G02X1086771Y392072I2015J-1162D01*
G01X1084813Y390886D02*
X1084826Y390909D01*
G01X1083863Y390173D02*
G03X1084813Y390886I-401J1524D01*
G01X1083682Y390069D02*
G02X1083863Y390173I283J-283D01*
G01X1082869Y389256D02*
X1083682Y390069D01*
G01X1081998Y387215D02*
G02X1082869Y389256I1463J582D01*
G01X1082122Y386967D02*
G02X1081998Y387215I1375J842D01*
G01X1082316Y385194D02*
G03X1082122Y386967I-2222J654D01*
G01X1083287Y383896D02*
G02X1082316Y385194I0J1012D01*
G01X1083462Y383896D02*
X1083287D01*
G01X1046500Y394900D02*
Y403500D01*
G01X1044100Y392500D02*
X1046500Y394900D01*
G01X1044100Y390459D02*
Y392500D01*
G01X1043889Y389672D02*
G03X1044100Y390459I-1363J787D01*
G01X1043864Y387389D02*
G02X1043889Y389672I2040J1119D01*
G01Y387347D02*
X1043864Y387389D01*
G01X1043908Y387313D02*
X1043889Y387347D01*
G01Y385772D02*
G03X1043908Y387313I-1365J787D01*
G01X1043864Y383489D02*
G02X1043889Y385772I2040J1119D01*
G01Y383447D02*
X1043864Y383489D01*
G01X1043908Y383413D02*
X1043889Y383447D01*
G01X1042583Y381085D02*
G03X1043908Y383413I-59J1575D01*
G01X1042454Y381085D02*
X1042583D01*
G01X1040509Y379922D02*
G02X1042454Y381085I2015J-1162D01*
G01X1040496Y379899D02*
X1040509Y379922D01*
G01X1039145Y379134D02*
G03X1040496Y379899I0J1575D01*
G01X1039060Y379134D02*
X1039145D01*
G01X1037130Y377972D02*
G02X1039060Y379134I2015J-1163D01*
G01X1037064Y377859D02*
X1037130Y377972D01*
G01X1035765Y374860D02*
X1037064Y377859D01*
G01X1045300Y395800D02*
Y403800D01*
G01X1040900Y391400D02*
X1045300Y395800D01*
G01X1040900Y390643D02*
Y391400D01*
G01X1041160Y389673D02*
G02X1040900Y390643I1679J970D01*
G01X1041195Y387407D02*
G03X1041160Y389673I-2050J1102D01*
G01Y387347D02*
X1041195Y387407D01*
G01X1041160Y385773D02*
G02Y387347I1364J787D01*
G01X1041195Y383507D02*
G03X1041160Y385773I-2050J1102D01*
G01Y383447D02*
X1041195Y383507D01*
G01X1041096Y383334D02*
X1041160Y383447D01*
G01X1039145Y380709D02*
X1041096Y383334D01*
G01X1054300Y401600D02*
Y403300D01*
G01X1054700Y401200D02*
X1054300Y401600D01*
G01X1054700Y388000D02*
Y401200D01*
G01X1051400Y384700D02*
X1054700Y388000D01*
G01X1050400Y384700D02*
X1051400D01*
G01X1049935Y384235D02*
X1050400Y384700D01*
G01X1049240Y384235D02*
X1049935D01*
G01X1047919Y381872D02*
G02X1049240Y384235I1365J788D01*
G01X1047944Y379589D02*
G03X1047919Y381872I-2040J1119D01*
G01Y379547D02*
X1047944Y379589D01*
G01X1047900Y379513D02*
X1047919Y379547D01*
G01Y377972D02*
G02X1047900Y379513I1365J787D01*
G01X1047944Y375689D02*
G03X1047919Y377972I-2040J1119D01*
G01Y375647D02*
X1047944Y375689D01*
G01X1047853Y375531D02*
X1047919Y375647D01*
G01X1045904Y372909D02*
X1047853Y375531D01*
G01X1051000Y401800D02*
Y403600D01*
G01X1049100Y399900D02*
X1051000Y401800D01*
G01X1049100Y393300D02*
Y399900D01*
G01X1047480Y391680D02*
X1049100Y393300D01*
G01X1047480Y384589D02*
Y391680D01*
G01X1047269Y383822D02*
G03X1047480Y384589I-1289J767D01*
G01X1047244Y383780D02*
X1047269Y383822D01*
G01Y381497D02*
G02X1047244Y383780I2015J1164D01*
G01X1047288Y379956D02*
G03X1047269Y381497I-1384J754D01*
G01Y379922D02*
X1047288Y379956D01*
G01X1047244Y379880D02*
X1047269Y379922D01*
G01Y377597D02*
G02X1047244Y379880I2015J1164D01*
G01X1045948Y375234D02*
G03X1047269Y377597I-44J1575D01*
G01X1045758Y375234D02*
X1045948D01*
G01X1042524Y374860D02*
X1045758Y375234D01*
G01X1049800Y402300D02*
Y404700D01*
G01X1047700Y400200D02*
X1049800Y402300D01*
G01X1047700Y394100D02*
Y400200D01*
G01X1045500Y391900D02*
X1047700Y394100D01*
G01X1045500Y390466D02*
Y391900D01*
G01X1045469Y390435D02*
X1045500Y390466D01*
G01X1044539Y389297D02*
G02X1045469Y390435I3936J-2268D01*
G01X1044520Y387756D02*
G02X1044539Y389297I1384J754D01*
G01Y387722D02*
X1044520Y387756D01*
G01X1044564Y387680D02*
X1044539Y387722D01*
G01Y385397D02*
G03X1044564Y387680I-2015J1164D01*
G01X1044520Y383856D02*
G02X1044539Y385397I1384J754D01*
G01Y383822D02*
X1044520Y383856D01*
G01X1044564Y383780D02*
X1044539Y383822D01*
G01Y381497D02*
G03X1044564Y383780I-2015J1164D01*
G01X1044520Y379956D02*
G02X1044539Y381497I1384J754D01*
G01Y379922D02*
X1044520Y379956D01*
G01X1044564Y379880D02*
X1044539Y379922D01*
G01X1042609Y376435D02*
G03X1044564Y379880I-85J2325D01*
G01X1042524Y376435D02*
X1042609D01*
G01X1041173Y375670D02*
G02X1042524Y376435I1351J-810D01*
G01X1041096Y375534D02*
X1041173Y375670D01*
G01X1039145Y372909D02*
X1041096Y375534D01*
G01X1085628Y394718D02*
Y404698D01*
G01X1085477Y394434D02*
X1085628Y394718D01*
G01X1083532Y393271D02*
G03X1085477Y394434I-70J2325D01*
G01X1083403Y393271D02*
X1083532D01*
G01X1082097Y392484D02*
G02X1083403Y393271I1365J-788D01*
G01X1080707Y391406D02*
G03X1082097Y392484I-622J2237D01*
G01X1080366Y391191D02*
X1080707Y391406D01*
G01X1080082Y390907D02*
X1080366Y391191D01*
G01X1080082Y389747D02*
Y390907D01*
G01X1068897Y389970D02*
Y404204D01*
G01X1068898Y389969D02*
X1068897Y389970D01*
G01X1068898Y388677D02*
Y389969D01*
G01X1071747Y385828D02*
X1068898Y388677D01*
G01X1071747Y382194D02*
Y385828D01*
G01X1071994Y381947D02*
X1071747Y382194D01*
G01X1073322Y381947D02*
X1071994D01*
G01X1061800Y401100D02*
Y406100D01*
G01X1058100Y397400D02*
X1061800Y401100D01*
G01X1058100Y384460D02*
Y397400D01*
G01X1055100Y381460D02*
X1058100Y384460D01*
G01X1055100Y376980D02*
Y381460D01*
G01X1052980Y374860D02*
X1055100Y376980D01*
G01X1049284Y374860D02*
X1052980D01*
G01X1060300Y401700D02*
Y404365D01*
G01X1057000Y398400D02*
X1060300Y401700D01*
G01X1057000Y385045D02*
Y398400D01*
G01X1052664Y380709D02*
X1057000Y385045D01*
G01X1075663Y358927D02*
X1075380Y359210D01*
G01X1077657Y358927D02*
X1075663D01*
G01X1077940Y359210D02*
X1077657Y358927D01*
G01X1080735Y360122D02*
X1078852D01*
G01X1087494D02*
X1085982D01*
G01X1094437Y360433D02*
X1092386D01*
G01X1080963Y364251D02*
X1079097D01*
G01X1088025Y364091D02*
X1085871D01*
G01X1035700Y400600D02*
X1038600Y403500D01*
G01X1035700Y391500D02*
Y400600D01*
G01X1034100Y389900D02*
X1035700Y391500D01*
G01X1034100Y386324D02*
Y389900D01*
G01X1037780Y358097D02*
G02X1033750I-2015J1163D01*
G01X1039086Y358884D02*
G03X1037780Y358097I59J-1575D01*
G01X1039145Y358884D02*
X1039086D01*
G01X1040496Y358119D02*
G03X1039145Y358884I-1351J-810D01*
G01X1040509Y358096D02*
X1040496Y358119D01*
G01X1042426Y356935D02*
G02X1040509Y358096I98J2325D01*
G01X1042609Y356935D02*
X1042426D01*
G01X1044539Y358097D02*
G02X1042609Y356935I-2015J1163D01*
G01X1045845Y358884D02*
G03X1044539Y358097I59J-1575D01*
G01X1045963Y358884D02*
X1045845D01*
G01X1047269Y358097D02*
G03X1045963Y358884I-1365J-788D01*
G01X1049199Y356935D02*
G02X1047269Y358097I85J2325D01*
G01X1049369Y356935D02*
X1049199D01*
G01X1051299Y358097D02*
G02X1049369Y356935I-2015J1163D01*
G01X1052661Y358883D02*
G03X1051299Y358097I0J-1573D01*
G01X1054313Y358883D02*
X1052661D01*
G01X1056218Y356978D02*
X1054313Y358883D01*
G01X1062319Y356978D02*
X1056218D01*
G01X1063075Y356222D02*
X1062319Y356978D01*
G01X1073366Y356222D02*
X1063075D01*
G01X1074687Y355434D02*
G03X1073366Y356222I-1365J-787D01*
G01X1076632Y354271D02*
G02X1074687Y355434I70J2325D01*
G01X1076772Y354271D02*
X1076632D01*
G01X1078717Y355434D02*
G02X1076772Y354271I-2015J1162D01*
G01X1080038Y356222D02*
G03X1078717Y355434I44J-1575D01*
G01X1080126Y356222D02*
X1080038D01*
G01X1081447Y355434D02*
G03X1080126Y356222I-1365J-787D01*
G01X1083392Y354271D02*
G02X1081447Y355434I70J2325D01*
G01X1083532Y354271D02*
X1083392D01*
G01X1085477Y355434D02*
G02X1083532Y354271I-2015J1162D01*
G01X1085490Y355457D02*
X1085477Y355434D01*
G01X1086841Y356222D02*
G03X1085490Y355457I0J-1575D01*
G01X1086885Y356222D02*
X1086841D01*
G01X1088206Y355434D02*
G03X1086885Y356222I-1365J-787D01*
G01X1090151Y354271D02*
G02X1088206Y355434I70J2325D01*
G01X1090291Y354271D02*
X1090151D01*
G01X1092236Y355434D02*
G02X1090291Y354271I-2015J1162D01*
G01X1093557Y356222D02*
G03X1092236Y355434I44J-1575D01*
G01X1093645Y356222D02*
X1093557D01*
G01X1094966Y355434D02*
G03X1093645Y356222I-1365J-787D01*
G01X1096911Y354271D02*
G02X1094966Y355434I70J2325D01*
G01X1069749Y416909D02*
X1068816Y417842D01*
G01X1069749Y406114D02*
Y416909D01*
G01X1068147Y404512D02*
X1069749Y406114D01*
G01X1063800Y405892D02*
Y406826D01*
G01X1063200Y405292D02*
X1063800Y405892D01*
G01X1075467Y417672D02*
X1076316Y418521D01*
G01X1075467Y406746D02*
Y417672D01*
G01X1071747Y403026D02*
X1075467Y406746D01*
G01X1043800Y405700D02*
Y406684D01*
G01X1043100Y405000D02*
X1043800Y405700D01*
G01X1057800Y404216D02*
Y405358D01*
G01X1058300Y403716D02*
X1057800Y404216D01*
G01X1092909Y408664D02*
X1093926Y409681D01*
G01X1092909Y407710D02*
Y408664D01*
G01X1088646Y403447D02*
X1092909Y407710D01*
G01X1045800Y406214D02*
X1044200Y404614D01*
G01X1045800Y406935D02*
Y406214D01*
G01X1087043Y410395D02*
X1086416Y411022D01*
G01X1087043Y407171D02*
Y410395D01*
G01X1084880Y405008D02*
X1087043Y407171D01*
G01X1074719Y417608D02*
X1073816Y418511D01*
G01X1074719Y407056D02*
Y417608D01*
G01X1070997Y403334D02*
X1074719Y407056D01*
G01X1041800Y405800D02*
Y406612D01*
G01X1039700Y403700D02*
X1041800Y405800D01*
G01X1091426Y409586D02*
Y410424D01*
G01X1092161Y408851D02*
X1091426Y409586D01*
G01X1092161Y408020D02*
Y408851D01*
G01X1087898Y403757D02*
X1092161Y408020D01*
G01X1049800Y406800D02*
Y407615D01*
G01X1046500Y403500D02*
X1049800Y406800D01*
G01X1037800Y405896D02*
Y406629D01*
G01X1037120Y405216D02*
X1037800Y405896D01*
G01X1037120Y403820D02*
Y405216D01*
G01X1047800Y406300D02*
Y407132D01*
G01X1045300Y403800D02*
X1047800Y406300D01*
G01X1055800Y404800D02*
Y405734D01*
G01X1054300Y403300D02*
X1055800Y404800D01*
G01X1035800Y405992D02*
Y406737D01*
G01X1035400Y405592D02*
X1035800Y405992D01*
G01X1035400Y404104D02*
Y405592D01*
G01X1053800Y406400D02*
Y407669D01*
G01X1051000Y403600D02*
X1053800Y406400D01*
G01X1051800Y406700D02*
Y407687D01*
G01X1049800Y404700D02*
X1051800Y406700D01*
G01X1087791Y410410D02*
X1088916Y411535D01*
G01X1087791Y406861D02*
Y410410D01*
G01X1085628Y404698D02*
X1087791Y406861D01*
G01X1070499Y417264D02*
X1071316Y418081D01*
G01X1070499Y405806D02*
Y417264D01*
G01X1068897Y404204D02*
X1070499Y405806D01*
G01X1059800Y404865D02*
Y405805D01*
G01X1060300Y404365D02*
X1059800Y404865D01*
G01X1033800Y404304D02*
Y406734D01*
G01X1039800Y405766D02*
Y406540D01*
G01X1038600Y404566D02*
X1039800Y405766D01*
G01X1038600Y403500D02*
Y404566D01*
G01X1134405Y216984D02*
G02X1134380Y219267I2015J1164D01*
G01X1134424Y215443D02*
G03X1134405Y216984I-1384J754D01*
G01Y215409D02*
X1134424Y215443D01*
G01X1134380Y215367D02*
X1134405Y215409D01*
G01X1136369Y211921D02*
G02X1134380Y215367I51J2326D01*
G01X1140258Y211921D02*
X1136369D01*
G01X1145970Y206209D02*
X1140258Y211921D01*
G01X1146674Y206209D02*
X1145970D01*
G01X1148018Y204865D02*
X1146674Y206209D01*
G01X1097200Y194392D02*
Y198401D01*
G01X1101104Y190488D02*
X1097200Y194392D01*
G01X1101104Y184696D02*
Y190488D01*
G01X1101800Y184000D02*
X1101104Y184696D01*
G01X1108016Y217359D02*
G02X1107997Y218900I1365J787D01*
G01X1108041Y215076D02*
G03X1108016Y217359I-2040J1119D01*
G01Y215034D02*
X1108041Y215076D01*
G01X1107997Y215000D02*
X1108016Y215034D01*
G01Y213459D02*
G02X1107997Y215000I1365J787D01*
G01X1108016Y211133D02*
G03Y213459I-2015J1163D01*
G01X1107969Y210958D02*
G02X1108016Y211133I351J0D01*
G01X1107969Y209961D02*
Y210958D01*
G01X1117050Y200880D02*
X1107969Y209961D01*
G01X1117050Y198012D02*
Y200880D01*
G01X1123780Y191282D02*
X1117050Y198012D01*
G01X1123780Y186870D02*
Y191282D01*
G01X1124492Y186158D02*
X1123780Y186870D01*
G01X1143511Y205100D02*
X1145116D01*
G01X1139840Y208771D02*
X1143511Y205100D01*
G01X1136376Y208771D02*
X1139840D01*
G01X1135055Y209559D02*
G03X1136376Y208771I1365J787D01*
G01X1133125Y210721D02*
G02X1135055Y209559I-85J-2325D01*
G01X1132996Y210721D02*
X1133125D01*
G01X1131675Y213084D02*
G03X1132996Y210721I1365J-788D01*
G01X1131700Y215367D02*
G02X1131675Y213084I-2040J-1119D01*
G01Y215409D02*
X1131700Y215367D01*
G01X1131656Y215443D02*
X1131675Y215409D01*
G01Y216984D02*
G03X1131656Y215443I1365J-787D01*
G01X1131700Y219267D02*
G02X1131675Y216984I-2040J-1119D01*
G01X1127637Y194825D02*
X1129160Y193302D01*
G01X1126445Y194825D02*
X1127637D01*
G01X1122210Y199060D02*
X1126445Y194825D01*
G01X1122210Y199891D02*
Y199060D01*
G01X1119930Y202171D02*
X1122210Y199891D01*
G01X1119435Y202171D02*
X1119930D01*
G01X1117505Y205659D02*
G03X1119435Y202171I2015J-1163D01*
G01X1117505Y207233D02*
G02Y205659I-1364J-787D01*
G01X1117480Y207275D02*
X1117505Y207233D01*
G01Y209560D02*
G03X1117480Y207275I2015J-1165D01*
G01X1117505Y211134D02*
G02Y209560I-1364J-787D01*
G01X1117470Y211194D02*
X1117505Y211134D01*
G01Y213460D02*
G03X1117470Y211194I2015J-1164D01*
G01X1117531Y213505D02*
X1117505Y213460D01*
G01X1117506Y215034D02*
G02X1117531Y213505I-1365J-787D01*
G01X1117481Y215076D02*
X1117506Y215034D01*
G01Y217359D02*
G03X1117481Y215076I2015J-1164D01*
G01X1117525Y218900D02*
G02X1117506Y217359I-1384J-754D01*
G01X1131900Y197448D02*
Y195894D01*
G01X1127408Y201940D02*
X1131900Y197448D01*
G01X1125659Y201940D02*
X1127408D01*
G01X1124265Y203334D02*
X1125659Y201940D01*
G01X1122944Y204122D02*
G02X1124265Y203334I-44J-1575D01*
G01X1122815Y204122D02*
X1122944D01*
G01X1120860Y207567D02*
G03X1122815Y204122I2040J-1120D01*
G01X1120885Y207609D02*
X1120860Y207567D01*
G01X1120904Y207643D02*
X1120885Y207609D01*
G01Y209184D02*
G02X1120904Y207643I-1365J-787D01*
G01X1120860Y211467D02*
G03X1120885Y209184I2040J-1119D01*
G01Y211509D02*
X1120860Y211467D01*
G01X1120904Y211543D02*
X1120885Y211509D01*
G01Y213084D02*
G02X1120904Y211543I-1365J-787D01*
G01X1120860Y215367D02*
G03X1120885Y213084I2040J-1119D01*
G01Y215409D02*
X1120860Y215367D01*
G01X1120885Y216983D02*
G02Y215409I-1364J-787D01*
G01X1120850Y219249D02*
G03X1120885Y216983I2050J-1102D01*
G01X1100350Y195582D02*
Y199611D01*
G01X1106020Y189912D02*
X1100350Y195582D01*
G01X1106020Y185680D02*
Y189912D01*
G01X1106800Y184900D02*
X1106020Y185680D01*
G01X1099600Y195270D02*
Y199300D01*
G01X1105270Y189600D02*
X1099600Y195270D01*
G01X1105270Y185770D02*
Y189600D01*
G01X1104300Y184800D02*
X1105270Y185770D01*
G01X1128748Y196380D02*
X1130493Y194635D01*
G01X1125951Y196380D02*
X1128748D01*
G01X1122960Y199371D02*
X1125951Y196380D01*
G01X1122960Y200202D02*
Y199371D01*
G01X1120241Y202921D02*
X1122960Y200202D01*
G01X1119520Y202921D02*
X1120241D01*
G01X1118156Y205283D02*
G03X1119520Y202921I1364J-787D01*
G01X1118156Y207609D02*
G02Y205283I-2015J-1163D01*
G01Y209183D02*
G03Y207609I1364J-787D01*
G01X1118191Y211449D02*
G02X1118156Y209183I-2050J-1102D01*
G01Y211509D02*
X1118191Y211449D01*
G01X1118156Y213083D02*
G03Y211509I1364J-787D01*
G01X1118191Y215349D02*
G02X1118156Y213083I-2050J-1102D01*
G01Y215409D02*
X1118191Y215349D01*
G01X1118137Y215443D02*
X1118156Y215409D01*
G01Y216984D02*
G03X1118137Y215443I1365J-787D01*
G01X1118181Y219267D02*
G02X1118156Y216984I-2040J-1119D01*
G01X1145790Y207450D02*
X1148099D01*
G01X1140568Y212672D02*
X1145790Y207450D01*
G01X1136361Y212672D02*
X1140568D01*
G01X1135036Y215000D02*
G03X1136361Y212672I1384J-753D01*
G01X1135055Y215034D02*
X1135036Y215000D01*
G01X1135080Y215076D02*
X1135055Y215034D01*
G01Y217359D02*
G02X1135080Y215076I-2015J-1164D01*
G01X1135036Y218900D02*
G03X1135055Y217359I1384J-754D01*
G01X1107366Y216984D02*
G02X1107341Y219267I2015J1164D01*
G01X1107385Y215443D02*
G03X1107366Y216984I-1384J754D01*
G01Y215409D02*
X1107385Y215443D01*
G01X1107341Y215367D02*
X1107366Y215409D01*
G01Y213084D02*
G02X1107341Y215367I2015J1164D01*
G01X1107385Y211543D02*
G03X1107366Y213084I-1384J754D01*
G01Y211509D02*
X1107385Y211543D01*
G01X1107200Y210889D02*
G02X1107366Y211509I1240J0D01*
G01X1107200Y209560D02*
Y210889D01*
G01X1116300Y200460D02*
X1107200Y209560D01*
G01X1116300Y197700D02*
Y200460D01*
G01X1122940Y191060D02*
X1116300Y197700D01*
G01X1122940Y186546D02*
Y191060D01*
G01X1121992Y185598D02*
X1122940Y186546D01*
G01X1104636Y216984D02*
G03X1104661Y219267I-2015J1164D01*
G01X1104617Y215443D02*
G02X1104636Y216984I1384J754D01*
G01Y215409D02*
X1104617Y215443D01*
G01X1104661Y215367D02*
X1104636Y215409D01*
G01Y213084D02*
G03X1104661Y215367I-2015J1164D01*
G01X1104617Y211543D02*
G02X1104636Y213084I1384J754D01*
G01X1105900Y209301D02*
X1104617Y211543D01*
G01X1105900Y207590D02*
Y209301D01*
G01X1114130Y199360D02*
X1105900Y207590D01*
G01X1114130Y196560D02*
Y199360D01*
G01X1118770Y191920D02*
X1114130Y196560D01*
G01X1118770Y186130D02*
Y191920D01*
G01X1119492Y185408D02*
X1118770Y186130D01*
G01X1139529Y208021D02*
X1145135Y202415D01*
G01X1136335Y208021D02*
X1139529D01*
G01X1134405Y209183D02*
G03X1136335Y208021I2015J1163D01*
G01X1133084Y209971D02*
G02X1134405Y209183I-44J-1575D01*
G01X1132955Y209971D02*
X1133084D01*
G01X1131025Y213459D02*
G03X1132955Y209971I2015J-1163D01*
G01X1131044Y215000D02*
G02X1131025Y213459I-1384J-754D01*
G01Y215034D02*
X1131044Y215000D01*
G01X1131000Y215076D02*
X1131025Y215034D01*
G01Y217359D02*
G03X1131000Y215076I2015J-1164D01*
G01X1131044Y218900D02*
G02X1131025Y217359I-1384J-754D01*
G01X1096450Y194080D02*
Y198090D01*
G01X1100230Y190300D02*
X1096450Y194080D01*
G01X1100230Y184630D02*
Y190300D01*
G01X1099300Y183700D02*
X1100230Y184630D01*
G01X1103986Y217359D02*
G03X1104005Y218900I-1365J787D01*
G01X1103961Y215076D02*
G02X1103986Y217359I2040J1119D01*
G01Y215034D02*
X1103961Y215076D01*
G01X1104005Y215000D02*
X1103986Y215034D01*
G01Y213459D02*
G03X1104005Y215000I-1365J787D01*
G01X1103961Y211176D02*
G02X1103986Y213459I2040J1119D01*
G01X1105069Y209156D02*
X1103961Y211176D01*
G01X1105069Y207170D02*
Y209156D01*
G01X1113310Y198929D02*
X1105069Y207170D01*
G01X1113310Y196318D02*
Y198929D01*
G01X1118020Y191608D02*
X1113310Y196318D01*
G01X1118020Y186220D02*
Y191608D01*
G01X1116992Y185192D02*
X1118020Y186220D01*
G01X1133345Y197065D02*
X1133395D01*
G01X1127720Y202690D02*
X1133345Y197065D01*
G01X1126050Y202690D02*
X1127720D01*
G01X1124551Y204189D02*
X1126050Y202690D01*
G01X1122970Y204872D02*
G02X1124551Y204189I-70J-2334D01*
G01X1122841Y204872D02*
X1122970D01*
G01X1121516Y207200D02*
G03X1122841Y204872I1384J-753D01*
G01X1121535Y207234D02*
X1121516Y207200D01*
G01X1121560Y207276D02*
X1121535Y207234D01*
G01Y209559D02*
G02X1121560Y207276I-2015J-1164D01*
G01X1121516Y211100D02*
G03X1121535Y209559I1384J-754D01*
G01Y211134D02*
X1121516Y211100D01*
G01X1121560Y211176D02*
X1121535Y211134D01*
G01Y213459D02*
G02X1121560Y211176I-2015J-1164D01*
G01X1121504Y214978D02*
G03X1121535Y213459I1396J-731D01*
G01X1121571Y215094D02*
X1121504Y214978D01*
G01X1121536Y217360D02*
G02X1121571Y215094I-2015J-1164D01*
G01X1121536Y218934D02*
G03Y217360I1364J-787D01*
G01X1126280Y237027D02*
Y235696D01*
G01X1126508Y237255D02*
X1126280Y237027D01*
G01X1127645Y236484D02*
G03X1126508Y237255I-1365J-789D01*
G01X1129609Y235321D02*
G02X1127645Y236484I51J2326D01*
G01X1129704Y235321D02*
X1129609D01*
G01X1131025Y234533D02*
G03X1129704Y235321I-1365J-787D01*
G01X1132955Y233371D02*
G02X1131025Y234533I85J2325D01*
G01X1133111Y233371D02*
X1132955D01*
G01X1134405Y231010D02*
G03X1133111Y233371I-1365J787D01*
G01X1134405Y228684D02*
G02Y231010I2015J1163D01*
G01X1134424Y227143D02*
G03X1134405Y228684I-1384J754D01*
G01Y227109D02*
X1134424Y227143D01*
G01X1134380Y227067D02*
X1134405Y227109D01*
G01Y224784D02*
G02X1134380Y227067I2015J1164D01*
G01X1134424Y223243D02*
G03X1134405Y224784I-1384J754D01*
G01Y223209D02*
X1134424Y223243D01*
G01X1134380Y223167D02*
X1134405Y223209D01*
G01Y220884D02*
G02X1134380Y223167I2015J1164D01*
G01X1134424Y219343D02*
G03X1134405Y220884I-1384J754D01*
G01Y219309D02*
X1134424Y219343D01*
G01X1134380Y219267D02*
X1134405Y219309D01*
G01X1107950Y236975D02*
X1106001Y239596D01*
G01X1108016Y236859D02*
X1107950Y236975D01*
G01X1108016Y234533D02*
G03Y236859I-2015J1163D01*
G01Y232959D02*
G02Y234533I1365J787D01*
G01X1108041Y232917D02*
X1108016Y232959D01*
G01Y230634D02*
G03X1108041Y232917I-2015J1164D01*
G01X1107997Y230600D02*
X1108016Y230634D01*
G01Y229059D02*
G02X1107997Y230600I1365J787D01*
G01X1108041Y226776D02*
G03X1108016Y229059I-2040J1119D01*
G01Y226734D02*
X1108041Y226776D01*
G01X1107997Y226700D02*
X1108016Y226734D01*
G01Y225159D02*
G02X1107997Y226700I1365J787D01*
G01X1108041Y222876D02*
G03X1108016Y225159I-2040J1119D01*
G01Y222834D02*
X1108041Y222876D01*
G01X1107997Y222800D02*
X1108016Y222834D01*
G01Y221259D02*
G02X1107997Y222800I1365J787D01*
G01X1108041Y218976D02*
G03X1108016Y221259I-2040J1119D01*
G01Y218934D02*
X1108041Y218976D01*
G01X1107997Y218900D02*
X1108016Y218934D01*
G01X1131675Y219309D02*
X1131700Y219267D01*
G01X1131656Y219343D02*
X1131675Y219309D01*
G01Y220884D02*
G03X1131656Y219343I1365J-787D01*
G01X1131700Y223167D02*
G02X1131675Y220884I-2040J-1119D01*
G01Y223209D02*
X1131700Y223167D01*
G01X1131656Y223243D02*
X1131675Y223209D01*
G01Y224784D02*
G03X1131656Y223243I1365J-787D01*
G01X1131700Y227067D02*
G02X1131675Y224784I-2040J-1119D01*
G01Y227109D02*
X1131700Y227067D01*
G01X1131656Y227143D02*
X1131675Y227109D01*
G01Y228684D02*
G03X1131656Y227143I1365J-787D01*
G01X1129745Y232172D02*
G02X1131675Y228684I-85J-2325D01*
G01X1129589Y232172D02*
X1129745D01*
G01X1128295Y232959D02*
G03X1129589Y232172I1365J787D01*
G01X1126350Y234122D02*
G02X1128295Y232959I-70J-2325D01*
G01X1126209Y234122D02*
X1126350D01*
G01X1124915Y234909D02*
G03X1126209Y234122I1365J787D01*
G01X1124577Y235479D02*
X1124915Y234909D01*
G01X1124500Y238435D02*
X1124577Y235479D01*
G01X1122900Y241547D02*
X1124500Y238435D01*
G01X1117506Y218934D02*
X1117525Y218900D01*
G01X1117481Y218976D02*
X1117506Y218934D01*
G01Y221259D02*
G03X1117481Y218976I2015J-1164D01*
G01X1116185Y223622D02*
G02X1117506Y221259I-44J-1575D01*
G01X1116056Y223622D02*
X1116185D01*
G01X1114126Y224784D02*
G03X1116056Y223622I2015J1163D01*
G01X1112820Y225571D02*
G02X1114126Y224784I-59J-1575D01*
G01X1112691Y225571D02*
X1112820D01*
G01X1110746Y229059D02*
G03X1112691Y225571I2015J-1163D01*
G01X1110746Y230634D02*
G02Y229059I-1363J-787D01*
G01X1110721Y232917D02*
G03X1110746Y230634I2040J-1119D01*
G01Y232959D02*
X1110721Y232917D01*
G01X1110812Y233075D02*
X1110746Y232959D01*
G01X1112761Y235696D02*
X1110812Y233075D01*
G01X1120885Y219309D02*
X1120850Y219249D01*
G01X1120885Y220883D02*
G02Y219309I-1364J-787D01*
G01X1120850Y223149D02*
G03X1120885Y220883I2050J-1102D01*
G01Y223209D02*
X1120850Y223149D01*
G01X1119521Y225571D02*
G02X1120885Y223209I0J-1575D01*
G01X1119451Y225571D02*
X1119521D01*
G01X1117506Y226734D02*
G03X1119451Y225571I2015J1162D01*
G01X1116185Y227522D02*
G02X1117506Y226734I-44J-1575D01*
G01X1116056Y227522D02*
X1116185D01*
G01X1114126Y231010D02*
G03X1116056Y227522I2015J-1163D01*
G01X1114191Y231124D02*
X1114126Y231010D01*
G01X1116141Y233746D02*
X1114191Y231124D01*
G01X1095912Y236072D02*
X1095802D01*
G01X1097160Y234647D02*
G03X1095912Y236072I-4241J-2455D01*
G01X1097226Y234533D02*
X1097160Y234647D01*
G01X1097226Y232959D02*
G03Y234533I-1365J787D01*
G01X1096941Y232598D02*
G03X1097226Y232959I-1081J1147D01*
G01X1096705Y232415D02*
G03X1096941Y232598I-843J1331D01*
G01X1095349Y231337D02*
G02X1096705Y232415I5692J-5768D01*
G01X1118156Y219309D02*
X1118181Y219267D01*
G01X1118137Y219343D02*
X1118156Y219309D01*
G01Y220884D02*
G03X1118137Y219343I1365J-787D01*
G01X1116211Y224372D02*
G02X1118156Y220884I-70J-2325D01*
G01X1116082Y224372D02*
X1116211D01*
G01X1114776Y225159D02*
G03X1116082Y224372I1365J788D01*
G01X1112846Y226321D02*
G02X1114776Y225159I-85J-2325D01*
G01X1112717Y226321D02*
X1112846D01*
G01X1111396Y228684D02*
G03X1112717Y226321I1365J-788D01*
G01X1111462Y228798D02*
X1111396Y228684D01*
G01Y231010D02*
G02X1111462Y228798I-2025J-1167D01*
G01X1112690Y233371D02*
G03X1111396Y231010I71J-1574D01*
G01X1114392Y235152D02*
G02X1112690Y233371I-1783J0D01*
G01X1114392Y235490D02*
Y235152D01*
G01X1114126Y236484D02*
G02X1114392Y235490I-1725J-994D01*
G01X1114060Y236597D02*
X1114126Y236484D01*
G01X1112761Y239596D02*
X1114060Y236597D01*
G01X1135055Y218934D02*
X1135036Y218900D01*
G01X1135080Y218976D02*
X1135055Y218934D01*
G01Y221259D02*
G02X1135080Y218976I-2015J-1164D01*
G01X1135036Y222800D02*
G03X1135055Y221259I1384J-754D01*
G01Y222834D02*
X1135036Y222800D01*
G01X1135080Y222876D02*
X1135055Y222834D01*
G01Y225159D02*
G02X1135080Y222876I-2015J-1164D01*
G01X1135036Y226700D02*
G03X1135055Y225159I1384J-754D01*
G01Y226734D02*
X1135036Y226700D01*
G01X1135080Y226776D02*
X1135055Y226734D01*
G01Y229059D02*
G02X1135080Y226776I-2015J-1164D01*
G01X1135036Y230600D02*
G03X1135055Y229059I1384J-754D01*
G01Y230634D02*
X1135036Y230600D01*
G01X1133110Y234122D02*
G02X1135055Y230634I-70J-2325D01*
G01X1132969Y234122D02*
X1133110D01*
G01X1131675Y234909D02*
G03X1132969Y234122I1365J787D01*
G01X1129711Y236072D02*
G02X1131675Y234909I-51J-2326D01*
G01X1129601Y236072D02*
X1129711D01*
G01X1128295Y236859D02*
G03X1129601Y236072I1365J788D01*
G01X1126536Y238009D02*
G02X1128295Y236859I-256J-2312D01*
G01X1126280Y238265D02*
X1126536Y238009D01*
G01X1126280Y239596D02*
Y238265D01*
G01X1107299Y232699D02*
X1106001Y235696D01*
G01X1107366Y232584D02*
X1107299Y232699D01*
G01X1107366Y231010D02*
G03Y232584I-1365J787D01*
G01Y228684D02*
G02Y231010I2015J1163D01*
G01X1107385Y227143D02*
G03X1107366Y228684I-1384J754D01*
G01Y227109D02*
X1107385Y227143D01*
G01X1107341Y227067D02*
X1107366Y227109D01*
G01Y224784D02*
G02X1107341Y227067I2015J1164D01*
G01X1107385Y223243D02*
G03X1107366Y224784I-1384J754D01*
G01Y223209D02*
X1107385Y223243D01*
G01X1107341Y223167D02*
X1107366Y223209D01*
G01Y220884D02*
G02X1107341Y223167I2015J1164D01*
G01X1107385Y219343D02*
G03X1107366Y220884I-1384J754D01*
G01Y219309D02*
X1107385Y219343D01*
G01X1107341Y219267D02*
X1107366Y219309D01*
G01X1104570Y238925D02*
X1102621Y241547D01*
G01X1104636Y238809D02*
X1104570Y238925D01*
G01X1104661Y238767D02*
X1104636Y238809D01*
G01Y236484D02*
G03X1104661Y238767I-2015J1164D01*
G01X1104617Y234943D02*
G02X1104636Y236484I1384J754D01*
G01Y234909D02*
X1104617Y234943D01*
G01X1104661Y232626D02*
G03X1104636Y234909I-2040J1119D01*
G01Y232584D02*
X1104661Y232626D01*
G01X1104636Y231010D02*
G02Y232584I1365J787D01*
G01Y228684D02*
G03Y231010I-2015J1163D01*
G01X1104617Y227143D02*
G02X1104636Y228684I1384J754D01*
G01Y227109D02*
X1104617Y227143D01*
G01X1104661Y227067D02*
X1104636Y227109D01*
G01Y224784D02*
G03X1104661Y227067I-2015J1164D01*
G01X1104617Y223243D02*
G02X1104636Y224784I1384J754D01*
G01Y223209D02*
X1104617Y223243D01*
G01X1104661Y223167D02*
X1104636Y223209D01*
G01Y220884D02*
G03X1104661Y223167I-2015J1164D01*
G01X1104617Y219343D02*
G02X1104636Y220884I1384J754D01*
G01Y219309D02*
X1104617Y219343D01*
G01X1104661Y219267D02*
X1104636Y219309D01*
G01X1131025Y218934D02*
X1131044Y218900D01*
G01X1131000Y218976D02*
X1131025Y218934D01*
G01Y221259D02*
G03X1131000Y218976I2015J-1164D01*
G01X1131044Y222800D02*
G02X1131025Y221259I-1384J-754D01*
G01Y222834D02*
X1131044Y222800D01*
G01X1131000Y222876D02*
X1131025Y222834D01*
G01Y225159D02*
G03X1131000Y222876I2015J-1164D01*
G01X1131044Y226700D02*
G02X1131025Y225159I-1384J-754D01*
G01Y226734D02*
X1131044Y226700D01*
G01X1131000Y226776D02*
X1131025Y226734D01*
G01Y229059D02*
G03X1131000Y226776I2015J-1164D01*
G01X1129731Y231421D02*
G02X1131025Y229059I-71J-1574D01*
G01X1129590Y231421D02*
X1129731D01*
G01X1127645Y232584D02*
G03X1129590Y231421I2015J1162D01*
G01X1126351Y233371D02*
G02X1127645Y232584I-71J-1574D01*
G01X1126195Y233371D02*
X1126351D01*
G01X1125029Y233363D02*
X1126195Y233371D01*
G01X1122900Y233746D02*
X1125029Y233363D01*
G01X1103921Y230746D02*
X1102621Y233746D01*
G01X1104005Y230600D02*
X1103921Y230746D01*
G01X1103986Y229059D02*
G03X1104005Y230600I-1365J787D01*
G01X1103961Y226776D02*
G02X1103986Y229059I2040J1119D01*
G01Y226734D02*
X1103961Y226776D01*
G01X1104005Y226700D02*
X1103986Y226734D01*
G01Y225159D02*
G03X1104005Y226700I-1365J787D01*
G01X1103961Y222876D02*
G02X1103986Y225159I2040J1119D01*
G01Y222834D02*
X1103961Y222876D01*
G01X1104005Y222800D02*
X1103986Y222834D01*
G01Y221259D02*
G03X1104005Y222800I-1365J787D01*
G01X1103961Y218976D02*
G02X1103986Y221259I2040J1119D01*
G01Y218934D02*
X1103961Y218976D01*
G01X1104005Y218900D02*
X1103986Y218934D01*
G01X1121571Y218994D02*
X1121536Y218934D01*
G01Y221260D02*
G02X1121571Y218994I-2015J-1164D01*
G01X1121536Y222834D02*
G03Y221260I1364J-787D01*
G01X1121571Y222894D02*
X1121536Y222834D01*
G01X1119619Y226321D02*
G02X1121571Y222894I-98J-2325D01*
G01X1119477Y226321D02*
X1119619D01*
G01X1118156Y227109D02*
G03X1119477Y226321I1365J787D01*
G01X1116211Y228272D02*
G02X1118156Y227109I-70J-2325D01*
G01X1116082Y228272D02*
X1116211D01*
G01X1115677Y231352D02*
G03X1116082Y228272I463J-1506D01*
G01X1117481Y232917D02*
G02X1115677Y231352I-3269J1946D01*
G01X1117506Y232959D02*
X1117481Y232917D01*
G01X1117506Y234533D02*
G02Y232959I-1365J-787D01*
G01X1117331Y234912D02*
G03X1117506Y234533I2191J782D01*
G01X1115610Y236163D02*
G02X1117331Y234912I-1275J-3563D01*
G01X1114757Y238400D02*
G03X1115610Y236163I1384J-753D01*
G01X1114844Y238551D02*
X1114757Y238400D01*
G01X1116141Y241547D02*
X1114844Y238551D01*
G01X1122656Y340209D02*
G03X1120711Y341372I-2015J-1162D01*
G01X1123977Y339421D02*
G02X1122656Y340209I44J1575D01*
G01X1124119Y339421D02*
X1123977D01*
G01X1126036Y338260D02*
G03X1124119Y339421I-2015J-1164D01*
G01X1126049Y338237D02*
X1126036Y338260D01*
G01X1127400Y337472D02*
G02X1126049Y338237I0J1575D01*
G01X1127470Y337472D02*
X1127400D01*
G01X1129415Y336309D02*
G03X1127470Y337472I-2015J-1162D01*
G01X1130736Y335521D02*
G02X1129415Y336309I44J1575D01*
G01X1130865Y335521D02*
X1130736D01*
G01X1132795Y334359D02*
G03X1130865Y335521I-2015J-1163D01*
G01X1134101Y333572D02*
G02X1132795Y334359I59J1575D01*
G01X1134230Y333572D02*
X1134101D01*
G01X1136175Y332409D02*
G03X1134230Y333572I-2015J-1162D01*
G01X1137496Y331621D02*
G02X1136175Y332409I44J1575D01*
G01X1137625Y331621D02*
X1137496D01*
G01X1139555Y330459D02*
G03X1137625Y331621I-2015J-1163D01*
G01X1140861Y329672D02*
G02X1139555Y330459I59J1575D01*
G01X1140990Y329672D02*
X1140861D01*
G01X1142935Y328509D02*
G03X1140990Y329672I-2015J-1162D01*
G01X1144256Y327721D02*
G02X1142935Y328509I44J1575D01*
G01X1144385Y327721D02*
X1144256D01*
G01X1146315Y326559D02*
G03X1144385Y327721I-2015J-1163D01*
G01X1147621Y325772D02*
G02X1146315Y326559I59J1575D01*
G01X1147731Y325772D02*
X1147621D01*
G01X1149695Y324609D02*
G03X1147731Y325772I-2015J-1163D01*
G01X1151016Y323821D02*
G02X1149695Y324609I44J1575D01*
G01X1151145Y323821D02*
X1151016D01*
G01X1153075Y322659D02*
G03X1151145Y323821I-2015J-1163D01*
G01X1153100Y320376D02*
G03X1153075Y322659I-2040J1119D01*
G01Y320334D02*
X1153100Y320376D01*
G01X1153056Y320300D02*
X1153075Y320334D01*
G01Y318759D02*
G02X1153056Y320300I1365J787D01*
G01X1154381Y317972D02*
G02X1153075Y318759I59J1575D01*
G01X1154510Y317972D02*
X1154381D01*
G01X1156455Y316809D02*
G03X1154510Y317972I-2015J-1162D01*
G01X1157776Y316021D02*
G02X1156455Y316809I44J1575D01*
G01X1120556Y340622D02*
G02X1118626Y341784I85J2325D01*
G01X1120685Y340622D02*
X1120556D01*
G01X1122006Y339834D02*
G03X1120685Y340622I-1365J-787D01*
G01X1123951Y338671D02*
G02X1122006Y339834I70J2325D01*
G01X1124021Y338671D02*
X1123951D01*
G01X1125372Y337906D02*
G03X1124021Y338671I-1351J-810D01*
G01X1125385Y337883D02*
X1125372Y337906D01*
G01X1127302Y336722D02*
G02X1125385Y337883I98J2325D01*
G01X1127444Y336722D02*
X1127302D01*
G01X1128765Y335934D02*
G03X1127444Y336722I-1365J-787D01*
G01X1130710Y334771D02*
G02X1128765Y335934I70J2325D01*
G01X1130839Y334771D02*
X1130710D01*
G01X1132145Y333984D02*
G03X1130839Y334771I-1365J-788D01*
G01X1134075Y332822D02*
G02X1132145Y333984I85J2325D01*
G01X1134204Y332822D02*
X1134075D01*
G01X1135525Y332034D02*
G03X1134204Y332822I-1365J-787D01*
G01X1137470Y330871D02*
G02X1135525Y332034I70J2325D01*
G01X1137599Y330871D02*
X1137470D01*
G01X1138905Y330084D02*
G03X1137599Y330871I-1365J-788D01*
G01X1140835Y328922D02*
G02X1138905Y330084I85J2325D01*
G01X1140964Y328922D02*
X1140835D01*
G01X1142285Y328134D02*
G03X1140964Y328922I-1365J-787D01*
G01X1144230Y326971D02*
G02X1142285Y328134I70J2325D01*
G01X1144359Y326971D02*
X1144230D01*
G01X1145665Y326184D02*
G03X1144359Y326971I-1365J-788D01*
G01X1147629Y325021D02*
G02X1145665Y326184I51J2326D01*
G01X1147724Y325021D02*
X1147629D01*
G01X1149045Y324233D02*
G03X1147724Y325021I-1365J-787D01*
G01X1150975Y323071D02*
G02X1149045Y324233I85J2325D01*
G01X1151104Y323071D02*
X1150975D01*
G01X1152425Y322283D02*
G03X1151104Y323071I-1365J-787D01*
G01X1152425Y320709D02*
G03Y322283I-1365J787D01*
G01X1152400Y320667D02*
X1152425Y320709D01*
G01Y318384D02*
G02X1152400Y320667I2015J1164D01*
G01X1154355Y317222D02*
G02X1152425Y318384I85J2325D01*
G01X1154484Y317222D02*
X1154355D01*
G01X1155805Y316434D02*
G03X1154484Y317222I-1365J-787D01*
G01X1157750Y315271D02*
G02X1155805Y316434I70J2325D01*
G01X1139200Y367730D02*
Y371121D01*
G01X1137440Y365970D02*
X1139200Y367730D01*
G01X1136888Y365970D02*
X1137440D01*
G01X1135279Y364361D02*
X1136888Y365970D01*
G01X1133848Y364361D02*
X1135279D01*
G01X1131678Y362191D02*
X1133848Y364361D01*
G01X1129995Y362191D02*
X1131678D01*
G01X1127968Y364218D02*
X1129995Y362191D01*
G01X1096937Y355021D02*
G02X1095616Y355809I44J1575D01*
G01X1097066Y355021D02*
X1096937D01*
G01X1098996Y353859D02*
G03X1097066Y355021I-2015J-1163D01*
G01X1100302Y353072D02*
G02X1098996Y353859I59J1575D01*
G01X1100431Y353072D02*
X1100302D01*
G01X1102376Y351909D02*
G03X1100431Y353072I-2015J-1162D01*
G01X1103697Y351121D02*
G02X1102376Y351909I44J1575D01*
G01X1103826Y351121D02*
X1103697D01*
G01X1105756Y349959D02*
G03X1103826Y351121I-2015J-1163D01*
G01X1107062Y349172D02*
G02X1105756Y349959I59J1575D01*
G01X1107191Y349172D02*
X1107062D01*
G01X1109136Y348009D02*
G03X1107191Y349172I-2015J-1162D01*
G01X1109149Y347986D02*
X1109136Y348009D01*
G01X1110500Y347221D02*
G02X1109149Y347986I0J1575D01*
G01X1110585Y347222D02*
X1110500Y347221D01*
G01X1112516Y346059D02*
G03X1110585Y347222I-2016J-1162D01*
G01X1113822Y345272D02*
G02X1112516Y346059I59J1575D01*
G01X1113951Y345272D02*
X1113822D01*
G01X1115896Y344109D02*
G03X1113951Y345272I-2015J-1162D01*
G01X1115909Y344086D02*
X1115896Y344109D01*
G01X1117260Y343321D02*
G02X1115909Y344086I0J1575D01*
G01X1117345Y343322D02*
X1117260Y343321D01*
G01X1119276Y342159D02*
G03X1117345Y343322I-2016J-1162D01*
G01X1120582Y341372D02*
G02X1119276Y342159I59J1575D01*
G01X1120711Y341372D02*
X1120582D01*
G01X1122637Y402643D02*
G02X1123962Y404971I1384J753D01*
G01X1122656Y402609D02*
X1122637Y402643D01*
G01X1122681Y402567D02*
X1122656Y402609D01*
G01Y400284D02*
G03X1122681Y402567I-2015J1164D01*
G01X1122637Y398743D02*
G02X1122656Y400284I1384J754D01*
G01Y398709D02*
X1122637Y398743D01*
G01X1122681Y398667D02*
X1122656Y398709D01*
G01Y396384D02*
G03X1122681Y398667I-2015J1164D01*
G01X1122637Y394843D02*
G02X1122656Y396384I1384J754D01*
G01Y394809D02*
X1122637Y394843D01*
G01X1122681Y394767D02*
X1122656Y394809D01*
G01Y392484D02*
G03X1122681Y394767I-2015J1164D01*
G01X1122637Y390943D02*
G02X1122656Y392484I1384J754D01*
G01X1122657Y390909D02*
X1122637Y390943D01*
G01X1122657Y388583D02*
G03Y390909I-2015J1163D01*
G01Y387009D02*
G02Y388583I1365J787D01*
G01Y384683D02*
G03Y387009I-2015J1163D01*
G01Y383109D02*
G02Y384683I1365J787D01*
G01Y380783D02*
G03Y383109I-2015J1163D01*
G01Y379209D02*
G02Y380783I1365J787D01*
G01X1122832Y378832D02*
G03X1122657Y379209I-2189J-787D01*
G01X1124021Y376096D02*
X1122832Y378832D01*
G01X1101701Y402276D02*
G02X1101726Y404559I2040J1119D01*
G01Y402234D02*
X1101701Y402276D01*
G01X1101745Y402200D02*
X1101726Y402234D01*
G01Y400659D02*
G03X1101745Y402200I-1365J787D01*
G01X1101701Y398376D02*
G02X1101726Y400659I2040J1119D01*
G01Y398334D02*
X1101701Y398376D01*
G01X1101745Y398300D02*
X1101726Y398334D01*
G01Y396759D02*
G03X1101745Y398300I-1365J787D01*
G01X1101701Y394476D02*
G02X1101726Y396759I2040J1119D01*
G01Y394434D02*
X1101701Y394476D01*
G01X1101745Y394400D02*
X1101726Y394434D01*
G01X1101802Y393009D02*
G03X1101745Y394400I-1441J638D01*
G01X1101726Y392861D02*
G03X1101802Y393009I-1245J733D01*
G01X1101726Y390535D02*
G02Y392861I2015J1163D01*
G01Y388961D02*
G03Y390535I-1365J787D01*
G01Y386635D02*
G02Y388961I2015J1163D01*
G01Y385061D02*
G03Y386635I-1365J787D01*
G01Y382735D02*
G02Y385061I2015J1163D01*
G01Y381161D02*
G03Y382735I-1365J787D01*
G01Y378835D02*
G02Y381161I2015J1163D01*
G01Y377261D02*
G03Y378835I-1365J787D01*
G01Y374935D02*
G02Y377261I2015J1163D01*
G01X1102243Y374039D02*
X1101726Y374935D01*
G01X1102603Y370869D02*
X1103741Y368296D01*
G01X1102376Y371411D02*
G02X1102603Y370869I-2015J-1163D01*
G01X1102304Y372844D02*
G03X1102376Y371411I1437J-646D01*
G01X1102243Y374039D02*
G02X1102304Y372844I-1136J-657D01*
G01X1115246Y402233D02*
G02Y404559I2015J1163D01*
G01X1115265Y400692D02*
G03X1115246Y402233I-1384J754D01*
G01Y400658D02*
X1115265Y400692D01*
G01X1115211Y400598D02*
X1115246Y400658D01*
G01Y398332D02*
G02X1115211Y400598I2015J1164D01*
G01X1115273Y396806D02*
G03X1115246Y398332I-1392J739D01*
G01Y396758D02*
X1115273Y396806D01*
G01X1115221Y396716D02*
X1115246Y396758D01*
G01Y394433D02*
G02X1115221Y396716I2015J1164D01*
G01X1115265Y392892D02*
G03X1115246Y394433I-1384J754D01*
G01Y392861D02*
G02X1115265Y392892I597J-344D01*
G01X1115246Y390535D02*
G02Y392861I2015J1163D01*
G01Y388961D02*
G03Y390535I-1365J787D01*
G01Y386635D02*
G02Y388961I2015J1163D01*
G01Y385061D02*
G03Y386635I-1365J787D01*
G01Y382735D02*
G02Y385061I2015J1163D01*
G01Y381161D02*
G03Y382735I-1365J787D01*
G01Y378835D02*
G02Y381161I2015J1163D01*
G01Y377261D02*
G03Y378835I-1365J787D01*
G01X1113311Y375617D02*
G03X1115246Y377261I-1400J3609D01*
G01X1112441Y373509D02*
G02X1113311Y375617I1440J639D01*
G01X1113881Y370247D02*
X1112441Y373509D01*
G01X1118645Y402643D02*
G03X1118626Y404184I-1384J754D01*
G01Y402609D02*
X1118645Y402643D01*
G01X1118601Y402567D02*
X1118626Y402609D01*
G01Y400284D02*
G02X1118601Y402567I2015J1164D01*
G01X1118645Y398743D02*
G03X1118626Y400284I-1384J754D01*
G01Y398709D02*
X1118645Y398743D01*
G01X1118601Y398667D02*
X1118626Y398709D01*
G01Y396384D02*
G02X1118601Y398667I2015J1164D01*
G01X1118645Y394843D02*
G03X1118626Y396384I-1384J754D01*
G01Y394809D02*
X1118645Y394843D01*
G01X1118601Y394767D02*
X1118626Y394809D01*
G01Y392484D02*
G02X1118601Y394767I2015J1164D01*
G01X1118645Y390943D02*
G03X1118626Y392484I-1384J754D01*
G01X1118627Y390909D02*
G03X1118645Y390943I-456J263D01*
G01X1118627Y388583D02*
G02Y390909I2015J1163D01*
G01Y387009D02*
G03Y388583I-1365J787D01*
G01Y384683D02*
G02Y387009I2015J1163D01*
G01Y383109D02*
G03Y384683I-1365J787D01*
G01Y380783D02*
G02Y383109I2015J1163D01*
G01Y379209D02*
G03Y380783I-1365J787D01*
G01Y376883D02*
G02Y379209I2015J1163D01*
G01Y375309D02*
G03Y376883I-1365J787D01*
G01X1118502Y373234D02*
G02X1118627Y375309I2140J912D01*
G01X1120641Y370247D02*
X1118502Y373234D01*
G01X1136109Y376769D02*
X1134160Y374146D01*
G01X1136175Y376884D02*
X1136109Y376769D01*
G01X1136200Y379167D02*
G02X1136175Y376884I-2040J-1119D01*
G01Y379209D02*
X1136200Y379167D01*
G01X1136156Y379243D02*
X1136175Y379209D01*
G01Y380784D02*
G03X1136156Y379243I1365J-787D01*
G01X1136200Y383067D02*
G02X1136175Y380784I-2040J-1119D01*
G01Y383109D02*
X1136200Y383067D01*
G01X1136156Y383143D02*
X1136175Y383109D01*
G01Y384684D02*
G03X1136156Y383143I1365J-787D01*
G01X1136200Y386967D02*
G02X1136175Y384684I-2040J-1119D01*
G01Y387009D02*
X1136200Y386967D01*
G01X1136156Y387043D02*
X1136175Y387009D01*
G01Y388584D02*
G03X1136156Y387043I1365J-787D01*
G01X1136200Y390867D02*
G02X1136175Y388584I-2040J-1119D01*
G01Y390909D02*
X1136200Y390867D01*
G01X1136156Y390943D02*
X1136175Y390909D01*
G01Y392484D02*
G03X1136156Y390943I1365J-787D01*
G01X1136175Y394810D02*
G02Y392484I-2015J-1163D01*
G01X1137469Y397171D02*
G03X1136175Y394810I71J-1574D01*
G01X1137625Y397171D02*
X1137469D01*
G01X1139555Y400659D02*
G02X1137625Y397171I-2015J-1163D01*
G01X1139536Y402200D02*
G03X1139555Y400659I1384J-754D01*
G01Y402234D02*
X1139536Y402200D01*
G01X1139580Y402276D02*
X1139555Y402234D01*
G01Y404559D02*
G02X1139580Y402276I-2015J-1164D01*
G01X1098365Y402643D02*
G03X1098346Y404184I-1384J754D01*
G01Y402609D02*
X1098365Y402643D01*
G01X1098321Y402567D02*
X1098346Y402609D01*
G01Y400284D02*
G02X1098321Y402567I2015J1164D01*
G01X1098365Y398743D02*
G03X1098346Y400284I-1384J754D01*
G01Y398709D02*
X1098365Y398743D01*
G01X1098321Y398667D02*
X1098346Y398709D01*
G01Y396384D02*
G02X1098321Y398667I2015J1164D01*
G01X1098365Y394843D02*
G03X1098346Y396384I-1384J754D01*
G01Y394809D02*
X1098365Y394843D01*
G01X1098321Y394767D02*
X1098346Y394809D01*
G01Y392484D02*
G02X1098321Y394767I2015J1164D01*
G01X1098365Y390943D02*
G03X1098346Y392484I-1384J754D01*
G01Y390911D02*
X1098365Y390943D01*
G01X1098346Y388585D02*
G02Y390911I2015J1163D01*
G01Y387011D02*
G03Y388585I-1365J787D01*
G01Y384685D02*
G02Y387011I2015J1163D01*
G01Y383111D02*
G03Y384685I-1365J787D01*
G01Y380785D02*
G02Y383111I2015J1163D01*
G01Y379211D02*
G03Y380785I-1365J787D01*
G01Y376885D02*
G02Y379211I2015J1163D01*
G01Y375311D02*
G03Y376885I-1365J787D01*
G01X1098788Y372433D02*
G02X1098346Y375311I1573J1715D01*
G01X1100361Y370247D02*
X1098788Y372433D01*
G01X1138924Y402643D02*
G03X1138905Y404184I-1384J754D01*
G01Y402609D02*
X1138924Y402643D01*
G01X1138880Y402567D02*
X1138905Y402609D01*
G01Y400284D02*
G02X1138880Y402567I2015J1164D01*
G01X1137611Y397922D02*
G03X1138905Y400284I-71J1574D01*
G01X1137455Y397922D02*
X1137611D01*
G01X1135525Y394434D02*
G02X1137455Y397922I2015J1163D01*
G01X1135544Y394400D02*
X1135525Y394434D01*
G01Y392859D02*
G03X1135544Y394400I-1365J787D01*
G01X1135500Y390576D02*
G02X1135525Y392859I2040J1119D01*
G01Y390534D02*
X1135500Y390576D01*
G01X1135544Y390500D02*
X1135525Y390534D01*
G01Y388959D02*
G03X1135544Y390500I-1365J787D01*
G01X1135500Y386676D02*
G02X1135525Y388959I2040J1119D01*
G01Y386634D02*
X1135500Y386676D01*
G01X1135544Y386600D02*
X1135525Y386634D01*
G01Y385059D02*
G03X1135544Y386600I-1365J787D01*
G01X1135500Y382776D02*
G02X1135525Y385059I2040J1119D01*
G01Y382734D02*
X1135500Y382776D01*
G01X1135544Y382700D02*
X1135525Y382734D01*
G01Y381159D02*
G03X1135544Y382700I-1365J787D01*
G01X1135500Y378876D02*
G02X1135525Y381159I2040J1119D01*
G01Y378834D02*
X1135500Y378876D01*
G01X1135544Y378800D02*
X1135525Y378834D01*
G01X1134219Y376472D02*
G03X1135544Y378800I-59J1575D01*
G01X1134109Y376472D02*
X1134219D01*
G01X1132120Y373026D02*
G02X1134109Y376472I2040J1120D01*
G01X1132145Y372984D02*
X1132120Y373026D01*
G01X1132211Y372868D02*
X1132145Y372984D01*
G01Y371410D02*
G03X1132211Y372868I-1123J781D01*
G01X1132145Y369084D02*
G02Y371410I2015J1163D01*
G01X1132164Y367543D02*
G03X1132145Y369084I-1384J754D01*
G01X1132077Y367392D02*
X1132164Y367543D01*
G01X1130780Y364396D02*
X1132077Y367392D01*
G01X1122007Y374933D02*
X1122524Y374037D01*
G01X1121981Y402276D02*
G02X1123936Y405721I2040J1120D01*
G01X1122006Y402234D02*
X1121981Y402276D01*
G01X1122025Y402200D02*
X1122006Y402234D01*
G01Y400659D02*
G03X1122025Y402200I-1365J787D01*
G01X1121981Y398376D02*
G02X1122006Y400659I2040J1119D01*
G01Y398334D02*
X1121981Y398376D01*
G01X1122025Y398300D02*
X1122006Y398334D01*
G01Y396759D02*
G03X1122025Y398300I-1365J787D01*
G01X1121981Y394476D02*
G02X1122006Y396759I2040J1119D01*
G01Y394434D02*
X1121981Y394476D01*
G01X1122025Y394400D02*
X1122006Y394434D01*
G01Y392859D02*
G03X1122025Y394400I-1365J787D01*
G01X1121981Y390576D02*
G02X1122006Y392859I2040J1119D01*
G01X1122007Y390533D02*
G03X1121981Y390576I-1045J-603D01*
G01X1122007Y388959D02*
G03Y390533I-1365J787D01*
G01Y386633D02*
G02Y388959I2015J1163D01*
G01Y385059D02*
G03Y386633I-1365J787D01*
G01Y382733D02*
G02Y385059I2015J1163D01*
G01Y381159D02*
G03Y382733I-1365J787D01*
G01Y378833D02*
G02Y381159I2015J1163D01*
G01Y377259D02*
G03Y378833I-1365J787D01*
G01Y374933D02*
G02Y377259I2015J1163D01*
G01X1122585Y372842D02*
G03X1122524Y374037I-1197J538D01*
G01X1122657Y371409D02*
G02X1122585Y372842I1365J787D01*
G01X1122842Y371003D02*
G03X1122657Y371409I-2200J-757D01*
G01X1124021Y368296D02*
X1122842Y371003D01*
G01X1112541Y402274D02*
G03X1112516Y404559I-2040J1120D01*
G01Y402232D02*
X1112541Y402274D01*
G01X1112516Y400658D02*
G02Y402232I1365J787D01*
G01Y398332D02*
G03Y400658I-2015J1163D01*
G01X1112497Y396791D02*
G02X1112516Y398332I1384J754D01*
G01Y396757D02*
X1112497Y396791D01*
G01X1112541Y396715D02*
X1112516Y396757D01*
G01Y394432D02*
G03X1112541Y396715I-2015J1164D01*
G01X1112497Y394400D02*
G02X1112516Y394432I442J-241D01*
G01Y392859D02*
G02X1112497Y394400I1365J787D01*
G01X1112541Y390576D02*
G03X1112516Y392859I-2040J1119D01*
G01Y390534D02*
X1112541Y390576D01*
G01X1112497Y390500D02*
X1112516Y390534D01*
G01Y388959D02*
G02X1112497Y390500I1365J787D01*
G01X1112541Y386676D02*
G03X1112516Y388959I-2040J1119D01*
G01Y386634D02*
X1112541Y386676D01*
G01X1112497Y386600D02*
X1112516Y386634D01*
G01Y385059D02*
G02X1112497Y386600I1365J787D01*
G01X1112541Y382776D02*
G03X1112516Y385059I-2040J1119D01*
G01Y382734D02*
X1112541Y382776D01*
G01X1112497Y382700D02*
X1112516Y382734D01*
G01Y381159D02*
G02X1112497Y382700I1365J787D01*
G01X1112541Y378876D02*
G03X1112516Y381159I-2040J1119D01*
G01Y378834D02*
X1112541Y378876D01*
G01X1112450Y378718D02*
X1112516Y378834D01*
G01X1112023Y378144D02*
X1112450Y378718D01*
G01X1110501Y376096D02*
X1112023Y378144D01*
G01X1102357Y402643D02*
G02X1102376Y404184I1384J754D01*
G01Y402609D02*
X1102357Y402643D01*
G01X1102401Y402567D02*
X1102376Y402609D01*
G01Y400284D02*
G03X1102401Y402567I-2015J1164D01*
G01X1102357Y398743D02*
G02X1102376Y400284I1384J754D01*
G01Y398709D02*
X1102357Y398743D01*
G01X1102401Y398667D02*
X1102376Y398709D01*
G01Y396384D02*
G03X1102401Y398667I-2015J1164D01*
G01X1102357Y394843D02*
G02X1102376Y396384I1384J754D01*
G01Y394809D02*
X1102357Y394843D01*
G01X1102401Y394767D02*
X1102376Y394809D01*
G01X1102492Y392713D02*
G03X1102401Y394767I-2131J935D01*
G01X1102376Y392485D02*
G03X1102492Y392713I-2117J1221D01*
G01X1102376Y390911D02*
G02Y392485I1365J787D01*
G01Y388585D02*
G03Y390911I-2015J1163D01*
G01Y387011D02*
G02Y388585I1365J787D01*
G01Y384685D02*
G03Y387011I-2015J1163D01*
G01Y383111D02*
G02Y384685I1365J787D01*
G01Y380785D02*
G03Y383111I-2015J1163D01*
G01Y379211D02*
G02Y380785I1365J787D01*
G01X1102623Y378590D02*
G03X1102376Y379211I-2263J-540D01*
G01X1103741Y376096D02*
X1102623Y378590D01*
G01X1136156Y402643D02*
G02X1136175Y404184I1384J754D01*
G01Y402609D02*
X1136156Y402643D01*
G01X1136200Y402567D02*
X1136175Y402609D01*
G01X1134245Y399122D02*
G03X1136200Y402567I-85J2325D01*
G01X1134116Y399122D02*
X1134245D01*
G01X1132795Y396759D02*
G02X1134116Y399122I1365J788D01*
G01X1132820Y394476D02*
G03X1132795Y396759I-2040J1119D01*
G01Y394434D02*
X1132820Y394476D01*
G01X1132776Y394400D02*
X1132795Y394434D01*
G01Y392859D02*
G02X1132776Y394400I1365J787D01*
G01X1132820Y390576D02*
G03X1132795Y392859I-2040J1119D01*
G01Y388959D02*
G02X1132820Y390576I1365J788D01*
G01X1132795Y386633D02*
G03Y388959I-2015J1163D01*
G01Y385059D02*
G02Y386633I1365J787D01*
G01Y382733D02*
G03Y385059I-2015J1163D01*
G01Y381159D02*
G02Y382733I1365J787D01*
G01Y378833D02*
G03Y381159I-2017J1163D01*
G01X1132651Y378498D02*
G02X1132795Y378833I1510J-450D01*
G01X1132501Y377986D02*
G02X1132651Y378498I5621J-1369D01*
G01X1130780Y376096D02*
X1132501Y377986D01*
G01X1099021Y402276D02*
G03X1098996Y404559I-2040J1119D01*
G01Y402234D02*
X1099021Y402276D01*
G01X1098977Y402200D02*
X1098996Y402234D01*
G01Y400659D02*
G02X1098977Y402200I1365J787D01*
G01X1099021Y398376D02*
G03X1098996Y400659I-2040J1119D01*
G01Y398334D02*
X1099021Y398376D01*
G01X1098977Y398300D02*
X1098996Y398334D01*
G01Y396759D02*
G02X1098977Y398300I1365J787D01*
G01X1099021Y394476D02*
G03X1098996Y396759I-2040J1119D01*
G01Y394434D02*
X1099021Y394476D01*
G01X1098977Y394400D02*
X1098996Y394434D01*
G01Y392859D02*
G02X1098977Y394400I1365J787D01*
G01X1099021Y390576D02*
G03X1098996Y392859I-2040J1119D01*
G01Y390535D02*
G02X1099021Y390576I847J-488D01*
G01X1098996Y388961D02*
G02Y390535I1365J787D01*
G01Y386635D02*
G03Y388961I-2015J1163D01*
G01Y385061D02*
G02Y386635I1365J787D01*
G01Y382735D02*
G03Y385061I-2015J1163D01*
G01Y381161D02*
G02Y382735I1365J787D01*
G01Y378835D02*
G03Y381161I-2015J1163D01*
G01Y377261D02*
G02Y378835I1365J787D01*
G01X1099244Y376639D02*
G03X1098996Y377261I-2263J-542D01*
G01X1100361Y374146D02*
X1099244Y376639D01*
G01X1119301Y402276D02*
G03X1119276Y404559I-2040J1119D01*
G01Y402234D02*
X1119301Y402276D01*
G01X1119257Y402200D02*
X1119276Y402234D01*
G01Y400659D02*
G02X1119257Y402200I1365J787D01*
G01X1119301Y398376D02*
G03X1119276Y400659I-2040J1119D01*
G01Y398334D02*
X1119301Y398376D01*
G01X1119257Y398300D02*
X1119276Y398334D01*
G01Y396759D02*
G02X1119257Y398300I1365J787D01*
G01X1119301Y394476D02*
G03X1119276Y396759I-2040J1119D01*
G01Y394434D02*
X1119301Y394476D01*
G01X1119257Y394400D02*
X1119276Y394434D01*
G01Y392859D02*
G02X1119257Y394400I1365J787D01*
G01X1119301Y390576D02*
G03X1119276Y392859I-2040J1119D01*
G01X1119277Y390533D02*
G03X1119301Y390576I-1531J883D01*
G01X1119277Y388959D02*
G02Y390533I1365J787D01*
G01Y386633D02*
G03Y388959I-2015J1163D01*
G01Y385059D02*
G02Y386633I1365J787D01*
G01Y382733D02*
G03Y385059I-2015J1163D01*
G01Y381159D02*
G02Y382733I1365J787D01*
G01Y378833D02*
G03Y381159I-2015J1163D01*
G01Y377259D02*
G02Y378833I1365J787D01*
G01X1119512Y376689D02*
G03X1119277Y377259I-2250J-594D01*
G01X1120641Y374146D02*
X1119512Y376689D01*
G01X1115896Y402608D02*
G02Y404184I1365J788D01*
G01X1115921Y400325D02*
G03X1115896Y402608I-2040J1119D01*
G01Y400283D02*
X1115921Y400325D01*
G01X1115877Y400249D02*
X1115896Y400283D01*
G01Y398708D02*
G02X1115877Y400249I1365J787D01*
G01X1115931Y396442D02*
G03X1115896Y398708I-2050J1102D01*
G01X1115869Y396334D02*
X1115931Y396442D01*
G01X1115896Y394808D02*
G02X1115869Y396334I1365J787D01*
G01X1115921Y392525D02*
G03X1115896Y394808I-2040J1119D01*
G01Y392485D02*
G02X1115921Y392525I574J-331D01*
G01X1115896Y390911D02*
G02Y392485I1365J787D01*
G01Y388585D02*
G03Y390911I-2015J1163D01*
G01Y387011D02*
G02Y388585I1365J787D01*
G01Y384685D02*
G03Y387011I-2015J1163D01*
G01Y383111D02*
G02Y384685I1365J787D01*
G01Y380785D02*
G03Y383111I-2015J1163D01*
G01Y379211D02*
G02Y380785I1365J787D01*
G01Y376885D02*
G03Y379211I-2015J1163D01*
G01X1113881Y374146D02*
G03X1115896Y376885I-11302J10425D01*
G01X1135500Y402276D02*
G02X1135525Y404559I2040J1119D01*
G01Y402234D02*
X1135500Y402276D01*
G01X1135544Y402200D02*
X1135525Y402234D01*
G01X1134219Y399872D02*
G03X1135544Y402200I-59J1575D01*
G01X1134090Y399872D02*
X1134219D01*
G01X1132145Y396384D02*
G02X1134090Y399872I2015J1163D01*
G01X1132164Y394843D02*
G03X1132145Y396384I-1384J754D01*
G01Y394809D02*
X1132164Y394843D01*
G01X1132120Y394767D02*
X1132145Y394809D01*
G01Y392484D02*
G02X1132120Y394767I2015J1164D01*
G01X1132164Y390943D02*
G03X1132145Y392484I-1384J754D01*
G01Y390909D02*
X1132164Y390943D01*
G01X1132145Y388583D02*
G02Y390909I2017J1163D01*
G01Y387009D02*
G03Y388583I-1365J787D01*
G01Y384683D02*
G02Y387009I2015J1163D01*
G01Y383109D02*
G03Y384683I-1365J787D01*
G01Y380783D02*
G02Y383109I2015J1163D01*
G01Y379209D02*
G03Y380783I-1364J787D01*
G01X1131514Y378602D02*
G03X1132145Y379209I-731J1392D01*
G01X1129700Y377243D02*
G02X1131514Y378602I5140J-4970D01*
G01X1129415Y375309D02*
G02X1129700Y377243I1365J787D01*
G01X1129415Y372983D02*
G03Y375309I-2015J1163D01*
G01X1129394Y371447D02*
G02X1129415Y372983I1386J749D01*
G01X1130780Y368296D02*
X1129394Y371447D01*
G01X1096479Y358391D02*
X1095548Y359322D01*
G01X1097842Y358391D02*
X1096479D01*
G01X1099255Y356978D02*
X1097842Y358391D01*
G01X1101290Y356978D02*
X1099255D01*
G01X1102477Y358165D02*
X1101290Y356978D01*
G01X1104812Y358165D02*
X1102477D01*
G01X1105999Y356978D02*
X1104812Y358165D01*
G01X1108210Y356978D02*
X1105999D01*
G01X1109397Y358165D02*
X1108210Y356978D01*
G01X1111717Y358165D02*
X1109397D01*
G01X1112904Y356978D02*
X1111717Y358165D01*
G01X1114860Y356978D02*
X1112904D01*
G01X1116047Y358165D02*
X1114860Y356978D01*
G01X1118176Y358165D02*
X1116047D01*
G01X1119363Y356978D02*
X1118176Y358165D01*
G01X1121637Y356978D02*
X1119363D01*
G01X1122824Y358165D02*
X1121637Y356978D01*
G01X1124932Y358165D02*
X1122824D01*
G01X1126436Y356661D02*
X1124932Y358165D01*
G01X1128271Y356661D02*
X1126436D01*
G01X1129905Y355027D02*
X1128271Y356661D01*
G01X1132131Y355027D02*
X1129905D01*
G01X1134077Y356973D02*
X1132131Y355027D01*
G01X1135691Y356973D02*
X1134077D01*
G01X1136888Y358170D02*
X1135691Y356973D01*
G01X1138317Y358170D02*
X1136888D01*
G01X1140268Y360121D02*
X1138317Y358170D01*
G01X1141231Y360121D02*
X1140268D01*
G01X1143932Y362822D02*
X1141231Y360121D01*
G01X1144945Y362822D02*
X1143932D01*
G01X1146106Y363983D02*
X1144945Y362822D01*
G01X1146106Y366992D02*
Y363983D01*
G01X1147035Y367921D02*
X1146106Y366992D01*
G01X1147573Y367921D02*
X1147035D01*
G01X1149410Y369758D02*
X1147573Y367921D01*
G01X1149410Y370080D02*
Y369758D01*
G01X1103087Y362070D02*
X1103017Y362000D01*
G01X1105270Y362070D02*
X1103087D01*
G01X1105340Y362000D02*
X1105270Y362070D01*
G01X1131508Y358898D02*
X1130080D01*
G01X1133180Y360570D02*
X1131508Y358898D01*
G01X1111885Y402642D02*
G03X1111866Y404183I-1384J754D01*
G01Y402608D02*
X1111885Y402642D01*
G01X1111866Y400282D02*
G02Y402608I2015J1163D01*
G01X1111885Y400248D02*
X1111866Y400282D01*
G01Y398707D02*
G03X1111885Y400248I-1365J787D01*
G01X1111841Y396424D02*
G02X1111866Y398707I2040J1119D01*
G01Y396382D02*
X1111841Y396424D01*
G01X1111866Y394808D02*
G03Y396382I-1365J787D01*
G01X1111753Y394587D02*
G02X1111866Y394808I2249J-1011D01*
G01Y392484D02*
G02X1111753Y394587I2015J1163D01*
G01X1111885Y390943D02*
G03X1111866Y392484I-1384J754D01*
G01Y390909D02*
X1111885Y390943D01*
G01X1111866Y388585D02*
G02Y390909I2015J1162D01*
G01Y387011D02*
G03Y388585I-1365J787D01*
G01Y384685D02*
G02Y387011I2015J1163D01*
G01Y383111D02*
G03Y384685I-1365J787D01*
G01Y380785D02*
G02Y383111I2015J1163D01*
G01Y379211D02*
G03Y380785I-1364J787D01*
G01X1111626Y378880D02*
G03X1111866Y379211I-1465J1315D01*
G01X1110426Y378280D02*
G03X1111626Y378880I-161J1821D01*
G01X1109976Y378130D02*
G02X1110426Y378280I540J-871D01*
G01X1109526Y377530D02*
G02X1109976Y378130I993J-276D01*
G01X1109136Y376884D02*
G02X1109526Y377530I16228J-9356D01*
G01X1109117Y375343D02*
G02X1109136Y376884I1384J754D01*
G01Y375309D02*
X1109117Y375343D01*
G01X1109161Y373026D02*
G03X1109136Y375309I-2040J1119D01*
G01Y372984D02*
X1109161Y373026D01*
G01X1109136Y371410D02*
G02Y372984I1365J787D01*
G01X1109202Y371296D02*
X1109136Y371410D01*
G01X1110501Y368296D02*
X1109202Y371296D01*
G01X1097040Y354271D02*
X1096911D01*
G01X1098346Y353484D02*
G03X1097040Y354271I-1365J-788D01*
G01X1100276Y352322D02*
G02X1098346Y353484I85J2325D01*
G01X1100405Y352322D02*
X1100276D01*
G01X1101726Y351534D02*
G03X1100405Y352322I-1365J-787D01*
G01X1103671Y350371D02*
G02X1101726Y351534I70J2325D01*
G01X1103800Y350371D02*
X1103671D01*
G01X1105106Y349584D02*
G03X1103800Y350371I-1365J-788D01*
G01X1107036Y348422D02*
G02X1105106Y349584I85J2325D01*
G01X1107121Y348422D02*
X1107036D01*
G01X1108472Y347657D02*
G03X1107121Y348422I-1351J-810D01*
G01X1108485Y347634D02*
X1108472Y347657D01*
G01X1110431Y346470D02*
G02X1108485Y347634I70J2325D01*
G01X1110501Y346471D02*
X1110431Y346470D01*
G01X1110560Y346471D02*
X1110501D01*
G01X1111866Y345684D02*
G03X1110560Y346471I-1365J-788D01*
G01X1113796Y344522D02*
G02X1111866Y345684I85J2325D01*
G01X1113881Y344522D02*
X1113796D01*
G01X1115232Y343757D02*
G03X1113881Y344522I-1351J-810D01*
G01X1115245Y343734D02*
X1115232Y343757D01*
G01X1117191Y342570D02*
G02X1115245Y343734I70J2325D01*
G01X1117261Y342571D02*
X1117191Y342570D01*
G01X1117320Y342571D02*
X1117261D01*
G01X1118626Y341784D02*
G03X1117320Y342571I-1365J-788D01*
G01X1135206Y421970D02*
X1136100Y422864D01*
G01X1135206Y420372D02*
Y421970D01*
G01X1132972Y418138D02*
X1135206Y420372D01*
G01X1132798Y417836D02*
X1132972Y418138D01*
G01X1130850Y416671D02*
G03X1132798Y417836I-70J2328D01*
G01X1130721Y416671D02*
X1130850D01*
G01X1129415Y415884D02*
G02X1130721Y416671I1365J-788D01*
G01X1127485Y414722D02*
G03X1129415Y415884I-85J2325D01*
G01X1127400Y414722D02*
X1127485D01*
G01X1126036Y412360D02*
G02X1127400Y414722I1364J787D01*
G01X1126071Y410094D02*
G03X1126036Y412360I-2050J1102D01*
G01Y410034D02*
X1126071Y410094D01*
G01X1126036Y408460D02*
G02Y410034I1364J787D01*
G01X1124091Y404971D02*
G03X1126036Y408460I-69J2325D01*
G01X1123962Y404971D02*
X1124091D01*
G01X1104808Y421056D02*
X1103850Y422014D01*
G01X1104808Y419990D02*
Y421056D01*
G01X1103785Y417421D02*
G03X1104808Y419990I-42J1505D01*
G01X1103656Y417421D02*
X1103785D01*
G01X1101701Y413976D02*
G02X1103656Y417421I2040J1120D01*
G01X1101726Y413934D02*
X1101701Y413976D01*
G01X1101745Y413900D02*
X1101726Y413934D01*
G01Y412359D02*
G03X1101745Y413900I-1365J787D01*
G01X1101701Y410076D02*
G02X1101726Y412359I2040J1119D01*
G01Y410034D02*
X1101701Y410076D01*
G01X1101745Y410000D02*
X1101726Y410034D01*
G01Y408459D02*
G03X1101745Y410000I-1365J787D01*
G01X1101701Y406176D02*
G02X1101726Y408459I2040J1119D01*
G01Y406134D02*
X1101701Y406176D01*
G01X1101745Y406100D02*
X1101726Y406134D01*
G01Y404559D02*
G03X1101745Y406100I-1365J787D01*
G01X1122216Y421248D02*
X1121340Y422124D01*
G01X1122216Y420524D02*
Y421248D01*
G01X1122006Y420159D02*
X1122216Y420524D01*
G01X1120700Y419372D02*
G03X1122006Y420159I-59J1575D01*
G01X1120571Y419372D02*
X1120700D01*
G01X1118626Y418209D02*
G02X1120571Y419372I2015J-1162D01*
G01X1118601Y418167D02*
X1118626Y418209D01*
G01Y415884D02*
G02X1118601Y418167I1858J1162D01*
G01X1118645Y414343D02*
G03X1118626Y415884I-1384J754D01*
G01Y414309D02*
X1118645Y414343D01*
G01X1118601Y414267D02*
X1118626Y414309D01*
G01Y411984D02*
G02X1118601Y414267I2015J1164D01*
G01X1118645Y410443D02*
G03X1118626Y411984I-1384J754D01*
G01Y410409D02*
X1118645Y410443D01*
G01X1117305Y409621D02*
G03X1118626Y410409I-44J1575D01*
G01X1117176Y409621D02*
X1117305D01*
G01X1115246Y408459D02*
G02X1117176Y409621I2015J-1163D01*
G01X1115221Y406176D02*
G02X1115246Y408459I2040J1119D01*
G01Y406134D02*
X1115221Y406176D01*
G01X1115265Y406100D02*
X1115246Y406134D01*
G01Y404559D02*
G03X1115265Y406100I-1365J787D01*
G01X1129356Y421994D02*
X1128640Y422710D01*
G01X1129356Y421185D02*
Y421994D01*
G01X1128765Y420158D02*
X1129356Y421185D01*
G01X1127449Y419371D02*
G03X1128765Y420158I-48J1574D01*
G01X1127401Y419371D02*
X1127449D01*
G01X1127303Y419372D02*
X1127401Y419371D01*
G01X1125385Y418209D02*
G02X1127303Y419372I2016J-1161D01*
G01X1125372Y418186D02*
X1125385Y418209D01*
G01X1124021Y417421D02*
G03X1125372Y418186I0J1575D01*
G01X1123936Y417421D02*
X1124021D01*
G01X1121981Y413976D02*
G02X1123936Y417421I2040J1120D01*
G01X1122006Y413934D02*
X1121981Y413976D01*
G01X1122025Y413900D02*
X1122006Y413934D01*
G01Y412359D02*
G03X1122025Y413900I-1365J787D01*
G01X1121981Y410076D02*
G02X1122006Y412359I2040J1119D01*
G01Y410034D02*
X1121981Y410076D01*
G01X1122025Y410000D02*
X1122006Y410034D01*
G01X1120700Y407672D02*
G03X1122025Y410000I-59J1575D01*
G01X1120571Y407672D02*
X1120700D01*
G01X1118626Y404184D02*
G02X1120571Y407672I2015J1163D01*
G01X1140876Y406922D02*
G03X1139555Y404559I44J-1575D01*
G01X1141005Y406922D02*
X1140876D01*
G01X1142935Y408084D02*
G02X1141005Y406922I-2015J1163D01*
G01X1144241Y408871D02*
G03X1142935Y408084I59J-1575D01*
G01X1144385Y408871D02*
X1144241D01*
G01X1146315Y410033D02*
G02X1144385Y408871I-2015J1163D01*
G01X1147636Y410821D02*
G03X1146315Y410033I44J-1575D01*
G01X1150036Y410821D02*
X1147636D01*
G01X1152006Y412791D02*
X1150036Y410821D01*
G01X1153382Y412791D02*
X1152006D01*
G01X1099556Y421308D02*
X1098740Y422124D01*
G01X1099556Y419141D02*
Y421308D01*
G01X1098035Y417620D02*
X1099556Y419141D01*
G01X1098035Y417047D02*
Y417620D01*
G01X1098346Y415884D02*
G02X1098035Y417047I2015J1162D01*
G01X1098365Y414343D02*
G03X1098346Y415884I-1384J754D01*
G01Y414309D02*
X1098365Y414343D01*
G01X1098321Y414267D02*
X1098346Y414309D01*
G01Y411984D02*
G02X1098321Y414267I2015J1164D01*
G01X1098365Y410443D02*
G03X1098346Y411984I-1384J754D01*
G01Y410409D02*
X1098365Y410443D01*
G01X1098321Y410367D02*
X1098346Y410409D01*
G01Y408084D02*
G02X1098321Y410367I2015J1164D01*
G01X1098365Y406543D02*
G03X1098346Y408084I-1384J754D01*
G01Y406509D02*
X1098365Y406543D01*
G01X1098321Y406467D02*
X1098346Y406509D01*
G01Y404184D02*
G02X1098321Y406467I2015J1164D01*
G01X1151589Y413435D02*
Y414534D01*
G01X1149725Y411571D02*
X1151589Y413435D01*
G01X1147595Y411571D02*
X1149725D01*
G01X1145665Y410409D02*
G02X1147595Y411571I2015J-1163D01*
G01X1144344Y409621D02*
G03X1145665Y410409I-44J1575D01*
G01X1144215Y409621D02*
X1144344D01*
G01X1142285Y408459D02*
G02X1144215Y409621I2015J-1163D01*
G01X1140979Y407672D02*
G03X1142285Y408459I-59J1575D01*
G01X1140850Y407672D02*
X1140979D01*
G01X1138905Y404184D02*
G02X1140850Y407672I2015J1163D01*
G01X1134456Y422289D02*
X1133640Y423105D01*
G01X1134456Y420683D02*
Y422289D01*
G01X1132368Y418595D02*
X1134456Y420683D01*
G01X1132145Y418209D02*
X1132368Y418595D01*
G01X1130824Y417421D02*
G03X1132145Y418209I-44J1575D01*
G01X1130695Y417421D02*
X1130824D01*
G01X1128765Y416259D02*
G02X1130695Y417421I2015J-1163D01*
G01X1127459Y415472D02*
G03X1128765Y416259I-59J1575D01*
G01X1127330Y415472D02*
X1127459D01*
G01X1125385Y411983D02*
G02X1127330Y415472I2015J1163D01*
G01X1125385Y410409D02*
G03Y411983I-1364J787D01*
G01X1125350Y410349D02*
X1125385Y410409D01*
G01Y408083D02*
G02X1125350Y410349I2015J1164D01*
G01X1124021Y405721D02*
G03X1125385Y408083I0J1575D01*
G01X1123936Y405721D02*
X1124021D01*
G01X1117856Y421140D02*
X1118840Y422124D01*
G01X1117856Y420467D02*
Y421140D01*
G01X1116208Y418819D02*
X1117856Y420467D01*
G01X1116208Y417047D02*
Y418819D01*
G01X1115896Y415884D02*
G03X1116208Y417047I-2015J1164D01*
G01X1115877Y414343D02*
G02X1115896Y415884I1384J754D01*
G01Y414309D02*
X1115877Y414343D01*
G01X1115921Y414267D02*
X1115896Y414309D01*
G01X1113966Y410822D02*
G03X1115921Y414267I-85J2325D01*
G01X1113862Y410822D02*
X1113966D01*
G01X1112516Y408459D02*
G02X1113862Y410822I1365J787D01*
G01X1112551Y406193D02*
G03X1112516Y408459I-2050J1102D01*
G01X1112489Y406085D02*
X1112551Y406193D01*
G01X1112516Y404559D02*
G02X1112489Y406085I1365J787D01*
G01X1105756Y421640D02*
X1106240Y422124D01*
G01X1105756Y420159D02*
Y421640D01*
G01X1105781Y417876D02*
G03X1105756Y420159I-2040J1119D01*
G01X1103811Y416671D02*
G03X1105781Y417876I-69J2325D01*
G01X1103682Y416671D02*
X1103811D01*
G01X1102357Y414343D02*
G02X1103682Y416671I1384J753D01*
G01X1102376Y414309D02*
X1102357Y414343D01*
G01X1102401Y414267D02*
X1102376Y414309D01*
G01Y411984D02*
G03X1102401Y414267I-2015J1164D01*
G01X1102357Y410443D02*
G02X1102376Y411984I1384J754D01*
G01Y410409D02*
X1102357Y410443D01*
G01X1102401Y410367D02*
X1102376Y410409D01*
G01Y408084D02*
G03X1102401Y410367I-2015J1164D01*
G01X1102357Y406543D02*
G02X1102376Y408084I1384J754D01*
G01Y406509D02*
X1102357Y406543D01*
G01X1102401Y406467D02*
X1102376Y406509D01*
G01Y404184D02*
G03X1102401Y406467I-2015J1164D01*
G01X1147988Y416002D02*
X1149521D01*
G01X1146851Y414862D02*
X1147988Y416002D01*
G01X1146313Y413935D02*
X1146851Y414862D01*
G01X1146315Y413933D02*
X1146313Y413935D01*
G01X1144385Y412771D02*
G03X1146315Y413933I-85J2325D01*
G01X1144241Y412771D02*
X1144385D01*
G01X1142935Y411984D02*
G02X1144241Y412771I1365J-788D01*
G01X1141005Y410822D02*
G03X1142935Y411984I-85J2325D01*
G01X1140876Y410822D02*
X1141005D01*
G01X1139555Y410034D02*
G02X1140876Y410822I1365J-787D01*
G01X1137610Y408871D02*
G03X1139555Y410034I-70J2325D01*
G01X1137481Y408871D02*
X1137610D01*
G01X1136156Y406543D02*
G02X1137481Y408871I1384J753D01*
G01X1136175Y406509D02*
X1136156Y406543D01*
G01X1136200Y406467D02*
X1136175Y406509D01*
G01Y404184D02*
G03X1136200Y406467I-2015J1164D01*
G01X1100306Y421190D02*
X1101240Y422124D01*
G01X1100306Y418830D02*
Y421190D01*
G01X1098785Y417309D02*
X1100306Y418830D01*
G01X1098785Y417046D02*
Y417309D01*
G01X1098996Y416259D02*
G02X1098785Y417046I1365J788D01*
G01X1099021Y413976D02*
G03X1098996Y416259I-2040J1119D01*
G01Y413934D02*
X1099021Y413976D01*
G01X1098977Y413900D02*
X1098996Y413934D01*
G01Y412359D02*
G02X1098977Y413900I1365J787D01*
G01X1099021Y410076D02*
G03X1098996Y412359I-2040J1119D01*
G01Y410034D02*
X1099021Y410076D01*
G01X1098977Y410000D02*
X1098996Y410034D01*
G01Y408459D02*
G02X1098977Y410000I1365J787D01*
G01X1099021Y406176D02*
G03X1098996Y408459I-2040J1119D01*
G01Y406134D02*
X1099021Y406176D01*
G01X1098977Y406100D02*
X1098996Y406134D01*
G01Y404559D02*
G02X1098977Y406100I1365J787D01*
G01X1130106Y422106D02*
X1131140Y423140D01*
G01X1130106Y420983D02*
Y422106D01*
G01X1129416Y419783D02*
X1130106Y420983D01*
G01X1127498Y418620D02*
G03X1129416Y419783I-98J2324D01*
G01X1127400Y418621D02*
X1127498Y418620D01*
G01X1127352Y418621D02*
X1127400D01*
G01X1126036Y417834D02*
G02X1127352Y418621I1364J-787D01*
G01X1124091Y416671D02*
G03X1126036Y417834I-70J2325D01*
G01X1123962Y416671D02*
X1124091D01*
G01X1122637Y414343D02*
G02X1123962Y416671I1384J753D01*
G01X1122656Y414309D02*
X1122637Y414343D01*
G01X1122681Y414267D02*
X1122656Y414309D01*
G01Y411984D02*
G03X1122681Y414267I-2015J1164D01*
G01X1122637Y410443D02*
G02X1122656Y411984I1384J754D01*
G01Y410409D02*
X1122637Y410443D01*
G01X1122681Y410367D02*
X1122656Y410409D01*
G01X1120726Y406922D02*
G03X1122681Y410367I-85J2325D01*
G01X1120597Y406922D02*
X1120726D01*
G01X1119276Y404559D02*
G02X1120597Y406922I1365J788D01*
G01X1122966Y421250D02*
X1123840Y422124D01*
G01X1122966Y420320D02*
Y421250D01*
G01X1122656Y419784D02*
X1122966Y420320D01*
G01X1120726Y418622D02*
G03X1122656Y419784I-85J2325D01*
G01X1120597Y418622D02*
X1120726D01*
G01X1119276Y417834D02*
G02X1120597Y418622I1365J-787D01*
G01X1119257Y417800D02*
X1119276Y417834D01*
G01Y416259D02*
G02X1119257Y417800I1330J787D01*
G01X1119301Y413976D02*
G03X1119276Y416259I-2040J1119D01*
G01Y413934D02*
X1119301Y413976D01*
G01X1119257Y413900D02*
X1119276Y413934D01*
G01Y412359D02*
G02X1119257Y413900I1365J787D01*
G01X1119301Y410076D02*
G03X1119276Y412359I-2040J1119D01*
G01Y410034D02*
X1119301Y410076D01*
G01X1117331Y408871D02*
G03X1119276Y410034I-70J2325D01*
G01X1117202Y408871D02*
X1117331D01*
G01X1115896Y408084D02*
G02X1117202Y408871I1365J-788D01*
G01X1115877Y406543D02*
G02X1115896Y408084I1384J754D01*
G01Y406509D02*
X1115877Y406543D01*
G01X1115921Y406467D02*
X1115896Y406509D01*
G01Y404184D02*
G03X1115921Y406467I-2015J1164D01*
G01X1147671Y416761D02*
Y417688D01*
G01X1146276Y415366D02*
X1147671Y416761D01*
G01X1146163Y415171D02*
X1146276Y415366D01*
G01X1145665Y414309D02*
X1146163Y415171D01*
G01X1144344Y413521D02*
G03X1145665Y414309I-44J1575D01*
G01X1144215Y413521D02*
X1144344D01*
G01X1142285Y412359D02*
G02X1144215Y413521I2015J-1163D01*
G01X1140979Y411572D02*
G03X1142285Y412359I-59J1575D01*
G01X1140850Y411572D02*
X1140979D01*
G01X1138905Y410409D02*
G02X1140850Y411572I2015J-1162D01*
G01X1137584Y409621D02*
G03X1138905Y410409I-44J1575D01*
G01X1137455Y409621D02*
X1137584D01*
G01X1135500Y406176D02*
G02X1137455Y409621I2040J1120D01*
G01X1135525Y406134D02*
X1135500Y406176D01*
G01X1135544Y406100D02*
X1135525Y406134D01*
G01Y404559D02*
G03X1135544Y406100I-1365J787D01*
G01X1117106Y421358D02*
X1116340Y422124D01*
G01X1117106Y420791D02*
Y421358D01*
G01X1115457Y419142D02*
X1117106Y420791D01*
G01X1115457Y417047D02*
Y419142D01*
G01X1115246Y416259D02*
G03X1115457Y417047I-1365J788D01*
G01X1115221Y413976D02*
G02X1115246Y416259I2040J1119D01*
G01Y413934D02*
X1115221Y413976D01*
G01X1115265Y413900D02*
X1115246Y413934D01*
G01X1113940Y411572D02*
G03X1115265Y413900I-59J1575D01*
G01X1113811Y411572D02*
X1113940D01*
G01X1111866Y408083D02*
G02X1113811Y411572I2015J1163D01*
G01X1111893Y406557D02*
G03X1111866Y408083I-1392J739D01*
G01X1111831Y406449D02*
X1111893Y406557D01*
G01X1111866Y404183D02*
G02X1111831Y406449I2015J1164D01*
G01X1166595Y277433D02*
G03Y279759I-2015J1163D01*
G01Y275859D02*
G02Y277433I1365J787D01*
G01X1166620Y273576D02*
G03X1166595Y275859I-2040J1119D01*
G01Y273534D02*
X1166620Y273576D01*
G01X1166576Y273500D02*
X1166595Y273534D01*
G01Y271959D02*
G02X1166576Y273500I1365J787D01*
G01X1167901Y271172D02*
G02X1166595Y271959I59J1575D01*
G01X1168030Y271172D02*
X1167901D01*
G01X1169975Y270009D02*
G03X1168030Y271172I-2015J-1162D01*
G01X1170452Y269191D02*
X1169975Y270009D01*
G01X1165945Y279384D02*
G02X1165920Y281667I2015J1164D01*
G01X1165964Y277843D02*
G03X1165945Y279384I-1384J754D01*
G01Y277809D02*
X1165964Y277843D01*
G01X1165945Y275483D02*
G02Y277809I2015J1163D01*
G01Y273909D02*
G03Y275483I-1365J787D01*
G01X1165920Y273867D02*
X1165945Y273909D01*
G01Y271584D02*
G02X1165920Y273867I2015J1164D01*
G01X1167875Y270422D02*
G02X1165945Y271584I85J2325D01*
G01X1167960Y270422D02*
X1167875D01*
G01X1169311Y269657D02*
G03X1167960Y270422I-1351J-810D01*
G01X1169324Y269634D02*
X1169311Y269657D01*
G01X1169324Y268060D02*
G03Y269634I-1364J787D01*
G01X1169207Y265962D02*
G02X1169324Y268060I2132J933D01*
G01X1169113Y265612D02*
X1169207Y265962D01*
G01X1167960Y264947D02*
X1169113Y265612D01*
G01X1157905Y316021D02*
X1157776D01*
G01X1159835Y314859D02*
G03X1157905Y316021I-2015J-1163D01*
G01X1159860Y312576D02*
G03X1159835Y314859I-2040J1119D01*
G01Y312534D02*
X1159860Y312576D01*
G01X1159835Y310960D02*
G02Y312534I1365J787D01*
G01Y308634D02*
G03Y310960I-2015J1163D01*
G01X1159816Y308600D02*
X1159835Y308634D01*
G01Y307059D02*
G02X1159816Y308600I1365J787D01*
G01X1161141Y306272D02*
G02X1159835Y307059I59J1575D01*
G01X1161270Y306272D02*
X1161141D01*
G01X1163215Y305109D02*
G03X1161270Y306272I-2015J-1162D01*
G01X1163240Y305067D02*
X1163215Y305109D01*
G01Y302784D02*
G03X1163240Y305067I-2015J1164D01*
G01X1163196Y301243D02*
G02X1163215Y302784I1384J754D01*
G01Y301209D02*
X1163196Y301243D01*
G01X1164536Y300421D02*
G02X1163215Y301209I44J1575D01*
G01X1164665Y300421D02*
X1164536D01*
G01X1166595Y299259D02*
G03X1164665Y300421I-2015J-1163D01*
G01X1166620Y296976D02*
G03X1166595Y299259I-2040J1119D01*
G01Y296934D02*
X1166620Y296976D01*
G01X1166576Y296900D02*
X1166595Y296934D01*
G01Y295359D02*
G02X1166576Y296900I1365J787D01*
G01X1166620Y293076D02*
G03X1166595Y295359I-2040J1119D01*
G01Y293034D02*
X1166620Y293076D01*
G01X1166576Y293000D02*
X1166595Y293034D01*
G01Y291459D02*
G02X1166576Y293000I1365J787D01*
G01X1166620Y289176D02*
G03X1166595Y291459I-2040J1119D01*
G01Y289134D02*
X1166620Y289176D01*
G01X1166576Y289100D02*
X1166595Y289134D01*
G01Y287559D02*
G02X1166576Y289100I1365J787D01*
G01X1166620Y285276D02*
G03X1166595Y287559I-2040J1119D01*
G01Y285234D02*
X1166620Y285276D01*
G01X1166576Y285200D02*
X1166595Y285234D01*
G01Y283659D02*
G02X1166576Y285200I1365J787D01*
G01X1166620Y281376D02*
G03X1166595Y283659I-2040J1119D01*
G01Y281334D02*
X1166620Y281376D01*
G01X1166576Y281300D02*
X1166595Y281334D01*
G01Y279759D02*
G02X1166576Y281300I1365J787D01*
G01X1157879Y315271D02*
X1157750D01*
G01X1159185Y314484D02*
G03X1157879Y315271I-1365J-788D01*
G01X1159204Y312943D02*
G03X1159185Y314484I-1384J754D01*
G01Y312909D02*
X1159204Y312943D01*
G01X1159160Y312867D02*
X1159185Y312909D01*
G01Y310584D02*
G02X1159160Y312867I2015J1164D01*
G01X1159185Y309010D02*
G03Y310584I-1365J787D01*
G01Y306684D02*
G02Y309010I2015J1163D01*
G01X1161115Y305522D02*
G02X1159185Y306684I85J2325D01*
G01X1161244Y305522D02*
X1161115D01*
G01X1162565Y304734D02*
G03X1161244Y305522I-1365J-787D01*
G01X1162584Y304700D02*
X1162565Y304734D01*
G01Y303159D02*
G03X1162584Y304700I-1365J787D01*
G01X1162540Y300876D02*
G02X1162565Y303159I2040J1119D01*
G01Y300834D02*
X1162540Y300876D01*
G01X1164510Y299671D02*
G02X1162565Y300834I70J2325D01*
G01X1164639Y299671D02*
X1164510D01*
G01X1165945Y298884D02*
G03X1164639Y299671I-1365J-788D01*
G01X1165964Y297343D02*
G03X1165945Y298884I-1384J754D01*
G01Y297309D02*
X1165964Y297343D01*
G01X1165920Y297267D02*
X1165945Y297309D01*
G01Y294984D02*
G02X1165920Y297267I2015J1164D01*
G01X1165964Y293443D02*
G03X1165945Y294984I-1384J754D01*
G01Y293409D02*
X1165964Y293443D01*
G01X1165920Y293367D02*
X1165945Y293409D01*
G01Y291084D02*
G02X1165920Y293367I2015J1164D01*
G01X1165964Y289543D02*
G03X1165945Y291084I-1384J754D01*
G01Y289509D02*
X1165964Y289543D01*
G01X1165920Y289467D02*
X1165945Y289509D01*
G01Y287184D02*
G02X1165920Y289467I2015J1164D01*
G01X1165964Y285643D02*
G03X1165945Y287184I-1384J754D01*
G01Y285609D02*
X1165964Y285643D01*
G01X1165920Y285567D02*
X1165945Y285609D01*
G01Y283284D02*
G02X1165920Y285567I2015J1164D01*
G01X1165964Y281743D02*
G03X1165945Y283284I-1384J754D01*
G01Y281709D02*
X1165964Y281743D01*
G01X1165920Y281667D02*
X1165945Y281709D01*
G01X1278900Y-14800D02*
X1273605Y-20095D01*
G01X1325194Y-20617D02*
X1352520Y6709D01*
G01X1301547Y-20617D02*
X1325194D01*
G01X1299549Y-18619D02*
X1301547Y-20617D01*
G01X1402300Y6700D02*
X1411100D01*
G01X1390100Y-5500D02*
X1402300Y6700D01*
G01X1390100Y-7457D02*
Y-5500D01*
G01X1379088Y-18469D02*
X1390100Y-7457D01*
G01X1371249Y-18469D02*
X1379088D01*
G01X1363400Y-10620D02*
X1371249Y-18469D01*
G01X1363400Y1559D02*
Y-10620D01*
G01X1358250Y6709D02*
X1363400Y1559D01*
G01X1352520Y6709D02*
X1358250D01*
G01X1435916Y-600D02*
X1487446D01*
G01X1426657Y8659D02*
X1435916Y-600D01*
G01X1413059Y8659D02*
X1426657D01*
G01X1411100Y6700D02*
X1413059Y8659D01*
G01X1513600Y10400D02*
X1530200D01*
G01X1508507Y5307D02*
X1513600Y10400D01*
G01X1501407Y5307D02*
X1508507D01*
G01X1495325Y-775D02*
X1501407Y5307D01*
G01X1487621Y-775D02*
X1495325D01*
G01X1487446Y-600D02*
X1487621Y-775D01*
G01X1487904Y337536D02*
Y337500D01*
G01X1489760Y339392D02*
X1487904Y337536D01*
G01X1489760Y341557D02*
Y339392D01*
G01X1472118Y313077D02*
X1470649Y314546D01*
G01X1474855Y313077D02*
X1472118D01*
G01X1477793Y316015D02*
X1474855Y313077D01*
G01X1496365Y316015D02*
X1477793D01*
G01X1501050Y311330D02*
X1496365Y316015D01*
G01X1506453Y311330D02*
X1501050D01*
G01X1512417Y305366D02*
X1506453Y311330D01*
G01X1520386Y305366D02*
X1512417D01*
G01X1523616Y308596D02*
X1520386Y305366D01*
G01X1530102Y308596D02*
X1523616D01*
G01X1486092Y345225D02*
X1489760Y341557D01*
G01X1482074Y345225D02*
X1486092D01*
G01X1479149Y348150D02*
X1482074Y345225D01*
G01X1587367Y8527D02*
X1589294Y6600D01*
G01X1577073Y8527D02*
X1587367D01*
G01X1576100Y9500D02*
X1577073Y8527D01*
G01X1531100Y9500D02*
X1576100D01*
G01X1530200Y10400D02*
X1531100Y9500D01*
G01X1531304Y309798D02*
X1530102Y308596D01*
G01X1534833Y309798D02*
X1531304D01*
G01X1541750Y401259D02*
G02X1542695Y403048I2325J-84D01*
G01X1541750Y401130D02*
Y401259D01*
G01X1540962Y399809D02*
G03X1541750Y401130I-787J1365D01*
G01X1539388Y399809D02*
G03X1540962I787J1365D01*
G01X1537062D02*
G02X1539388I1163J-2015D01*
G01X1535488D02*
G03X1537062I787J1365D01*
G01X1533162D02*
G02X1535488I1163J-2015D01*
G01X1531794Y399710D02*
G03X1533162Y399809I582J1464D01*
G01X1531710Y400020D02*
X1531794Y399710D01*
G01X1532375Y401174D02*
X1531710Y400020D01*
G01X1546025Y401985D02*
X1548010Y403970D01*
G01X1543587Y402682D02*
G03X1544450Y404370I-1219J1688D01*
G01X1543100Y402411D02*
G02X1543587Y402682I1090J-1385D01*
G01X1542500Y401218D02*
G02X1543100Y402411I1575J-45D01*
G01X1542500Y401089D02*
Y401218D01*
G01X1541338Y399159D02*
G03X1542500Y401089I-1163J2015D01*
G01X1539012Y399159D02*
G03X1541338I1163J2015D01*
G01X1537438D02*
G02X1539012I787J-1365D01*
G01X1535112D02*
G03X1537438I1163J2015D01*
G01X1533538D02*
G02X1535112I787J-1365D01*
G01X1531442Y399042D02*
G03X1533538Y399159I932J2132D01*
G01X1531090Y398948D02*
X1531442Y399042D01*
G01X1530425Y397794D02*
X1531090Y398948D01*
G01X1565923Y446926D02*
X1565525D01*
G01X1567509Y445340D02*
X1565923Y446926D01*
G01X1571945Y445340D02*
X1567509D01*
G01X1574601Y442684D02*
X1571945Y445340D01*
G01X1574601Y413746D02*
Y442684D01*
G01X1573766Y412911D02*
X1574601Y413746D01*
G01X1564524Y412911D02*
X1573766D01*
G01X1563366Y411753D02*
X1564524Y412911D01*
G01X1563366Y411126D02*
Y411753D01*
G01X1562823Y410186D02*
G03X1563366Y411126I-542J940D01*
G01X1562412Y409949D02*
X1562823Y410186D01*
G01X1560838Y409949D02*
G03X1562412I787J1365D01*
G01X1558512D02*
G02X1560838I1163J-2015D01*
G01X1556938D02*
G03X1558512I787J1365D01*
G01X1554612D02*
G02X1556938I1163J-2015D01*
G01X1553038D02*
G03X1554612I787J1365D01*
G01X1550783Y409988D02*
G02X1553038Y409949I1092J-2054D01*
G01X1550713Y409948D02*
X1550783Y409988D01*
G01X1550351Y409691D02*
G02X1550713Y409948I1521J-1759D01*
G01X1550231Y409579D02*
G02X1550351Y409691I1645J-1642D01*
G01X1548921Y408268D02*
X1550231Y409579D01*
G01X1546300Y408268D02*
X1548921D01*
G01X1543700Y405668D02*
X1546300Y408268D01*
G01X1543700Y404413D02*
Y405668D01*
G01X1543080Y403281D02*
G03X1543700Y404413I-723J1132D01*
G01X1542695Y403048D02*
G02X1543080Y403281I1483J-2016D01*
G01X1571236Y455497D02*
X1569425Y453686D01*
G01X1572025Y455497D02*
X1571236D01*
G01X1575062Y458534D02*
X1572025Y455497D01*
G01X1596272Y458534D02*
X1575062D01*
G01X1572681Y406123D02*
X1574464Y407906D01*
G01X1566939Y406123D02*
X1572681D01*
G01X1566697Y406365D02*
X1566939Y406123D01*
G01X1549606Y406365D02*
X1566697D01*
G01X1548010Y404769D02*
X1549606Y406365D01*
G01X1548010Y403970D02*
Y404769D01*
G01X1578760Y446100D02*
X1582300D01*
G01X1575350Y442690D02*
X1578760Y446100D01*
G01X1575350Y412561D02*
Y442690D01*
G01X1572495Y409706D02*
X1575350Y412561D01*
G01X1566621Y409706D02*
X1572495D01*
G01X1566486Y409571D02*
X1566621Y409706D01*
G01X1563803Y409571D02*
X1566486D01*
G01X1562788Y409299D02*
G02X1563803Y409571I1015J-1759D01*
G01X1560462Y409299D02*
G03X1562788I1163J2015D01*
G01X1558888D02*
G02X1560462I787J-1365D01*
G01X1556562D02*
G03X1558888I1163J2015D01*
G01X1554988D02*
G02X1556562I787J-1365D01*
G01X1552662D02*
G03X1554988I1163J2015D01*
G01X1551133Y409324D02*
G02X1552662Y409299I742J-1390D01*
G01X1551088Y409298D02*
X1551133Y409324D01*
G01X1550761Y409048D02*
G02X1551088Y409298I1112J-1115D01*
G01X1549232Y407519D02*
X1550761Y409048D01*
G01X1546611Y407519D02*
X1549232D01*
G01X1544450Y405358D02*
X1546611Y407519D01*
G01X1544450Y404370D02*
Y405358D01*
G01X1580751Y451961D02*
X1583358Y449354D01*
G01X1561039Y451961D02*
X1580751D01*
G01X1572319Y462749D02*
X1575300Y465730D01*
G01X1568617Y462749D02*
X1572319D01*
G01X1568125Y462257D02*
X1568617Y462749D01*
G01X1564677Y462257D02*
X1568125D01*
G01X1563771Y461351D02*
X1564677Y462257D01*
G01X1563771Y460278D02*
Y461351D01*
G01X1562252Y458759D02*
X1563771Y460278D01*
G01X1561086Y458759D02*
X1562252D01*
G01X1560679Y459166D02*
X1561086Y458759D01*
G01X1564349Y455400D02*
X1559100D01*
G01X1565637Y456688D02*
X1564349Y455400D01*
G01X1565637Y457993D02*
Y456688D01*
G01X1566430Y458786D02*
X1565637Y457993D01*
G01X1569984Y458786D02*
X1566430D01*
G01X1572440Y461242D02*
X1569984Y458786D01*
G01X1553038Y461811D02*
G02X1549925Y460446I-7749J13440D01*
G01X1554612Y461811D02*
G03X1553038I-787J-1365D01*
G01X1556938D02*
G02X1554612I-1163J2015D01*
G01X1558512D02*
G03X1556938I-787J-1365D01*
G01X1560838D02*
G02X1558512I-1163J2015D01*
G01X1561890Y462863D02*
X1560838Y461811D01*
G01X1561890Y464459D02*
Y462863D01*
G01X1562932Y465501D02*
X1561890Y464459D01*
G01X1575300Y465730D02*
X1592769D01*
G01X1570099Y465501D02*
X1562932D01*
G01X1571407Y466809D02*
X1570099Y465501D01*
G01X1579009Y466809D02*
X1571407D01*
G01X1643849Y-3690D02*
X1654285D01*
G01X1637752Y2407D02*
X1643849Y-3690D01*
G01X1605337Y2407D02*
X1637752D01*
G01X1601144Y6600D02*
X1605337Y2407D01*
G01X1589294Y6600D02*
X1601144D01*
G01X1590081Y143030D02*
X1591143Y144092D01*
G01X1612183Y442623D02*
X1596272Y458534D01*
G01X1604600Y437100D02*
X1603000Y435500D01*
G01X1613701Y437100D02*
X1604600D01*
G01X1616200Y439599D02*
X1613701Y437100D01*
G01X1616200Y447500D02*
Y439599D01*
G01X1610619Y453081D02*
X1616200Y447500D01*
G01X1605418Y453081D02*
X1610619D01*
G01X1592769Y465730D02*
X1605418Y453081D01*
G01X1609993Y451500D02*
X1604999D01*
G01X1615033Y446460D02*
X1609993Y451500D01*
G01X1615033Y440204D02*
Y446460D01*
G01X1613220Y438391D02*
X1615033Y440204D01*
G01X1603652Y438391D02*
X1613220D01*
G01X1696138Y9238D02*
X1734875D01*
G01X1694600Y7700D02*
X1696138Y9238D01*
G01X1676800Y7700D02*
X1694600D01*
G01X1672725Y3625D02*
X1676800Y7700D01*
G01X1661600Y3625D02*
X1672725D01*
G01X1654285Y-3690D02*
X1661600Y3625D01*
G01X1693548Y159990D02*
X1695680D01*
G01X1691968Y158410D02*
X1693548Y159990D01*
G01X1685887Y158410D02*
X1691968D01*
G01X1685567Y158730D02*
X1685887Y158410D01*
G01X1825292Y64870D02*
X1820969D01*
G01X1835562Y54600D02*
X1825292Y64870D01*
G01X1824703Y63139D02*
X1834914Y52928D01*
G01X1820708Y63139D02*
X1824703D01*
G01X1825722Y66760D02*
X1834178Y58304D01*
G01X1821071Y66760D02*
X1825722D01*
G54D13*
G01X-19772Y136741D02*
X-15748Y132717D01*
G01X-19772Y158857D02*
Y136741D01*
G01X-16290Y128988D02*
X-8453D01*
G01X-20940Y133638D02*
X-16290Y128988D01*
G01X-20940Y159430D02*
Y133638D01*
G01X-15748Y118752D02*
Y116969D01*
G01X-13018Y121482D02*
X-15748Y118752D01*
G01X-16135Y168687D02*
X-12861Y165413D01*
G01X-16135Y170935D02*
Y168687D01*
G01X-20396Y175196D02*
X-16135Y170935D01*
G01X-20396Y335904D02*
Y175196D01*
G01X-17344Y161285D02*
X-19772Y158857D01*
G01X-17344Y163029D02*
Y161285D01*
G01X-16320Y164053D02*
X-17344Y163029D01*
G01X-14932Y164053D02*
X-16320D01*
G01X-19210Y161160D02*
X-20940Y159430D01*
G01X-19210Y162529D02*
Y161160D01*
G01Y172380D02*
Y162529D01*
G01X-21548Y174718D02*
X-19210Y172380D01*
G01X-21548Y336382D02*
Y174718D01*
G01X-15768Y161922D02*
X-13847D01*
G01X-13800Y342500D02*
X-20396Y335904D01*
G01X-14278Y343652D02*
X-21548Y336382D01*
G01X-16504Y486088D02*
X-6763Y476347D01*
G01X-16504Y494880D02*
Y486088D01*
G01X-14864Y496520D02*
X-16504Y494880D01*
G01X-16766Y500106D02*
X-14864Y498204D01*
G01X-19908Y484678D02*
X-9170Y473940D01*
G01X-19908Y504192D02*
Y484678D01*
G01X-17302Y506798D02*
X-19908Y504192D01*
G01X-18206Y485383D02*
X-7468Y474645D01*
G01X-18206Y495894D02*
Y485383D01*
G01X-16700Y497400D02*
X-18206Y495894D01*
G01X-17200Y510800D02*
X-11415Y505015D01*
G01X45012Y11193D02*
X52596D01*
G01X39559Y16646D02*
X45012Y11193D01*
G01X35624Y16646D02*
X39559D01*
G01X34719Y17551D02*
X35624Y16646D01*
G01X34719Y19455D02*
Y17551D01*
G01X40700Y94400D02*
Y116000D01*
G01X46400Y88700D02*
X40700Y94400D01*
G01X39500Y93900D02*
Y108521D01*
G01X45800Y87600D02*
X39500Y93900D01*
G01X45870Y87600D02*
X45800D01*
G01X45922Y87548D02*
X45870Y87600D01*
G01X56665Y87548D02*
X45922D01*
G01X38300Y93400D02*
Y107900D01*
G01X45100Y86600D02*
X38300Y93400D01*
G01X45523Y86600D02*
X45100D01*
G01X45527Y86596D02*
X45523Y86600D01*
G01X56270Y86596D02*
X45527D01*
G01X-4725Y132716D02*
Y132717D01*
G01X-8453Y128988D02*
X-4725Y132716D01*
G01X35218Y121482D02*
X-13018D01*
G01X40700Y116000D02*
X35218Y121482D01*
G01X36383Y139079D02*
X37037Y138425D01*
G01X36383Y143483D02*
Y139079D01*
G01X40830Y147930D02*
X36383Y143483D01*
G01X40830Y152559D02*
Y147930D01*
G01X47029Y158758D02*
X40830Y152559D01*
G01X41542Y154901D02*
X39109D01*
G01X47855Y161214D02*
X41542Y154901D01*
G01X-7205Y120000D02*
X-10236Y116969D01*
G01X-4000Y120000D02*
X-7205D01*
G01X-2000Y118000D02*
X-4000Y120000D01*
G01X-2000Y116000D02*
Y118000D01*
G01X0Y114000D02*
X-2000Y116000D01*
G01X34021Y114000D02*
X0D01*
G01X39500Y108521D02*
X34021Y114000D01*
G01X-788Y113032D02*
X-4725Y116969D01*
G01X33168Y113032D02*
X-788D01*
G01X38300Y107900D02*
X33168Y113032D01*
G01X-12861Y165413D02*
Y163165D01*
G01X-14044D02*
X-14932Y164053D01*
G01X-12861Y163165D02*
X-14044D01*
G01X45083Y195401D02*
Y266311D01*
G01X53469Y187015D02*
X45083Y195401D01*
G01X-11384Y162413D02*
X50716D01*
G01X-12208Y161589D02*
X-11384Y162413D01*
G01X-13514Y161589D02*
X-12208D01*
G01X-13847Y161922D02*
X-13514Y161589D01*
G01X45083Y266311D02*
X47528Y268756D01*
G01X45248Y311725D02*
Y342740D01*
G01X45753Y311220D02*
X45248Y311725D01*
G01X45753Y281788D02*
Y311220D01*
G01X47528Y280013D02*
X45753Y281788D01*
G01X2400Y342500D02*
X-13800D01*
G01X6400Y346500D02*
X2400Y342500D01*
G01X38600Y346500D02*
X6400D01*
G01X41109Y349009D02*
X38600Y346500D01*
G01X49117Y349009D02*
X41109D01*
G01X1922Y343652D02*
X-14278D01*
G01X5922Y347652D02*
X1922Y343652D01*
G01X37752Y347652D02*
X5922D01*
G01X41609Y351509D02*
X37752Y347652D01*
G01X49091Y351509D02*
X41609D01*
G01X45248Y342740D02*
X49017Y346509D01*
G01X11589Y449260D02*
X64123D01*
G01X2712Y458137D02*
X11589Y449260D01*
G01X-413Y458137D02*
X2712D01*
G01X-4806Y453744D02*
X-413Y458137D01*
G01X-4806Y444777D02*
Y453744D01*
G01X-14488Y435095D02*
X-4806Y444777D01*
G01X-14488Y434094D02*
Y435095D01*
G01X24203Y477104D02*
X61558D01*
G01X19145Y482162D02*
X24203Y477104D01*
G01X12745Y482162D02*
X19145D01*
G01X12744Y482163D02*
X12745Y482162D01*
G01X11336Y482163D02*
X12744D01*
G01X11335Y482162D02*
X11336Y482163D01*
G01X11334Y482162D02*
X11335D01*
G01X10338Y481166D02*
X11334Y482162D01*
G01X10338Y481165D02*
Y481166D01*
G01X5520Y476347D02*
X10338Y481165D01*
G01X-6763Y476347D02*
X5520D01*
G01X-14864Y498204D02*
Y496520D01*
G01X25227Y473700D02*
X60148D01*
G01X25226Y473699D02*
X25227Y473700D01*
G01X22794Y473699D02*
X25226D01*
G01X17735Y478758D02*
X22794Y473699D01*
G01X12745Y478758D02*
X17735D01*
G01X6930Y472943D02*
X12745Y478758D01*
G01X-8174Y472943D02*
X6930D01*
G01X-9170Y473939D02*
X-8174Y472943D01*
G01X-9170Y473940D02*
Y473939D01*
G01X24521Y475402D02*
X60853D01*
G01X24520Y475401D02*
X24521Y475402D01*
G01X23499Y475401D02*
X24520D01*
G01X18440Y480460D02*
X23499Y475401D01*
G01X12040Y480460D02*
X18440D01*
G01X6225Y474645D02*
X12040Y480460D01*
G01X-7468Y474645D02*
X6225D01*
G01X31947Y487600D02*
X47800D01*
G01X28898Y490649D02*
X31947Y487600D01*
G01X15219Y490649D02*
X28898D01*
G01X13430Y492438D02*
X15219Y490649D01*
G01X230Y492438D02*
X13430D01*
G01X-3456Y496124D02*
X230Y492438D01*
G01X-7515Y496124D02*
X-3456D01*
G01X-11415Y500024D02*
X-7515Y496124D01*
G01X-11415Y505015D02*
Y500024D01*
G01X84450Y-56200D02*
X80500Y-52250D01*
G01X145030Y-56200D02*
X84450D01*
G01X82100Y-16400D02*
X82300Y-16600D01*
G01X81800Y-16400D02*
X82100D01*
G01X76508Y-11108D02*
X81800Y-16400D01*
G01X66935Y-11108D02*
X76508D01*
G01X57252Y-1425D02*
X66935Y-11108D01*
G01X57252Y6537D02*
Y-1425D01*
G01X52596Y11193D02*
X57252Y6537D01*
G01X107445Y-12815D02*
X113034Y-18404D01*
G01X107445Y-595D02*
Y-12815D01*
G01X103077Y3773D02*
X107445Y-595D01*
G01X103077Y3823D02*
Y3773D01*
G01X102000Y4900D02*
X103077Y3823D01*
G01X102000Y71671D02*
Y4900D01*
G01X87900Y5243D02*
Y84189D01*
G01X90522Y2621D02*
X87900Y5243D01*
G01X102599Y2621D02*
X90522D01*
G01X106293Y-1073D02*
X102599Y2621D01*
G01X106293Y-13293D02*
Y-1073D01*
G01X112556Y-19556D02*
X106293Y-13293D01*
G01X104229Y4251D02*
X108597Y-117D01*
G01X104229Y92007D02*
Y4251D01*
G01X54307Y-9739D02*
Y-8051D01*
G01X61281Y-16713D02*
X54307Y-9739D01*
G01X66153Y-16713D02*
X61281D01*
G01X70500Y-21060D02*
X66153Y-16713D01*
G01X405124Y-21060D02*
X70500D01*
G01X104500Y-12950D02*
Y-1850D01*
G01X111858Y-20308D02*
X104500Y-12950D01*
G01X106972Y78753D02*
X114896Y86677D01*
G01X106972Y64399D02*
Y78753D01*
G01X109152Y62219D02*
X106972Y64399D01*
G01X105820Y63181D02*
X108000Y61001D01*
G01X105820Y79231D02*
Y63181D01*
G01X113744Y87155D02*
X105820Y79231D01*
G01X100300Y73371D02*
X102000Y71671D01*
G01X100300Y76114D02*
Y73371D01*
G01X102661Y78475D02*
X100300Y76114D01*
G01X102661Y92191D02*
Y78475D01*
G01X110400Y99930D02*
X102661Y92191D01*
G01X87900Y84189D02*
X82046Y90043D01*
G01X57143Y88700D02*
X46400D01*
G01X59900Y85943D02*
X57143Y88700D01*
G01X75339Y85943D02*
X59900D01*
G01X77978Y88582D02*
X75339Y85943D01*
G01X77978Y97338D02*
Y88582D01*
G01X111552Y99330D02*
X104229Y92007D01*
G01X59422Y84791D02*
X56665Y87548D01*
G01X75817Y84791D02*
X59422D01*
G01X79130Y88104D02*
X75817Y84791D01*
G01X79130Y96860D02*
Y88104D01*
G01X59027Y83839D02*
X56270Y86596D01*
G01X76212Y83839D02*
X59027D01*
G01X80082Y87709D02*
X76212Y83839D01*
G01X80082Y87942D02*
Y87709D01*
G01X80083Y87943D02*
X80082Y87942D01*
G01X80083Y96183D02*
Y87943D01*
G01X92344Y155455D02*
X93488Y156599D01*
G01X84957Y155455D02*
X92344D01*
G01X82905Y153403D02*
X84957Y155455D01*
G01X82905Y140125D02*
Y153403D01*
G01X97657Y125373D02*
X82905Y140125D01*
G01X103687Y125373D02*
X97657D01*
G01X114896Y114164D02*
X103687Y125373D01*
G01X102835Y124194D02*
X113744Y113285D01*
G01X96248Y124194D02*
X102835D01*
G01X76424Y144018D02*
X96248Y124194D01*
G01X76424Y147182D02*
Y144018D01*
G01X78762Y149520D02*
X76424Y147182D01*
G01X79519Y149520D02*
X78762D01*
G01X81678Y151679D02*
X79519Y149520D01*
G01X81678Y156222D02*
Y151679D01*
G01X101734Y131300D02*
X117200Y115834D01*
G01X95500Y131300D02*
X101734D01*
G01X85638Y141162D02*
X95500Y131300D01*
G01X85638Y150812D02*
Y141162D01*
G01X87200Y152374D02*
X85638Y150812D01*
G01X103565Y140835D02*
X118352Y126048D01*
G01X94676Y140835D02*
X103565D01*
G01X89980Y145531D02*
X94676Y140835D01*
G01X106720Y109480D02*
X110400Y105800D01*
G01X105777Y109480D02*
X106720D01*
G01X104424Y110833D02*
X105777Y109480D01*
G01X82940Y102300D02*
X77978Y97338D01*
G01X89785Y102300D02*
X82940D01*
G01X92485Y105000D02*
X89785Y102300D01*
G01X100783Y123037D02*
X111552Y112268D01*
G01X95775Y123037D02*
X100783D01*
G01X75272Y143540D02*
X95775Y123037D01*
G01X75272Y147660D02*
Y143540D01*
G01X78462Y150850D02*
X75272Y147660D01*
G01X79219Y150850D02*
X78462D01*
G01X80526Y152157D02*
X79219Y150850D01*
G01X80526Y193326D02*
Y152157D01*
G01X94640Y155157D02*
Y177383D01*
G01X93550Y154067D02*
X94640Y155157D01*
G01X85487Y154067D02*
X93550D01*
G01X84250Y152830D02*
X85487Y154067D01*
G01X84250Y140410D02*
Y152830D01*
G01X94610Y130050D02*
X84250Y140410D01*
G01X100832Y130050D02*
X94610D01*
G01X116048Y114834D02*
X100832Y130050D01*
G01X77711Y154049D02*
X78950Y152810D01*
G01X74973Y154049D02*
X77711D01*
G01X72624Y151700D02*
X74973Y154049D01*
G01X72624Y121529D02*
Y151700D01*
G01X79306Y114847D02*
X72624Y121529D01*
G01X80094Y114847D02*
X79306D01*
G01X80095Y114848D02*
X80094Y114847D01*
G01X91152Y114848D02*
X80095D01*
G01X97406Y108594D02*
X91152Y114848D01*
G01X97406Y105000D02*
Y108594D01*
G01X83222Y100952D02*
X79130Y96860D01*
G01X95952Y100952D02*
X83222D01*
G01X97406Y102406D02*
X95952Y100952D01*
G01X97406Y105000D02*
Y102406D01*
G01X102328Y105182D02*
Y105000D01*
G01X91710Y115800D02*
X102328Y105182D01*
G01X79700Y115800D02*
X91710D01*
G01X73576Y121924D02*
X79700Y115800D01*
G01X73576Y150296D02*
Y121924D01*
G01X75660Y152380D02*
X73576Y150296D01*
G01X83700Y99800D02*
X80083Y96183D01*
G01X97200Y99800D02*
X83700D01*
G01X102328Y104928D02*
X97200Y99800D01*
G01X102328Y105000D02*
Y104928D01*
G01X93488Y175185D02*
X86952Y181721D01*
G01X93488Y156599D02*
Y175185D01*
G01X81708Y156252D02*
X81678Y156222D01*
G01X81708Y192878D02*
Y156252D01*
G01X88300Y199470D02*
X81708Y192878D01*
G01X88300Y205570D02*
Y199470D01*
G01X102752Y220022D02*
X88300Y205570D01*
G01X53469Y165166D02*
Y187015D01*
G01X50716Y162413D02*
X53469Y165166D01*
G01X86900Y199700D02*
X80526Y193326D01*
G01X86900Y205800D02*
Y199700D01*
G01X101600Y220500D02*
X86900Y205800D01*
G01X84824Y163676D02*
X91306Y157194D01*
G01X84824Y191124D02*
Y163676D01*
G01X89515Y195815D02*
X84824Y191124D01*
G01X89515Y204815D02*
Y195815D01*
G01X103504Y218804D02*
X89515Y204815D01*
G01X52367Y158758D02*
X47029D01*
G01X56139Y162530D02*
X52367Y158758D01*
G01X56139Y164576D02*
Y162530D01*
G01X55773Y164942D02*
X56139Y164576D01*
G01X55773Y188041D02*
Y164942D01*
G01X47387Y196427D02*
X55773Y188041D01*
G01X47387Y265355D02*
Y196427D01*
G01X94640Y177383D02*
X87151Y184872D01*
G01X51626Y161214D02*
X47855D01*
G01X54621Y164209D02*
X51626Y161214D01*
G01X54621Y187563D02*
Y164209D01*
G01X46235Y195949D02*
X54621Y187563D01*
G01X46235Y265833D02*
Y195949D01*
G01X102752Y261748D02*
Y220022D01*
G01X86700Y277800D02*
X102752Y261748D01*
G01X86700Y284573D02*
Y277800D01*
G01X47528Y268756D02*
Y280013D01*
G01X101600Y261100D02*
Y220500D01*
G01X100400Y262300D02*
X101600Y261100D01*
G01X97671Y262300D02*
X100400D01*
G01X85300Y274671D02*
X97671Y262300D01*
G01X85300Y284803D02*
Y274671D01*
G01X103504Y262626D02*
Y218804D01*
G01X87852Y278278D02*
X103504Y262626D01*
G01X87852Y284095D02*
Y278278D01*
G01X51400Y269368D02*
X47387Y265355D01*
G01X51400Y308833D02*
Y269368D01*
G01X48680Y268278D02*
X46235Y265833D01*
G01X48680Y280491D02*
Y268278D01*
G01X87628Y285501D02*
X86700Y284573D01*
G01X87628Y300143D02*
Y285501D01*
G01X81118Y306653D02*
X87628Y300143D01*
G01X64127Y306653D02*
X81118D01*
G01X61400Y309380D02*
X64127Y306653D01*
G01X61400Y320200D02*
Y309380D01*
G01X62900Y321700D02*
X61400Y320200D01*
G01X62900Y339000D02*
Y321700D01*
G01X86476Y285979D02*
X85300Y284803D01*
G01X86476Y299665D02*
Y285979D01*
G01X80641Y305500D02*
X86476Y299665D01*
G01X62429Y305500D02*
X80641D01*
G01X56529Y311400D02*
X62429Y305500D01*
G01X54300Y311400D02*
X56529D01*
G01X51500Y314200D02*
X54300Y311400D01*
G01X51500Y316160D02*
Y314200D01*
G01X57876Y322536D02*
X51500Y316160D01*
G01X57876Y361614D02*
Y322536D01*
G01X91285Y287528D02*
X87852Y284095D01*
G01X91285Y298266D02*
Y287528D01*
G01X93373Y300354D02*
X91285Y298266D01*
G01X93373Y304223D02*
Y300354D01*
G01X89296Y308300D02*
X93373Y304223D01*
G01X77744Y308300D02*
X89296D01*
G01X75626Y310418D02*
X77744Y308300D01*
G01X47649Y312584D02*
X51400Y308833D01*
G01X47649Y319419D02*
Y312584D01*
G01X50900Y322670D02*
X47649Y319419D01*
G01X50900Y329060D02*
Y322670D01*
G01X47624Y332336D02*
X50900Y329060D01*
G01X47624Y341303D02*
Y332336D01*
G01X48547Y342226D02*
X47624Y341303D01*
G01X46905Y282266D02*
X48680Y280491D01*
G01X46905Y311698D02*
Y282266D01*
G01X46497Y312106D02*
X46905Y311698D01*
G01X46497Y319897D02*
Y312106D01*
G01X49748Y323148D02*
X46497Y319897D01*
G01X49748Y328582D02*
Y323148D01*
G01X46400Y331930D02*
X49748Y328582D01*
G01X46400Y341800D02*
Y331930D01*
G01X53800Y365690D02*
X57876Y361614D01*
G01X53800Y373812D02*
Y365690D01*
G01X54995Y376695D02*
X53800Y373812D01*
G01X56500Y378200D02*
X54995Y376695D01*
G01X64200Y378200D02*
X56500D01*
G01X69467Y372933D02*
X64200Y378200D01*
G01X81143Y372933D02*
X69467D01*
G01X83130Y374920D02*
X81143Y372933D01*
G01X83130Y392630D02*
Y374920D01*
G01X86200Y395700D02*
X83130Y392630D01*
G01X86200Y427183D02*
Y395700D01*
G01X49864Y342226D02*
X48547D01*
G01X51923Y344285D02*
X49864Y342226D01*
G01X51923Y346164D02*
Y344285D01*
G01X48609Y344009D02*
X46400Y341800D01*
G01X49017Y344009D02*
X48609D01*
G01X98963Y472337D02*
X134630Y436670D01*
G01X97553Y468933D02*
X133926Y432560D01*
G01X98258Y470635D02*
X134213Y434680D01*
G01X64123Y449260D02*
X86200Y427183D01*
G01X65450Y477250D02*
Y475610D01*
G01X63751Y478949D02*
X65450Y477250D01*
G01X63751Y481651D02*
Y478949D01*
G01X66369Y484269D02*
X63751Y481651D01*
G01X91259Y484269D02*
X66369D01*
G01X102441Y495451D02*
X91259Y484269D01*
G01X102441Y607461D02*
Y495451D01*
G01X71400Y472337D02*
X98963D01*
G01X69729Y474008D02*
X71400Y472337D01*
G01X64654Y474008D02*
X69729D01*
G01X61558Y477104D02*
X64654Y474008D01*
G01X69989Y468933D02*
X97553D01*
G01X68318Y470604D02*
X69989Y468933D01*
G01X63244Y470604D02*
X68318D01*
G01X60148Y473700D02*
X63244Y470604D01*
G01X70694Y470635D02*
X98258D01*
G01X70020Y471309D02*
X70694Y470635D01*
G01X70020Y471310D02*
Y471309D01*
G01X69024Y472306D02*
X70020Y471310D01*
G01X63949Y472306D02*
X69024D01*
G01X60853Y475402D02*
X63949Y472306D01*
G01X103480Y495020D02*
Y607030D01*
G01X91690Y483230D02*
X103480Y495020D01*
G01X66800Y483230D02*
X91690D01*
G01X64790Y481220D02*
X66800Y483230D01*
G01X64790Y479380D02*
Y481220D01*
G01X66230Y477940D02*
X64790Y479380D01*
G01X67477Y477940D02*
X66230D01*
G01X114929Y619949D02*
X102441Y607461D01*
G01X103480Y607030D02*
X115360Y618910D01*
G01X147382Y-53848D02*
X145030Y-56200D01*
G01X445509Y-53848D02*
X147382D01*
G01X148901Y-50496D02*
X445509D01*
G01X109152Y2588D02*
Y62219D01*
G01X110901Y839D02*
X109152Y2588D01*
G01X110901Y-11381D02*
Y839D01*
G01X114468Y-14948D02*
X110901Y-11381D01*
G01X402588Y-14948D02*
X114468D01*
G01X113990Y-16100D02*
X403066D01*
G01X109749Y-11859D02*
X113990Y-16100D01*
G01X109749Y361D02*
Y-11859D01*
G01X108000Y2110D02*
X109749Y361D01*
G01X108000Y61001D02*
Y2110D01*
G01X111456Y6044D02*
X114000Y3500D01*
G01X111456Y64144D02*
Y6044D01*
G01X117800Y9820D02*
X114100Y6120D01*
G01X117800Y59570D02*
Y9820D01*
G01X113034Y-18404D02*
X404022D01*
G01X404500Y-19556D02*
X112556D01*
G01X113512Y-17252D02*
X403544D01*
G01X108597Y-12337D02*
X113512Y-17252D01*
G01X108597Y-117D02*
Y-12337D01*
G01X110304Y3066D02*
Y62697D01*
G01X112053Y1317D02*
X110304Y3066D01*
G01X112053Y-10903D02*
Y1317D01*
G01X114946Y-13796D02*
X112053Y-10903D01*
G01X402110Y-13796D02*
X114946D01*
G01X404812Y-20308D02*
X111858D01*
G01X114896Y86677D02*
Y114164D01*
G01X113744Y113285D02*
Y87155D01*
G01X109276Y66324D02*
X111456Y64144D01*
G01X109276Y77797D02*
Y66324D01*
G01X117200Y85721D02*
X109276Y77797D01*
G01X117200Y115834D02*
Y85721D01*
G01X110428Y66942D02*
X117800Y59570D01*
G01X110428Y77319D02*
Y66942D01*
G01X118352Y85243D02*
X110428Y77319D01*
G01X118352Y126048D02*
Y85243D01*
G01X116048Y86199D02*
Y114834D01*
G01X108124Y78275D02*
X116048Y86199D01*
G01X108124Y64877D02*
Y78275D01*
G01X110304Y62697D02*
X108124Y64877D01*
G01X110400Y105800D02*
Y99930D01*
G01X111552Y112268D02*
Y99330D01*
G01X163233Y400655D02*
X170407Y393481D01*
G01X150956Y400655D02*
X163233D01*
G01X142243Y409368D02*
X150956Y400655D01*
G01X163261Y401807D02*
X170713Y394355D01*
G01X151434Y401807D02*
X163261D01*
G01X143121Y410120D02*
X151434Y401807D01*
G01X148409Y425861D02*
Y422239D01*
G01X137600Y436670D02*
X148409Y425861D01*
G01X134630Y436670D02*
X137600D01*
G01X126368Y409368D02*
X142243D01*
G01X123308Y412428D02*
X126368Y409368D01*
G01X123308Y418133D02*
Y412428D01*
G01X122242Y419199D02*
X123308Y418133D01*
G01X144545Y418355D02*
X148300Y414600D01*
G01X144545Y424911D02*
Y418355D01*
G01X136896Y432560D02*
X144545Y424911D01*
G01X133926Y432560D02*
X136896D01*
G01X148136Y417397D02*
X148666D01*
G01X146406Y419127D02*
X148136Y417397D01*
G01X146406Y425457D02*
Y419127D01*
G01X137183Y434680D02*
X146406Y425457D01*
G01X134213Y434680D02*
X137183D01*
G01X126680Y410120D02*
X143121D01*
G01X124082Y412718D02*
X126680Y410120D01*
G01X124082Y421154D02*
Y412718D01*
G01X123441Y421795D02*
X124082Y421154D01*
G01X342305Y619949D02*
X114929D01*
G01X115360Y618910D02*
X342280D01*
G01X198804Y359167D02*
X245991Y311980D01*
G01X200168Y359852D02*
X246969Y312961D01*
G01X198804Y360930D02*
Y359167D01*
G01X193300Y366434D02*
X198804Y360930D01*
G01X193300Y371975D02*
Y366434D01*
G01X178248Y387027D02*
X193300Y371975D01*
G01X178248Y388181D02*
Y387027D01*
G01X172948Y393481D02*
X178248Y388181D01*
G01X170407Y393481D02*
X172948D01*
G01X200168Y361460D02*
Y359852D01*
G01X194498Y367130D02*
X200168Y361460D01*
G01X194498Y372255D02*
Y367130D01*
G01X179220Y387533D02*
X194498Y372255D01*
G01X179220Y389033D02*
Y387533D01*
G01X173898Y394355D02*
X179220Y389033D01*
G01X170713Y394355D02*
X173898D01*
G01X245991Y311980D02*
X257793Y308818D01*
G01X246969Y312961D02*
X258103Y309978D01*
G01X307675Y95756D02*
Y92657D01*
G01X311892Y99973D02*
X307675Y95756D01*
G01X311892Y109028D02*
Y99973D01*
G01X337092Y134228D02*
X311892Y109028D01*
G01X337092Y181501D02*
Y134228D01*
G01X335892Y182701D02*
X337092Y181501D01*
G01X335892Y197600D02*
Y182701D01*
G01X336242Y197950D02*
X335892Y197600D01*
G01X336242Y200350D02*
Y197950D01*
G01X335892Y200700D02*
X336242Y200350D01*
G01X335892Y214200D02*
Y200700D01*
G01X333792Y216300D02*
X335892Y214200D01*
G01X333792Y221400D02*
Y216300D01*
G01X335392Y223000D02*
X333792Y221400D01*
G01X336392Y223000D02*
X335392D01*
G01X338838Y225446D02*
X336392Y223000D01*
G01X338838Y230560D02*
Y225446D01*
G01X345095Y617159D02*
X342305Y619949D01*
G01X449969Y617159D02*
X345095D01*
G01X344783Y616407D02*
X450687D01*
G01X342280Y618910D02*
X344783Y616407D01*
G01X404779Y-12757D02*
X402588Y-14948D01*
G01X458913Y-12757D02*
X404779D01*
G01X405257Y-13909D02*
X458435D01*
G01X403066Y-16100D02*
X405257Y-13909D01*
G01X406213Y-16213D02*
X457479D01*
G01X404022Y-18404D02*
X406213Y-16213D01*
G01X406691Y-17365D02*
X404500Y-19556D01*
G01X457001Y-17365D02*
X406691D01*
G01X405735Y-15061D02*
X457957D01*
G01X403544Y-17252D02*
X405735Y-15061D01*
G01X407315Y-18869D02*
X405124Y-21060D01*
G01X455969Y-18869D02*
X407315D01*
G01X404301Y-11605D02*
X402110Y-13796D01*
G01X409895Y-11605D02*
X404301D01*
G01X409900Y-11600D02*
X409895Y-11605D01*
G01X459780Y-11600D02*
X409900D01*
G01X407003Y-18117D02*
X404812Y-20308D01*
G01X456281Y-18117D02*
X407003D01*
G01X408958Y356972D02*
X418773D01*
G01X405395Y353409D02*
X408958Y356972D01*
G01X403056Y353409D02*
X405395D01*
G01X411431Y359351D02*
X417451D01*
G01X411086Y355360D02*
X420688D01*
G01X445509Y-50496D02*
G02Y-53848I0J-1676D01*
G01X461544Y-15388D02*
X458913Y-12757D01*
G01X645941Y-15388D02*
X461544D01*
G01X461066Y-16540D02*
X646419D01*
G01X458435Y-13909D02*
X461066Y-16540D01*
G01X460110Y-18844D02*
X647375D01*
G01X457479Y-16213D02*
X460110Y-18844D01*
G01X459632Y-19996D02*
X457001Y-17365D01*
G01X649426Y-19996D02*
X459632D01*
G01X460588Y-17692D02*
X646897D01*
G01X457957Y-15061D02*
X460588Y-17692D01*
G01X458600Y-21500D02*
X455969Y-18869D01*
G01X651499Y-21500D02*
X458600D01*
G01X462416Y-14236D02*
X459780Y-11600D01*
G01X617064Y-14236D02*
X462416D01*
G01X458912Y-20748D02*
X456281Y-18117D01*
G01X650779Y-20748D02*
X458912D01*
G01X477040Y261260D02*
X478840Y259460D01*
G01X475470Y261260D02*
X477040D01*
G01X474050Y262680D02*
X475470Y261260D01*
G01X472320Y262680D02*
X474050D01*
G01X470930Y261290D02*
X472320Y262680D01*
G01X468900Y261290D02*
X470930D01*
G01X466990Y263200D02*
X468900Y261290D01*
G01X465630Y263200D02*
X466990D01*
G01X463883Y264947D02*
X465630Y263200D01*
G01X459773Y264947D02*
X463883D01*
G01X451514Y293686D02*
X453400D01*
G01X445100Y300100D02*
X451514Y293686D01*
G01X445100Y313400D02*
Y300100D01*
G01X468400Y336700D02*
X445100Y313400D01*
G01X471546Y336700D02*
X468400D01*
G01X474267Y339421D02*
X471546Y336700D01*
G01X425008Y360991D02*
X425508Y361491D01*
G01X422462Y360661D02*
X424678D01*
G01X418773Y356972D02*
X422462Y360661D01*
G01X472700Y348514D02*
X471033Y346847D01*
G01X472700Y353204D02*
Y348514D01*
G01X474096Y354600D02*
X472700Y353204D01*
G01X474900Y354600D02*
X474096D01*
G01X477000Y356700D02*
X474900Y354600D01*
G01X478700Y356700D02*
X477000D01*
G01X422200Y364100D02*
X424599D01*
G01X417451Y359351D02*
X422200Y364100D01*
G01X424659Y356972D02*
X425594Y357907D01*
G01X422300Y356972D02*
X424659D01*
G01X420688Y355360D02*
X422300Y356972D01*
G01X454320Y621510D02*
X449969Y617159D01*
G01X454320Y622250D02*
Y621510D01*
G01X453250Y623320D02*
X454320Y622250D01*
G01X455180Y621590D02*
X456910Y623320D01*
G01X455180Y620900D02*
Y621590D01*
G01X450687Y616407D02*
X455180Y620900D01*
G01X519900Y202400D02*
X595944Y126356D01*
G01X508600Y202400D02*
X519900D01*
G01X498900Y212100D02*
X508600Y202400D01*
G01X497500Y212100D02*
X498900D01*
G01X495200Y214400D02*
X497500Y212100D01*
G01X493600Y214400D02*
X495200D01*
G01X489300Y218700D02*
X493600Y214400D01*
G01X501452Y262098D02*
Y262996D01*
G01X504188Y259362D02*
X501452Y262098D01*
G01X505862Y259362D02*
X504188D01*
G01X509200Y262700D02*
X505862Y259362D01*
G01X514900Y262700D02*
X509200D01*
G01X516200Y261400D02*
X514900Y262700D01*
G01X516200Y260100D02*
Y261400D01*
G01X517000Y259300D02*
X516200Y260100D01*
G01X519200Y259300D02*
X517000D01*
G01X520200Y258300D02*
X519200Y259300D01*
G01X520200Y258164D02*
Y258300D01*
G01X521593Y256771D02*
X520200Y258164D01*
G01X538875Y262875D02*
X540600Y264600D01*
G01X537600Y262875D02*
X538875D01*
G01X535627Y264848D02*
X537600Y262875D01*
G01X534000Y264848D02*
X535627D01*
G01X532352Y263200D02*
X534000Y264848D01*
G01X531000Y263200D02*
X532352D01*
G01X529500Y264700D02*
X531000Y263200D01*
G01X527600Y264700D02*
X529500D01*
G01X525600Y262700D02*
X527600Y264700D01*
G01X524100Y262700D02*
X525600D01*
G01X522066Y260666D02*
X524100Y262700D01*
G01X518733Y260666D02*
X522066D01*
G01X518352Y261047D02*
X518733Y260666D01*
G01X539800Y251500D02*
X541400Y253100D01*
G01X537700Y251500D02*
X539800D01*
G01X536300Y252900D02*
X537700Y251500D01*
G01X534300Y252900D02*
X536300D01*
G01X532800Y251400D02*
X534300Y252900D01*
G01X530800Y251400D02*
X532800D01*
G01X529100Y253100D02*
X530800Y251400D01*
G01X527400Y253100D02*
X529100D01*
G01X525900Y251600D02*
X527400Y253100D01*
G01X524000Y251600D02*
X525900D01*
G01X522500Y253100D02*
X524000Y251600D01*
G01X521100Y253100D02*
X522500D01*
G01X519000Y255200D02*
X521100Y253100D01*
G01X517400Y255200D02*
X519000D01*
G01X515719Y256881D02*
X517400Y255200D01*
G01X513781Y256881D02*
X515719D01*
G01X512200Y255300D02*
X513781Y256881D01*
G01X504100Y255300D02*
X512200D01*
G01X502300Y257100D02*
X504100Y255300D01*
G01X500900Y257100D02*
X502300D01*
G01X499800Y258200D02*
X500900Y257100D01*
G01X499800Y261900D02*
Y258200D01*
G01X498900Y262800D02*
X499800Y261900D01*
G01X497400Y262800D02*
X498900D01*
G01X495600Y264600D02*
X497400Y262800D01*
G01X493600Y264600D02*
X495600D01*
G01X492000Y263000D02*
X493600Y264600D01*
G01X485800Y263000D02*
X492000D01*
G01X483500Y260700D02*
X485800Y263000D01*
G01X482300Y260700D02*
X483500D01*
G01X481060Y259460D02*
X482300Y260700D01*
G01X478840Y259460D02*
X481060D01*
G01X507885Y264100D02*
X504832Y261047D01*
G01X515600Y264100D02*
X507885D01*
G01X516700Y263000D02*
X515600Y264100D01*
G01X519200Y263000D02*
X516700D01*
G01X520800Y264600D02*
X519200Y263000D01*
G01X522328Y264600D02*
X520800D01*
G01X525000Y267272D02*
X522328Y264600D01*
G01X526639Y267272D02*
X525000D01*
G01X528167Y268800D02*
X526639Y267272D01*
G01X529100Y268800D02*
X528167D01*
G01X530900Y267000D02*
X529100Y268800D01*
G01X532700Y267000D02*
X530900D01*
G01X534500Y268800D02*
X532700Y267000D01*
G01X535575Y268800D02*
X534500D01*
G01X537600Y266775D02*
X535575Y268800D01*
G01X538875Y266775D02*
X537600D01*
G01X540800Y268700D02*
X538875Y266775D01*
G01X489300Y238100D02*
Y218700D01*
G01X487804Y239596D02*
X489300Y238100D01*
G01X483432Y239596D02*
X487804D01*
G01X483863Y271177D02*
X484500D01*
G01X482826Y272214D02*
X483863Y271177D01*
G01X482826Y282721D02*
Y272214D01*
G01X484552Y284447D02*
X482826Y282721D01*
G01X505099Y399500D02*
X508899Y403300D01*
G01X503134Y399500D02*
X505099D01*
G01X498856Y395222D02*
X503134Y399500D01*
G01X497419Y395222D02*
X498856D01*
G01X496497Y394300D02*
X497419Y395222D01*
G01X496497Y371774D02*
Y394300D01*
G01X494723Y370000D02*
X496497Y371774D01*
G01X493734Y370000D02*
X494723D01*
G01X480166Y358166D02*
X478700Y356700D01*
G01X481934Y358166D02*
X480166D01*
G01X483123Y356977D02*
X481934Y358166D01*
G01X485577Y356977D02*
X483123D01*
G01X487100Y358500D02*
X485577Y356977D01*
G01X488500Y358500D02*
X487100D01*
G01X490117Y360117D02*
X488500Y358500D01*
G01X492083Y360117D02*
X490117D01*
G01X493274Y358926D02*
X492083Y360117D01*
G01X495826Y358926D02*
X493274D01*
G01X497017Y360117D02*
X495826Y358926D01*
G01X498983Y360117D02*
X497017D01*
G01X500174Y358926D02*
X498983Y360117D01*
G01X502426Y358926D02*
X500174D01*
G01X503617Y360117D02*
X502426Y358926D01*
G01X505783Y360117D02*
X503617D01*
G01X506974Y358926D02*
X505783Y360117D01*
G01X508926Y358926D02*
X506974D01*
G01X510117Y360117D02*
X508926Y358926D01*
G01X512583Y360117D02*
X510117D01*
G01X513774Y358926D02*
X512583Y360117D01*
G01X515826Y358926D02*
X513774D01*
G01X517017Y360117D02*
X515826Y358926D01*
G01X519183Y360117D02*
X517017D01*
G01X520374Y358926D02*
X519183Y360117D01*
G01X522626Y358926D02*
X520374D01*
G01X523817Y360117D02*
X522626Y358926D01*
G01X525983Y360117D02*
X523817D01*
G01X527174Y358926D02*
X525983Y360117D01*
G01X529426Y358926D02*
X527174D01*
G01X530617Y360117D02*
X529426Y358926D01*
G01X532683Y360117D02*
X530617D01*
G01X533874Y358926D02*
X532683Y360117D01*
G01X536226Y358926D02*
X533874D01*
G01X537417Y360117D02*
X536226Y358926D01*
G01X539483Y360117D02*
X537417D01*
G01X540674Y358926D02*
X539483Y360117D01*
G01X500600Y399700D02*
X506600Y405700D01*
G01X497901Y399700D02*
X500600D01*
G01X495373Y397172D02*
X497901Y399700D01*
G01X494039Y397172D02*
X495373D01*
G01X493072Y396205D02*
X494039Y397172D01*
G01X493072Y373258D02*
Y396205D01*
G01X492041Y372227D02*
X493072Y373258D01*
G01X490819Y372227D02*
X492041D01*
G01X515610Y401310D02*
X517830Y403530D01*
G01X514130Y401310D02*
X515610D01*
G01X512240Y399420D02*
X514130Y401310D01*
G01X509330Y399420D02*
X512240D01*
G01X505881Y395971D02*
X509330Y399420D01*
G01X504580Y395971D02*
X505881D01*
G01X501880Y393271D02*
X504580Y395971D01*
G01X500799Y393271D02*
X501880D01*
G01X499877Y392349D02*
X500799Y393271D01*
G01X499877Y369824D02*
Y392349D01*
G01X498553Y368500D02*
X499877Y369824D01*
G01X497892Y368500D02*
X498553D01*
G01X495892Y366500D02*
X497892Y368500D01*
G01X494307Y366500D02*
X495892D01*
G01X492148Y364341D02*
X494307Y366500D01*
G01X490148Y364341D02*
X492148D01*
G01X536590Y417000D02*
X588371Y468781D01*
G01X527392Y417000D02*
X536590D01*
G01X515792Y405400D02*
X527392Y417000D01*
G01X514401Y405400D02*
X515792D01*
G01X512301Y403300D02*
X514401Y405400D01*
G01X508899Y403300D02*
X512301D01*
G01X536291Y419500D02*
X588372Y471581D01*
G01X525299Y419500D02*
X536291D01*
G01X511499Y405700D02*
X525299Y419500D01*
G01X506600Y405700D02*
X511499D01*
G01X537392Y415000D02*
X588977Y466585D01*
G01X530309Y415000D02*
X537392D01*
G01X518839Y403530D02*
X530309Y415000D01*
G01X517830Y403530D02*
X518839D01*
G01X595944Y126356D02*
X607694D01*
G01X564311Y256390D02*
X563936Y256765D01*
G01X574079Y256390D02*
X564311D01*
G01X574095Y256374D02*
X574079Y256390D01*
G01X576197Y256374D02*
X574095D01*
G01X587174Y267351D02*
X576197Y256374D01*
G01X612102Y267351D02*
X587174D01*
G01X574874Y270759D02*
X610650D01*
G01X567315Y263200D02*
X574874Y270759D01*
G01X557600Y263200D02*
X567315D01*
G01X555900Y264900D02*
X557600Y263200D01*
G01X554600Y264900D02*
X555900D01*
G01X552600Y262900D02*
X554600Y264900D01*
G01X551500Y262900D02*
X552600D01*
G01X549700Y264700D02*
X551500Y262900D01*
G01X547500Y264700D02*
X549700D01*
G01X545700Y262900D02*
X547500Y264700D01*
G01X544400Y262900D02*
X545700D01*
G01X542700Y264600D02*
X544400Y262900D01*
G01X540600Y264600D02*
X542700D01*
G01X587652Y266199D02*
X612580D01*
G01X577065Y255612D02*
X587652Y266199D01*
G01X576111Y255612D02*
X577065D01*
G01X576109Y255614D02*
X576111Y255612D01*
G01X565230Y255614D02*
X576109D01*
G01X563242Y253626D02*
X565230Y255614D01*
G01X562526Y253626D02*
X563242D01*
G01X560250Y251350D02*
X562526Y253626D01*
G01X558150Y251350D02*
X560250D01*
G01X556500Y253000D02*
X558150Y251350D01*
G01X554900Y253000D02*
X556500D01*
G01X553350Y251450D02*
X554900Y253000D01*
G01X551050Y251450D02*
X553350D01*
G01X549500Y253000D02*
X551050Y251450D01*
G01X547600Y253000D02*
X549500D01*
G01X546100Y251500D02*
X547600Y253000D01*
G01X544400Y251500D02*
X546100D01*
G01X542800Y253100D02*
X544400Y251500D01*
G01X541400Y253100D02*
X542800D01*
G01X543100Y268700D02*
X540800D01*
G01X544528Y267272D02*
X543100Y268700D01*
G01X546044Y267272D02*
X544528D01*
G01X547600Y268828D02*
X546044Y267272D01*
G01X549428Y268828D02*
X547600D01*
G01X551300Y270700D02*
X549428Y268828D01*
G01X553000Y270700D02*
X551300D01*
G01X555229Y268471D02*
X553000Y270700D01*
G01X556184Y268471D02*
X555229D01*
G01X557900Y266755D02*
X556184Y268471D01*
G01X557900Y266700D02*
Y266755D01*
G01X559400Y266700D02*
X557900D01*
G01X564605Y271905D02*
X559400Y266700D01*
G01X574390Y271905D02*
X564605D01*
G01X574396Y271911D02*
X574390Y271905D01*
G01X610172Y271911D02*
X574396D01*
G01X557016Y259884D02*
X556256Y260644D01*
G01X566212Y259884D02*
X557016D01*
G01X566999Y260671D02*
X566212Y259884D01*
G01X567026Y260671D02*
X566999D01*
G01X575610Y269255D02*
X567026Y260671D01*
G01X611274Y269255D02*
X575610D01*
G01X562437Y273063D02*
X609694D01*
G01X560900Y274600D02*
X562437Y273063D01*
G01X575922Y268503D02*
X566368Y258949D01*
G01X611624Y268503D02*
X575922D01*
G01X562749Y273815D02*
X609382D01*
G01X561213Y275351D02*
X562749Y273815D01*
G01X557014Y262094D02*
X556341Y261421D01*
G01X567273Y262094D02*
X557014D01*
G01X575186Y270007D02*
X567273Y262094D01*
G01X610962Y270007D02*
X575186D01*
G01X542726Y358926D02*
X540674D01*
G01X543917Y360117D02*
X542726Y358926D01*
G01X546183Y360117D02*
X543917D01*
G01X547374Y358926D02*
X546183Y360117D01*
G01X549429Y358926D02*
X547374D01*
G01X551013Y360510D02*
X549429Y358926D01*
G01X552435Y360510D02*
X551013D01*
G01X553800Y361875D02*
X552435Y360510D01*
G01X553800Y400982D02*
Y361875D01*
G01X554378Y402378D02*
X553800Y400982D01*
G01X554400Y402431D02*
X554378Y402378D01*
G01X565076Y428205D02*
X554400Y402431D01*
G01X570716Y343327D02*
X568986D01*
G01X577191Y349802D02*
X570716Y343327D01*
G01X577191Y357772D02*
Y349802D01*
G01X583401Y363982D02*
X577191Y357772D01*
G01X583401Y373807D02*
Y363982D01*
G01X587007Y377413D02*
X583401Y373807D01*
G01X619399Y377413D02*
X587007D01*
G01X587139Y450268D02*
X565076Y428205D01*
G01X592772Y450268D02*
X587139D01*
G01X595070Y447970D02*
X592772Y450268D01*
G01X592410Y442105D02*
X616595D01*
G01X590251Y444264D02*
X592410Y442105D01*
G01X590251Y446153D02*
Y444264D01*
G01X592068Y447970D02*
X590251Y446153D01*
G01X595070Y447970D02*
X592068D01*
G01X588371Y468781D02*
X608494D01*
G01X588372Y471581D02*
X606906D01*
G01X588977Y466585D02*
X603906D01*
G01X649142Y-12187D02*
X645941Y-15388D01*
G01X649142Y-1255D02*
Y-12187D01*
G01X656132Y5735D02*
X649142Y-1255D01*
G01X656132Y9951D02*
Y5735D01*
G01X661213Y15032D02*
X656132Y9951D01*
G01X673446Y15032D02*
X661213D01*
G01X661691Y13880D02*
X676680D01*
G01X657284Y9473D02*
X661691Y13880D01*
G01X657284Y5257D02*
Y9473D01*
G01X650339Y-1688D02*
X657284Y5257D01*
G01X650339Y-12620D02*
Y-1688D01*
G01X646419Y-16540D02*
X650339Y-12620D01*
G01X625500Y-3000D02*
X623000D01*
G01X631400Y2900D02*
X625500Y-3000D01*
G01X650037Y2900D02*
X631400D01*
G01X653828Y6691D02*
X650037Y2900D01*
G01X653828Y11226D02*
Y6691D01*
G01X660602Y18000D02*
X653828Y11226D01*
G01X672854Y18000D02*
X660602D01*
G01X659982Y19400D02*
X672499D01*
G01X652676Y12094D02*
X659982Y19400D01*
G01X652676Y7169D02*
Y12094D01*
G01X649607Y4100D02*
X652676Y7169D01*
G01X629510Y4100D02*
X649607D01*
G01X624770Y-640D02*
X629510Y4100D01*
G01X662647Y11576D02*
X679495D01*
G01X659588Y8517D02*
X662647Y11576D01*
G01X659588Y4301D02*
Y8517D01*
G01X653039Y-2248D02*
X659588Y4301D01*
G01X653039Y-13180D02*
Y-2248D01*
G01X647375Y-18844D02*
X653039Y-13180D01*
G01X654225Y-15197D02*
X649426Y-19996D01*
G01X654225Y-2692D02*
Y-15197D01*
G01X660740Y3823D02*
X654225Y-2692D01*
G01X660740Y5204D02*
Y3823D01*
G01X663634Y8098D02*
X660740Y5204D01*
G01X662169Y12728D02*
X677328D01*
G01X658436Y8995D02*
X662169Y12728D01*
G01X658436Y4779D02*
Y8995D01*
G01X651658Y-1999D02*
X658436Y4779D01*
G01X651658Y-12931D02*
Y-1999D01*
G01X646897Y-17692D02*
X651658Y-12931D01*
G01X656659Y-16340D02*
X651499Y-21500D01*
G01X656659Y-7241D02*
Y-16340D01*
G01X659100Y-4800D02*
X656659Y-7241D01*
G01X661500Y-4800D02*
X659100D01*
G01X662700Y-3600D02*
X661500Y-4800D01*
G01X662700Y-2814D02*
Y-3600D01*
G01X671514Y6000D02*
X662700Y-2814D01*
G01X632600Y1300D02*
X617064Y-14236D01*
G01X650067Y1300D02*
X632600D01*
G01X654980Y6213D02*
X650067Y1300D01*
G01X654980Y10429D02*
Y6213D01*
G01X660735Y16184D02*
X654980Y10429D01*
G01X672758Y16184D02*
X660735D01*
G01X657825Y-19634D02*
X656807Y-20652D01*
G01X657825Y-8175D02*
Y-19634D01*
G01X660448Y-5552D02*
X657825Y-8175D01*
G01X661812Y-5552D02*
X660448D01*
G01X663452Y-3912D02*
X661812Y-5552D01*
G01X655770Y-15757D02*
X650779Y-20748D01*
G01X655770Y-6230D02*
Y-15757D01*
G01X659100Y-2900D02*
X655770Y-6230D01*
G01X659100Y-1277D02*
Y-2900D01*
G01X660838Y461D02*
X659100Y-1277D01*
G01X663961Y461D02*
X660838D01*
G01X668100Y39400D02*
X650800D01*
G01D02*
X646000Y44200D01*
G01D02*
X634400D01*
G01D02*
X629800Y48800D01*
G01D02*
Y91900D01*
G01D02*
X633365Y95465D01*
G01X667978Y32022D02*
X661800Y38200D01*
G01D02*
X650302D01*
G01D02*
X645454Y43048D01*
G01D02*
X634878D01*
G01D02*
X634877Y43047D01*
G01D02*
X633923D01*
G01D02*
X628648Y48322D01*
G01D02*
Y92748D01*
G01D02*
X632121Y96221D01*
G01X633535Y98281D02*
X626040D01*
G01X634271Y97545D02*
X633535Y98281D01*
G01X653140Y97545D02*
X634271D01*
G01X670503Y114908D02*
X653140Y97545D01*
G01X607694Y126356D02*
X609482Y124568D01*
G01X633365Y95465D02*
X670915D01*
G01X632121Y96221D02*
X670041D01*
G01X628083Y283332D02*
X612102Y267351D01*
G01X610650Y270759D02*
X627723Y287832D01*
G01X629151Y278761D02*
X631529Y281139D01*
G01X625142Y278761D02*
X629151D01*
G01X612580Y266199D02*
X625142Y278761D01*
G01X627669Y289408D02*
X610172Y271911D01*
G01X627523Y285504D02*
X611274Y269255D01*
G01X609694Y273063D02*
X626869Y290238D01*
G01X627873Y284752D02*
X611624Y268503D01*
G01X609382Y273815D02*
X626680Y291113D01*
G01X627211Y286256D02*
X610962Y270007D01*
G01X671228Y251272D02*
X662348Y260152D01*
G01D02*
X654152D01*
G01D02*
X653200Y259200D01*
G01D02*
X633800D01*
G01D02*
X628900Y264100D01*
G01D02*
Y275768D01*
G01D02*
X629843Y276711D01*
G01D02*
Y276723D01*
G01D02*
X631117Y277997D01*
G01D02*
X631129D01*
G01D02*
X631367Y278235D01*
G01D02*
X642620D01*
G01D02*
X645081Y280696D01*
G01X670750Y250120D02*
X661870Y259000D01*
G01D02*
X654630D01*
G01D02*
X653678Y258048D01*
G01D02*
X633152D01*
G01D02*
X627700Y263500D01*
G01D02*
Y276198D01*
G01D02*
X628691Y277189D01*
G01D02*
Y277201D01*
G01D02*
X630639Y279149D01*
G01D02*
X630651D01*
G01D02*
X630937Y279435D01*
G01D02*
X642189D01*
G01D02*
X642317Y279563D01*
G01X642318D02*
X643241Y280486D01*
G01X639734Y283332D02*
X628083D01*
G01X650605Y294203D02*
X639734Y283332D01*
G01X650605Y330200D02*
Y294203D01*
G01X657027Y336622D02*
X650605Y330200D01*
G01X659948Y336622D02*
X657027D01*
G01X668741Y345415D02*
X659948Y336622D01*
G01X627723Y287832D02*
X628525D01*
G01X641607Y282164D02*
Y281139D01*
G01X651802Y292359D02*
X641607Y282164D01*
G01X651802Y328532D02*
Y292359D01*
G01X654892Y331622D02*
X651802Y328532D01*
G01X656578Y331622D02*
X654892D01*
G01X669219Y344263D02*
X656578Y331622D01*
G01X631529Y281139D02*
X641607D01*
G01D02*
X641665D01*
G01X629188Y289408D02*
X627669D01*
G01X630549Y288047D02*
X629188Y289408D01*
G01X631982Y288047D02*
X630549D01*
G01X633775Y289840D02*
X631982Y288047D01*
G01X635040Y289840D02*
X633775D01*
G01X637100Y291900D02*
X635040Y289840D01*
G01X642300Y291900D02*
X637100D01*
G01X644437Y294037D02*
X642300Y291900D01*
G01X648183Y294037D02*
X644437D01*
G01X649653Y295507D02*
X648183Y294037D01*
G01X649653Y330595D02*
Y295507D01*
G01X656632Y337574D02*
X649653Y330595D01*
G01X659553Y337574D02*
X656632D01*
G01X668346Y346367D02*
X659553Y337574D01*
G01X622048Y335895D02*
Y374764D01*
G01X628143Y329800D02*
X622048Y335895D01*
G01X636100Y329800D02*
X628143D01*
G01X634225Y285504D02*
X627523D01*
G01X636985Y288264D02*
X634225Y285504D01*
G01X630662Y290238D02*
X631250Y289650D01*
G01X626869Y290238D02*
X630662D01*
G01X648501Y331445D02*
X662075Y345019D01*
G01X648501Y296310D02*
Y331445D01*
G01X646980Y294789D02*
X648501Y296310D01*
G01X642959Y294789D02*
X646980D01*
G01X641222Y293052D02*
X642959Y294789D01*
G01X636505Y293052D02*
X641222D01*
G01X634445Y290992D02*
X636505Y293052D01*
G01X632592Y290992D02*
X634445D01*
G01X631250Y289650D02*
X632592Y290992D01*
G01X635881Y284752D02*
X627873D01*
G01X636799Y285670D02*
X635881Y284752D01*
G01X644271Y329398D02*
X661045Y346172D01*
G01X644271Y297882D02*
Y329398D01*
G01X640489Y294100D02*
X644271Y297882D01*
G01X635821Y294100D02*
X640489D01*
G01X633865Y292144D02*
X635821Y294100D01*
G01X630698Y292144D02*
X633865D01*
G01X629667Y291113D02*
X630698Y292144D01*
G01X626680Y291113D02*
X629667D01*
G01X632748Y286256D02*
X627211D01*
G01X634407Y287915D02*
X632748Y286256D01*
G01X645081Y280696D02*
Y281793D01*
G01D02*
X645080Y281794D01*
G01D02*
Y283509D01*
G01D02*
X656300Y294729D01*
G01D02*
Y300900D01*
G01D02*
X664800Y309400D01*
G01X642317Y279563D02*
X642318D01*
G01X643241Y280486D02*
Y280487D01*
G01D02*
X643928Y281174D01*
G01D02*
Y283421D01*
G01D02*
X652800Y292293D01*
G01D02*
Y302200D01*
G01D02*
X661300Y310700D01*
G01D02*
X680800D01*
G01X616595Y442105D02*
X676900Y381800D01*
G01X622048Y374764D02*
X619399Y377413D01*
G01X662075Y345019D02*
X665049D01*
G01X661045Y346172D02*
X664501D01*
G01X607016Y463475D02*
X608800D01*
G01X603906Y466585D02*
X607016Y463475D01*
G01X608494Y468781D02*
X608800Y468475D01*
G01X606906Y471581D02*
X608800Y473475D01*
G01X629968Y554490D02*
Y511067D01*
G01D02*
X634685Y506350D01*
G01D02*
X663182D01*
G01D02*
X668535Y511703D01*
G01X624943Y523043D02*
Y552657D01*
G01X623600Y521700D02*
X624943Y523043D01*
G01X630721Y511486D02*
Y554179D01*
G01X635104Y507103D02*
X630721Y511486D01*
G01X662871Y507103D02*
X635104D01*
G01X668448Y512680D02*
X662871Y507103D01*
G01X663494Y505598D02*
X634156D01*
G01D02*
X628956Y510798D01*
G01D02*
Y554542D01*
G01X663806Y504846D02*
X633760D01*
G01D02*
X628203Y510403D01*
G01D02*
Y554853D01*
G01X666769Y569121D02*
X657050Y559402D01*
G01D02*
X634880D01*
G01D02*
X629968Y554490D01*
G01X656071Y561679D02*
X665770Y571378D01*
G01X633965Y561679D02*
X656071D01*
G01X624943Y552657D02*
X633965Y561679D01*
G01X657362Y558650D02*
X667081Y568369D01*
G01X635192Y558650D02*
X657362D01*
G01X630721Y554179D02*
X635192Y558650D01*
G01X628956Y554542D02*
X634568Y560154D01*
G01D02*
X656738D01*
G01D02*
X666457Y569873D01*
G01X628203Y554853D02*
X634257Y560907D01*
G01D02*
X656427D01*
G01D02*
X666145Y570625D01*
G01X679004Y20590D02*
X673446Y15032D01*
G01X682843Y20590D02*
X679004D01*
G01X685405Y18028D02*
X682843Y20590D01*
G01X693631Y18028D02*
X685405D01*
G01X695947Y15712D02*
X693631Y18028D01*
G01X718583Y15712D02*
X695947D01*
G01X718747Y15876D02*
X718583Y15712D01*
G01X720053Y15876D02*
X718747D01*
G01X721650Y14279D02*
X720053Y15876D01*
G01X721650Y10234D02*
Y14279D01*
G01X724109Y7775D02*
X721650Y10234D01*
G01X724109Y4301D02*
Y7775D01*
G01X725904Y2506D02*
X724109Y4301D01*
G01X724752Y-4522D02*
X735782Y-15552D01*
G01X724752Y2028D02*
Y-4522D01*
G01X722957Y3823D02*
X724752Y2028D01*
G01X722957Y7197D02*
Y3823D01*
G01X715594Y14560D02*
X722957Y7197D01*
G01X695469Y14560D02*
X715594D01*
G01X693153Y16876D02*
X695469Y14560D01*
G01X685106Y16876D02*
X693153D01*
G01X684162Y15932D02*
X685106Y16876D01*
G01X678902Y15932D02*
X684162D01*
G01X678880Y15910D02*
X678902Y15932D01*
G01X678710Y15910D02*
X678880D01*
G01X676680Y13880D02*
X678710Y15910D01*
G01X677944Y23090D02*
X672854Y18000D01*
G01X692339Y23090D02*
X677944D01*
G01X693976Y21453D02*
X692339Y23090D01*
G01X693976Y20923D02*
Y21453D01*
G01X694567Y20332D02*
X693976Y20923D01*
G01X694587Y20332D02*
X694567D01*
G01X696903Y18016D02*
X694587Y20332D01*
G01X717627Y18016D02*
X696903D01*
G01X717791Y18180D02*
X717627Y18016D01*
G01X723038Y18180D02*
X717791D01*
G01X726413Y14805D02*
X723038Y18180D01*
G01X723516Y19332D02*
X727600Y15248D01*
G01X706918Y19332D02*
X723516D01*
G01X703502Y22748D02*
X706918Y19332D01*
G01X694923Y22748D02*
X703502D01*
G01X691129Y26542D02*
X694923Y22748D01*
G01X679641Y26542D02*
X691129D01*
G01X672499Y19400D02*
X679641Y26542D01*
G01X722251Y-15345D02*
X725450Y-18544D01*
G01X722251Y-14005D02*
Y-15345D01*
G01X723489Y-12767D02*
X722251Y-14005D01*
G01X723489Y-6519D02*
Y-12767D01*
G01X722448Y-5478D02*
X723489Y-6519D01*
G01X722448Y1072D02*
Y-5478D01*
G01X720653Y2867D02*
X722448Y1072D01*
G01X720653Y6241D02*
Y2867D01*
G01X714638Y12256D02*
X720653Y6241D01*
G01X682122Y12256D02*
X714638D01*
G01X681136Y11270D02*
X682122Y12256D01*
G01X679801Y11270D02*
X681136D01*
G01X679495Y11576D02*
X679801Y11270D01*
G01X679592Y8098D02*
X663634D01*
G01X682600Y11104D02*
X679592Y8098D01*
G01X701460Y11104D02*
X682600D01*
G01X703402Y9162D02*
X701460Y11104D01*
G01X703402Y9091D02*
Y9162D01*
G01X703428Y9065D02*
X703402Y9091D01*
G01X703428Y7910D02*
Y9065D01*
G01X704812Y6526D02*
X703428Y7910D01*
G01X705103Y6526D02*
X704812D01*
G01X706382Y5247D02*
X705103Y6526D01*
G01X706382Y1182D02*
Y5247D01*
G01X706902Y662D02*
X706382Y1182D01*
G01X706902Y-738D02*
Y662D01*
G01X712441Y-6277D02*
X706902Y-738D01*
G01X712441Y-15659D02*
Y-6277D01*
G01X712793Y-16011D02*
X712441Y-15659D01*
G01X712796Y-16011D02*
X712793D01*
G01X723600Y-5000D02*
X735992Y-17392D01*
G01X723600Y1550D02*
Y-5000D01*
G01X721805Y3345D02*
X723600Y1550D01*
G01X721805Y6719D02*
Y3345D01*
G01X715116Y13408D02*
X721805Y6719D01*
G01X689663Y13408D02*
X715116D01*
G01X688291Y14780D02*
X689663Y13408D01*
G01X679380Y14780D02*
X688291D01*
G01X677328Y12728D02*
X679380Y14780D01*
G01X679653Y6000D02*
X671514D01*
G01X683253Y9600D02*
X679653Y6000D01*
G01X699600Y9600D02*
X683253D01*
G01X701100Y8100D02*
X699600Y9600D01*
G01X723749Y21200D02*
X727543Y17406D01*
G01X706899Y21200D02*
X723749D01*
G01X703099Y25000D02*
X706899Y21200D01*
G01X695879Y25000D02*
X703099D01*
G01X688579Y32300D02*
X695879Y25000D01*
G01X672204Y32300D02*
X688579D01*
G01X670227Y34277D02*
X672204Y32300D01*
G01X678384Y21810D02*
X672758Y16184D01*
G01X684190Y21810D02*
X678384D01*
G01X686820Y19180D02*
X684190Y21810D01*
G01X694109Y19180D02*
X686820D01*
G01X696425Y16864D02*
X694109Y19180D01*
G01X718105Y16864D02*
X696425D01*
G01X718269Y17028D02*
X718105Y16864D01*
G01X720531Y17028D02*
X718269D01*
G01X722803Y14756D02*
X720531Y17028D01*
G01X722803Y13802D02*
Y14756D01*
G01X722802Y13801D02*
X722803Y13802D01*
G01X722802Y10712D02*
Y13801D01*
G01X725261Y8253D02*
X722802Y10712D01*
G01X663452Y-3126D02*
Y-3912D01*
G01X671378Y4800D02*
X663452Y-3126D01*
G01X680100Y4800D02*
X671378D01*
G01X684064Y8764D02*
X680100Y4800D01*
G01X697736Y8764D02*
X684064D01*
G01X706150Y350D02*
X697736Y8764D01*
G01X706150Y-1050D02*
Y350D01*
G01X707600Y-2500D02*
X706150Y-1050D01*
G01X707600Y-14643D02*
Y-2500D01*
G01X714603Y-21646D02*
X707600Y-14643D01*
G01X1275854Y-21646D02*
X714603D01*
G01X670300Y6800D02*
X663961Y461D01*
G01X679389Y6800D02*
X670300D01*
G01X682941Y10352D02*
X679389Y6800D01*
G01X701148Y10352D02*
X682941D01*
G01X702650Y8850D02*
X701148Y10352D01*
G01X702650Y8779D02*
Y8850D01*
G01X702676Y8753D02*
X702650Y8779D01*
G01X702676Y7447D02*
Y8753D01*
G01X702650Y7421D02*
X702676Y7447D01*
G01X702650Y6750D02*
Y7421D01*
G01X704450Y4950D02*
X702650Y6750D01*
G01X711791Y23716D02*
Y27209D01*
G01D02*
X705200Y33800D01*
G01X670400Y26100D02*
X671500D01*
G01D02*
X672821Y27421D01*
G01D02*
Y29667D01*
G01D02*
X670466Y32022D01*
G01D02*
X667978D01*
G01X705200Y33800D02*
X673700D01*
G01D02*
X668100Y39400D01*
G01X682800Y147900D02*
X728274Y102426D01*
G01X682800Y187800D02*
Y147900D01*
G01X670503Y115884D02*
Y114908D01*
G01X681848Y147505D02*
Y187688D01*
G01X727322Y102031D02*
X681848Y147505D01*
G01X670915Y95465D02*
X688864Y113414D01*
G01D02*
Y134236D01*
G01D02*
X680696Y142404D01*
G01D02*
Y187776D01*
G01X670041Y96221D02*
X687658Y113838D01*
G01D02*
Y132691D01*
G01D02*
X679944Y140405D01*
G01D02*
Y187464D01*
G01X675924Y194676D02*
X682800Y187800D01*
G01X675924Y199459D02*
Y194676D01*
G01X684200Y207735D02*
X675924Y199459D01*
G01X684200Y236483D02*
Y207735D01*
G01X683447Y208046D02*
Y236794D01*
G01X675172Y199771D02*
X683447Y208046D01*
G01X675172Y194364D02*
Y199771D01*
G01X681848Y187688D02*
X675172Y194364D01*
G01X680696Y187776D02*
X674420Y194052D01*
G01D02*
Y200083D01*
G01D02*
X680973Y206636D01*
G01D02*
Y238921D01*
G01X679944Y187464D02*
X673668Y193740D01*
G01D02*
Y200395D01*
G01D02*
X680221Y206948D01*
G01D02*
Y240051D01*
G01X697288Y249571D02*
X684200Y236483D01*
G01X697288Y262971D02*
Y249571D01*
G01X693568Y266691D02*
X697288Y262971D01*
G01X693568Y281362D02*
Y266691D01*
G01X698500Y273392D02*
Y294321D01*
G01X707198Y264694D02*
X698500Y273392D01*
G01X707198Y257595D02*
Y264694D01*
G01X716733Y248060D02*
X707198Y257595D01*
G01X721460Y248060D02*
X716733D01*
G01X723400Y250000D02*
X721460Y248060D01*
G01X718330Y252070D02*
X720450Y249950D01*
G01X715130Y252070D02*
X718330D01*
G01X708900Y258300D02*
X715130Y252070D01*
G01X708900Y265399D02*
Y258300D01*
G01X700324Y273975D02*
X708900Y265399D01*
G01X700324Y293738D02*
Y273975D01*
G01X723389Y246200D02*
X726328Y249139D01*
G01X716162Y246200D02*
X723389D01*
G01X707896Y254466D02*
X716162Y246200D01*
G01X707896Y254490D02*
Y254466D01*
G01X705496Y256890D02*
X707896Y254490D01*
G01X705496Y263989D02*
Y256890D01*
G01X696780Y272705D02*
X705496Y263989D01*
G01X696780Y295008D02*
Y272705D01*
G01X692616Y266579D02*
Y280967D01*
G01X696536Y262659D02*
X692616Y266579D01*
G01X696536Y249883D02*
Y262659D01*
G01X683447Y236794D02*
X696536Y249883D01*
G01X680973Y238921D02*
X685152Y243100D01*
G01D02*
Y248458D01*
G01D02*
X682338Y251272D01*
G01D02*
X671228D01*
G01X680221Y240051D02*
X684000Y243830D01*
G01D02*
Y247980D01*
G01D02*
X681860Y250120D01*
G01D02*
X670750D01*
G01X691830Y283100D02*
X693568Y281362D01*
G01X691001Y283100D02*
X691830D01*
G01X690048Y284053D02*
X691001Y283100D01*
G01X701077Y344277D02*
X697000Y340200D01*
G01D02*
Y337500D01*
G01D02*
X693500Y334000D01*
G01D02*
Y331400D01*
G01D02*
X687300Y325200D01*
G01X721800Y324108D02*
Y409159D01*
G01X710608Y312916D02*
X721800Y324108D01*
G01X710608Y308709D02*
Y312916D01*
G01X708291Y306392D02*
X710608Y308709D01*
G01X704931Y306392D02*
X708291D01*
G01X701730Y303191D02*
X704931Y306392D01*
G01X701730Y297551D02*
Y303191D01*
G01X698500Y294321D02*
X701730Y297551D01*
G01X703432Y296846D02*
X700324Y293738D01*
G01X703432Y302486D02*
Y296846D01*
G01X705589Y304643D02*
X703432Y302486D01*
G01X708949Y304643D02*
X705589D01*
G01X712310Y308004D02*
X708949Y304643D01*
G01X712310Y312211D02*
Y308004D01*
G01X723600Y323501D02*
X712310Y312211D01*
G01X723600Y408552D02*
Y323501D01*
G01X700028Y298256D02*
X696780Y295008D01*
G01X700028Y303896D02*
Y298256D01*
G01X704333Y308201D02*
X700028Y303896D01*
G01X707693Y308201D02*
X704333D01*
G01X708906Y309414D02*
X707693Y308201D01*
G01X708906Y313673D02*
Y309414D01*
G01X720000Y324767D02*
X708906Y313673D01*
G01X720000Y409766D02*
Y324767D01*
G01X691040Y282045D02*
X690048Y281053D01*
G01X691538Y282045D02*
X691040D01*
G01X692616Y280967D02*
X691538Y282045D01*
G01X683000Y328040D02*
X699925Y344965D01*
G01X664800Y309400D02*
X682500D01*
G01D02*
X683000Y309900D01*
G01D02*
Y328040D01*
G01X681300Y327970D02*
X698773Y345443D01*
G01X680800Y310700D02*
X681300Y311200D01*
G01D02*
Y327970D01*
G01X689687Y345415D02*
X668741D01*
G01X691905Y347633D02*
X689687Y345415D01*
G01X693470Y347633D02*
X691905D01*
G01X693525Y347688D02*
X693470Y347633D01*
G01X694312Y347688D02*
X693525D01*
G01X695700Y346300D02*
X694312Y347688D01*
G01X697621Y357957D02*
Y345667D01*
G01D02*
X696217Y344263D01*
G01D02*
X669219D01*
G01X693595Y361983D02*
X697621Y357957D01*
G01X693595Y365595D02*
Y361983D01*
G01X687427Y371763D02*
X693595Y365595D01*
G01X687427Y384926D02*
Y371763D01*
G01X689292Y346367D02*
X668346D01*
G01X691510Y348585D02*
X689292Y346367D01*
G01X693075Y348585D02*
X691510D01*
G01X695790Y351300D02*
X693075Y348585D01*
G01X695960Y372189D02*
X701077Y367072D01*
G01D02*
Y344277D01*
G01X698300Y487600D02*
Y397800D01*
G01D02*
X696500Y396000D01*
G01D02*
Y387500D01*
G01D02*
X695960Y386960D01*
G01D02*
Y372189D01*
G01X677300Y394998D02*
Y479270D01*
G01X684699Y387599D02*
X677300Y394998D01*
G01X684699Y371231D02*
Y387599D01*
G01X691000Y364930D02*
X684699Y371231D01*
G01X691000Y359288D02*
Y364930D01*
G01X695644Y354644D02*
X691000Y359288D01*
G01X691616Y395008D02*
Y413084D01*
G01X685851Y389243D02*
X691616Y395008D01*
G01X685851Y371709D02*
Y389243D01*
G01X692400Y365160D02*
X685851Y371709D01*
G01X692400Y360600D02*
Y365160D01*
G01X695700Y357300D02*
X692400Y360600D01*
G01X680638Y384693D02*
X679523Y385808D01*
G01X680638Y375638D02*
Y384693D01*
G01X675140Y370140D02*
X680638Y375638D01*
G01X675140Y363340D02*
Y370140D01*
G01X667200Y355400D02*
X675140Y363340D01*
G01X667200Y347170D02*
Y355400D01*
G01X665049Y345019D02*
X667200Y347170D01*
G01X677947Y387267D02*
X679385Y388705D01*
G01X677947Y382982D02*
Y387267D01*
G01X678476Y382453D02*
X677947Y382982D01*
G01X678476Y375106D02*
Y382453D01*
G01X673988Y370618D02*
X678476Y375106D01*
G01X673988Y364488D02*
Y370618D01*
G01X666197Y356697D02*
X673988Y364488D01*
G01X666197Y347868D02*
Y356697D01*
G01X664501Y346172D02*
X666197Y347868D01*
G01X699925Y344965D02*
Y360545D01*
G01D02*
X696600Y363870D01*
G01D02*
Y369000D01*
G01D02*
X695000Y370600D01*
G01D02*
Y488340D01*
G01X698773Y345443D02*
Y359445D01*
G01D02*
X695385Y362833D01*
G01D02*
Y368585D01*
G01D02*
X693848Y370122D01*
G01D02*
Y414652D01*
G01X689024Y415676D02*
Y485624D01*
G01X691616Y413084D02*
X689024Y415676D01*
G01X724429Y424738D02*
X760022Y460331D01*
G01X724429Y411788D02*
Y424738D01*
G01X721800Y409159D02*
X724429Y411788D01*
G01X726131Y411083D02*
X723600Y408552D01*
G01X722727Y412493D02*
X720000Y409766D01*
G01X722727Y425443D02*
Y412493D01*
G01X757950Y460666D02*
X722727Y425443D01*
G01X693848Y414652D02*
X692176Y416324D01*
G01D02*
Y487146D01*
G01X721900Y507200D02*
X739065Y524365D01*
G01X717300Y507200D02*
X721900D01*
G01X716600Y507900D02*
X717300Y507200D01*
G01X710050Y507900D02*
X716600D01*
G01X707850Y505700D02*
X710050Y507900D01*
G01X720142Y513300D02*
X726200D01*
G01X717842Y511000D02*
X720142Y513300D01*
G01X713800Y511000D02*
X717842D01*
G01X712100Y512700D02*
X713800Y511000D01*
G01X668535Y511703D02*
X676084D01*
G01D02*
X678637Y509150D01*
G01D02*
X692133D01*
G01D02*
X699800Y501483D01*
G01D02*
Y489100D01*
G01D02*
X698300Y487600D01*
G01X688202Y490172D02*
Y497736D01*
G01X677300Y479270D02*
X688202Y490172D01*
G01X691401Y497799D02*
X691000Y498200D01*
G01X691401Y488001D02*
Y497799D01*
G01X689024Y485624D02*
X691401Y488001D01*
G01X676171Y512680D02*
X668448D01*
G01X678881Y509970D02*
X676171Y512680D01*
G01X692377Y509970D02*
X678881D01*
G01X700508Y501839D02*
X692377Y509970D01*
G01X708978Y501839D02*
X700508D01*
G01X711339Y499478D02*
X708978Y501839D01*
G01X695000Y488340D02*
X698728Y492068D01*
G01D02*
Y501491D01*
G01D02*
X691895Y508324D01*
G01D02*
X666220D01*
G01D02*
X663494Y505598D01*
G01X692176Y487146D02*
X697576Y492546D01*
G01D02*
Y501470D01*
G01D02*
X691474Y507572D01*
G01D02*
X666532D01*
G01D02*
X663806Y504846D01*
G01X728237Y574228D02*
X698777D01*
G01D02*
X695088Y570539D01*
G01D02*
X678730D01*
G01D02*
X677312Y569121D01*
G01D02*
X666769D01*
G01X688930Y580471D02*
X700759Y592300D01*
G01X688930Y579040D02*
Y580471D01*
G01X683162Y573272D02*
X688930Y579040D01*
G01X678107Y573272D02*
X683162D01*
G01X676213Y571378D02*
X678107Y573272D01*
G01X665770Y571378D02*
X676213D01*
G01X699089Y573476D02*
X727925D01*
G01X695327Y569714D02*
X699089Y573476D01*
G01X678969Y569714D02*
X695327D01*
G01X677624Y568369D02*
X678969Y569714D01*
G01X667081Y568369D02*
X677624D01*
G01X666457Y569873D02*
X677000D01*
G01D02*
X678418Y571291D01*
G01D02*
X694776D01*
G01D02*
X698465Y574980D01*
G01D02*
X728549D01*
G01X666145Y570625D02*
X676625D01*
G01D02*
X678255Y572255D01*
G01D02*
X683785D01*
G01D02*
X689006Y577476D01*
G01D02*
X691624D01*
G01D02*
X693200Y575900D01*
G01X701600D02*
X693200D01*
G01X714100Y588400D02*
X701600Y575900D01*
G01X716074Y615426D02*
X713500Y618000D01*
G01X734425Y615426D02*
X716074D01*
G01X722827Y613500D02*
X736582D01*
G01X719188Y609861D02*
X722827Y613500D01*
G01X719188Y597901D02*
Y609861D01*
G01X713587Y592300D02*
X719188Y597901D01*
G01X700759Y592300D02*
X713587D01*
G01X713500Y614274D02*
X735359D01*
G01X711500Y616274D02*
X713500Y614274D01*
G01X729301Y588400D02*
X714100D01*
G01X756714Y27255D02*
Y23130D01*
G01X759979Y30520D02*
X756714Y27255D01*
G01X759979Y75309D02*
Y30520D01*
G01X761149Y586D02*
X999520D01*
G01X760039Y-524D02*
X761149Y586D01*
G01X755424Y-524D02*
X760039D01*
G01X754600Y300D02*
X755424Y-524D01*
G01X725904Y-3731D02*
Y2506D01*
G01X737108Y-14935D02*
X725904Y-3731D01*
G01X1267465Y-14935D02*
X737108D01*
G01X736783Y-16240D02*
X1267860D01*
G01X736095Y-15552D02*
X736783Y-16240D01*
G01X735782Y-15552D02*
X736095D01*
G01X726413Y5487D02*
Y14805D01*
G01X726448Y5452D02*
X726413Y5487D01*
G01X726448Y5222D02*
Y5452D01*
G01X731570Y100D02*
X726448Y5222D01*
G01X740843Y100D02*
X731570D01*
G01X741547Y804D02*
X740843Y100D01*
G01X747637Y804D02*
X741547D01*
G01X750919Y-2478D02*
X747637Y804D01*
G01X750919Y-3848D02*
Y-2478D01*
G01X759702Y-12631D02*
X750919Y-3848D01*
G01X1003249Y-12631D02*
X759702D01*
G01X777129Y-11479D02*
X1002771D01*
G01X770750Y-5100D02*
X777129Y-11479D01*
G01X759500Y-5100D02*
X770750D01*
G01X756828Y-2428D02*
X759500Y-5100D01*
G01X753200Y-2428D02*
X756828D01*
G01X752236Y-1464D02*
X753200Y-2428D01*
G01X751535Y-1464D02*
X752236D01*
G01X747971Y2100D02*
X751535Y-1464D01*
G01X740348Y2100D02*
X747971D01*
G01X739500Y1252D02*
X740348Y2100D01*
G01X732048Y1252D02*
X739500D01*
G01X727600Y5700D02*
X732048Y1252D01*
G01X727600Y15248D02*
Y5700D01*
G01X725450Y-18544D02*
X1268968D01*
G01X735992Y-17392D02*
X1268490D01*
G01X778404Y1938D02*
X1007200D01*
G01X778345Y1879D02*
X778404Y1938D01*
G01X763970Y1879D02*
X778345D01*
G01X763550Y2299D02*
X763970Y1879D01*
G01X749402Y2299D02*
X763550D01*
G01X748449Y3252D02*
X749402Y2299D01*
G01X740201Y3252D02*
X748449D01*
G01X728752Y14701D02*
X740201Y3252D01*
G01X728752Y16171D02*
Y14701D01*
G01X727543Y17380D02*
X728752Y16171D01*
G01X727543Y17406D02*
Y17380D01*
G01X725261Y5009D02*
Y8253D01*
G01X725296Y4974D02*
X725261Y5009D01*
G01X725296Y4744D02*
Y4974D01*
G01X727056Y2984D02*
X725296Y4744D01*
G01X727056Y-3253D02*
Y2984D01*
G01X737586Y-13783D02*
X727056Y-3253D01*
G01X1266987Y-13783D02*
X737586D01*
G01X759056Y30944D02*
Y75168D01*
G01X755762Y27650D02*
X759056Y30944D01*
G01X755762Y25326D02*
Y27650D01*
G01X753675Y23239D02*
X755762Y25326D01*
G01X761461Y-166D02*
X999208D01*
G01X760351Y-1276D02*
X761461Y-166D01*
G01X753776Y-1276D02*
X760351D01*
G01X752100Y400D02*
X753776Y-1276D01*
G01X751900Y400D02*
X752100D01*
G01X756955Y15300D02*
X755000Y17255D01*
G01X760100Y15300D02*
X756955D01*
G01X767819Y7581D02*
X760100Y15300D01*
G01X770219Y7581D02*
X767819D01*
G01X770500Y7300D02*
X770219Y7581D01*
G01X1020400Y7300D02*
X770500D01*
G01X753624Y81664D02*
X759979Y75309D01*
G01X740800Y81664D02*
X753624D01*
G01X737164Y85300D02*
X740800Y81664D01*
G01X730564Y85300D02*
X737164D01*
G01X728274Y87590D02*
X730564Y85300D01*
G01X728274Y102426D02*
Y87590D01*
G01X727322Y87478D02*
Y102031D01*
G01X730252Y84548D02*
X727322Y87478D01*
G01X736852Y84548D02*
X730252D01*
G01X740488Y80912D02*
X736852Y84548D01*
G01X753312Y80912D02*
X740488D01*
G01X759056Y75168D02*
X753312Y80912D01*
G01X726328Y249139D02*
Y249979D01*
G01X766852Y459242D02*
Y515240D01*
G01X771930Y454164D02*
X766852Y459242D01*
G01X771930Y453889D02*
Y454164D01*
G01X821380Y404439D02*
X771930Y453889D01*
G01X778593Y410738D02*
X788432D01*
G01X776905Y412426D02*
X778593Y410738D01*
G01X769097Y412426D02*
X776905D01*
G01X768211Y411540D02*
X769097Y412426D01*
G01X763177Y411540D02*
X768211D01*
G01X762989Y411728D02*
X763177Y411540D01*
G01X760022Y460331D02*
Y576199D01*
G01X726131Y424033D02*
Y411083D01*
G01X761724Y459626D02*
X726131Y424033D01*
G01X761724Y575494D02*
Y459626D01*
G01X779192Y428566D02*
X787236D01*
G01X771336Y420710D02*
X779192Y428566D01*
G01X771336Y418570D02*
Y420710D01*
G01X768366Y415600D02*
X771336Y418570D01*
G01X767605Y415600D02*
X768366D01*
G01X766200Y417005D02*
X767605Y415600D01*
G01X757950Y576939D02*
Y460666D01*
G01X778618Y429318D02*
X787652D01*
G01X768080Y418780D02*
X778618Y429318D01*
G01X779401Y411490D02*
X788120D01*
G01X777713Y413178D02*
X779401Y411490D01*
G01X768785Y413178D02*
X777713D01*
G01X767941Y412334D02*
X768785Y413178D01*
G01X765176Y412334D02*
X767941D01*
G01X763069Y414441D02*
X765176Y412334D01*
G01X768373Y414397D02*
X766394D01*
G01X772146Y418170D02*
X768373Y414397D01*
G01X772146Y420149D02*
Y418170D01*
G01X779777Y427780D02*
X772146Y420149D01*
G01X786890Y427780D02*
X779777D01*
G01X765700Y458764D02*
Y512256D01*
G01X770778Y453686D02*
X765700Y458764D01*
G01X770778Y453206D02*
Y453686D01*
G01X839757Y384227D02*
X770778Y453206D01*
G01X747985Y524365D02*
X752258Y528638D01*
G01X739065Y524365D02*
X747985D01*
G01X763794Y521986D02*
X763544Y522236D01*
G01X763794Y518298D02*
Y521986D01*
G01X766852Y515240D02*
X763794Y518298D01*
G01X747492Y525273D02*
X751085Y528866D01*
G01X738173Y525273D02*
X747492D01*
G01X726200Y513300D02*
X738173Y525273D01*
G01X765700Y512256D02*
X763706Y514250D01*
G01X752258Y581452D02*
X773599Y602793D01*
G01X752258Y528638D02*
Y581452D01*
G01X751085Y581506D02*
X759711Y590132D01*
G01X751085Y528866D02*
Y581506D01*
G01X737352Y592243D02*
Y581592D01*
G01D02*
X734400Y578640D01*
G01D02*
Y573489D01*
G01D02*
X733285Y572374D01*
G01D02*
X730091D01*
G01D02*
X728237Y574228D01*
G01X765741Y581918D02*
X900627D01*
G01X760022Y576199D02*
X765741Y581918D01*
G01X766446Y580216D02*
X761724Y575494D01*
G01X904100Y580216D02*
X766446D01*
G01X745879Y581400D02*
X758559Y594080D01*
G01X743937Y581400D02*
X745879D01*
G01X733596Y571059D02*
X743937Y581400D01*
G01X730342Y571059D02*
X733596D01*
G01X727925Y573476D02*
X730342Y571059D01*
G01X768550Y589950D02*
X765900Y587300D01*
G01X764631Y583620D02*
X757950Y576939D01*
G01X897251Y583620D02*
X764631D01*
G01X766553Y585724D02*
X769302Y588473D01*
G01X763974Y585724D02*
X766553D01*
G01X763450Y585200D02*
X763974Y585724D01*
G01X728549Y574980D02*
X729579Y573950D01*
G01D02*
X732600D01*
G01Y578470D02*
Y573950D01*
G01X736200Y582070D02*
X732600Y578470D01*
G01X736200Y609833D02*
Y582070D01*
G01X741389Y622390D02*
X734425Y615426D01*
G01X742411Y622390D02*
X741389D01*
G01X742562Y622541D02*
X742411Y622390D01*
G01X1043262Y622541D02*
X742562D01*
G01X773599Y602793D02*
X1032607D01*
G01X768913Y614225D02*
X1023675D01*
G01X759711Y605023D02*
X768913Y614225D01*
G01X759711Y590132D02*
Y605023D01*
G01X1041199Y617020D02*
X752520D01*
G01D02*
X750919Y615419D01*
G01D02*
Y605810D01*
G01D02*
X737352Y592243D01*
G01X767418Y615990D02*
X1040599D01*
G01X757650Y606222D02*
X767418Y615990D01*
G01X757650Y595400D02*
Y606222D01*
G01X755900Y593650D02*
X757650Y595400D01*
G01X743719Y620637D02*
X1042472D01*
G01X736582Y613500D02*
X743719Y620637D01*
G01X768158Y615100D02*
X1029067D01*
G01X758559Y605501D02*
X768158Y615100D01*
G01X758559Y594080D02*
Y605501D01*
G01X768550Y592372D02*
Y589950D01*
G01X777819Y601641D02*
X768550Y592372D01*
G01X1031759Y601641D02*
X777819D01*
G01X778131Y600889D02*
X1030411D01*
G01X769302Y592060D02*
X778131Y600889D01*
G01X769302Y588473D02*
Y592060D01*
G01X742874Y621789D02*
X1042950D01*
G01X735359Y614274D02*
X742874Y621789D01*
G01X744139Y617772D02*
X736200Y609833D01*
G01X1042077Y617772D02*
X744139D01*
G01X735021Y594120D02*
X729301Y588400D01*
G01X735021Y610284D02*
Y594120D01*
G01X744222Y619485D02*
X735021Y610284D01*
G01X1041994Y619485D02*
X744222D01*
G01X825576Y400038D02*
Y403516D01*
G01X840235Y385379D02*
X825576Y400038D01*
G01X848514Y385379D02*
X840235D01*
G01X845107Y354377D02*
X851570D01*
G01X834646Y364838D02*
X845107Y354377D01*
G01X820476Y364838D02*
X834646D01*
G01X818707Y366607D02*
X820476Y364838D01*
G01X818707Y376409D02*
Y366607D01*
G01X817246Y377870D02*
X818707Y376409D01*
G01X817246Y396322D02*
Y377870D01*
G01X813200Y400368D02*
X817246Y396322D01*
G01X813200Y405243D02*
Y400368D01*
G01X833297Y381640D02*
X851010Y363927D01*
G01X833297Y388473D02*
Y381640D01*
G01X801892Y419878D02*
X833297Y388473D01*
G01X834882Y381271D02*
X852112Y364041D01*
G01X834882Y387952D02*
Y381271D01*
G01X802204Y420630D02*
X834882Y387952D01*
G01X846552Y355448D02*
X851563D01*
G01X840300Y361700D02*
X846552Y355448D01*
G01X840300Y370131D02*
Y361700D01*
G01X837146Y373285D02*
X840300Y370131D01*
G01X823353Y373285D02*
X837146D01*
G01X818095Y378543D02*
X823353Y373285D01*
G01X818095Y397011D02*
Y378543D01*
G01X814500Y400606D02*
X818095Y397011D01*
G01X814500Y405126D02*
Y400606D01*
G01X832545Y388145D02*
X801564Y419126D01*
G01X832545Y381328D02*
Y388145D01*
G01X850258Y363615D02*
X832545Y381328D01*
G01X848036Y384227D02*
X839757D01*
G01X852853Y379409D02*
X848036Y384227D01*
G01X824653Y404439D02*
X821380D01*
G01X825576Y403516D02*
X824653Y404439D01*
G01X800913Y417530D02*
X813200Y405243D01*
G01X795224Y417530D02*
X800913D01*
G01X788432Y410738D02*
X795224Y417530D01*
G01X795924Y419878D02*
X801892D01*
G01X787236Y428566D02*
X795924Y419878D01*
G01X796340Y420630D02*
X802204D01*
G01X787652Y429318D02*
X796340Y420630D01*
G01X801326Y418300D02*
X814500Y405126D01*
G01X794930Y418300D02*
X801326D01*
G01X788120Y411490D02*
X794930Y418300D01*
G01X795544Y419126D02*
X786890Y427780D01*
G01X801564Y419126D02*
X795544D01*
G01X897973Y316668D02*
X854701Y359940D01*
G01X907878Y316668D02*
X897973D01*
G01X908246Y316300D02*
X907878Y316668D01*
G01X917379Y316300D02*
X908246D01*
G01X895650Y310297D02*
X914714D01*
G01X851570Y354377D02*
X895650Y310297D01*
G01X851010Y358129D02*
X895538Y313601D01*
G01X896214Y314522D02*
X918234D01*
G01X852112Y358624D02*
X896214Y314522D01*
G01X895962Y311049D02*
X915026D01*
G01X851563Y355448D02*
X895962Y311049D01*
G01X895593Y312482D02*
X850258Y357817D01*
G01X917577Y312482D02*
X895593D01*
G01X897495Y315516D02*
X853549Y359462D01*
G01X917682Y315516D02*
X897495D01*
G01X853837Y380056D02*
X848514Y385379D01*
G01X854006Y379886D02*
X853837Y380056D01*
G01X854701Y378149D02*
X854006Y379886D01*
G01X854701Y359940D02*
Y378149D01*
G01X851010Y363927D02*
Y358129D01*
G01X852112Y364041D02*
Y358624D01*
G01X850258Y357817D02*
Y363615D01*
G01X853350Y378170D02*
X852853Y379409D01*
G01X853549Y377673D02*
X853350Y378170D01*
G01X853549Y359462D02*
Y377673D01*
G01X903830Y585121D02*
Y592730D01*
G01X900627Y581918D02*
X903830Y585121D01*
G01X908862Y584978D02*
X904100Y580216D01*
G01X908862Y587038D02*
Y584978D01*
G01X908656Y587244D02*
X908862Y587038D01*
G01X908656Y592150D02*
Y587244D01*
G01X897553Y583922D02*
X897251Y583620D01*
G01X897557Y583922D02*
X897553D01*
G01X898597Y584962D02*
X897557Y583922D01*
G01X898597Y584966D02*
Y584962D01*
G01X898930Y585299D02*
X898597Y584966D01*
G01X898930Y595871D02*
Y585299D01*
G01X908292Y597192D02*
X1026878D01*
G01X903830Y592730D02*
X908292Y597192D01*
G01X911996Y595490D02*
X908656Y592150D01*
G01X901953Y598894D02*
X898930Y595871D01*
G01X1027583Y598894D02*
X901953D01*
G01X957283Y92657D02*
Y95100D01*
G01X961500Y109028D02*
X986700Y134228D01*
G01X961500Y99317D02*
Y109028D01*
G01X957283Y95100D02*
X961500Y99317D01*
G01X919628Y318549D02*
X917379Y316300D01*
G01X920364Y318549D02*
X919628D01*
G01X914714Y310297D02*
X917613Y307398D01*
G01X915026Y311049D02*
X918145Y307930D01*
G01X919823Y310236D02*
X917577Y312482D01*
G01X921155Y310236D02*
X919823D01*
G01X922031Y309360D02*
X921155Y310236D01*
G01X919896Y317730D02*
X917682Y315516D01*
G01X920226Y317730D02*
X919896D01*
G01X1026122Y595490D02*
X911996D01*
G01X1033036Y-800D02*
X1035392Y1556D01*
G01X1033021Y-800D02*
X1033036D01*
G01X1029538Y-4283D02*
X1033021Y-800D01*
G01X1021156Y-4283D02*
X1029538D01*
G01X1019972Y-5467D02*
X1021156Y-4283D01*
G01X1008367Y-5467D02*
X1019972D01*
G01X1006504Y-3604D02*
X1008367Y-5467D01*
G01X1003710Y-3604D02*
X1006504D01*
G01X999520Y586D02*
X1003710Y-3604D01*
G01X1003781Y-12099D02*
X1003249Y-12631D01*
G01X1018477Y-12099D02*
X1003781D01*
G01X1021147Y-9429D02*
X1018477Y-12099D01*
G01X1028419Y-9429D02*
X1021147D01*
G01X1031566Y-12576D02*
X1028419Y-9429D01*
G01X1266564Y-12576D02*
X1031566D01*
G01X1021518Y-6615D02*
X1028639D01*
G01X1020562Y-7571D02*
X1021518Y-6615D01*
G01X1020478Y-7571D02*
X1020562D01*
G01X1019849Y-8200D02*
X1020478Y-7571D01*
G01X1006050Y-8200D02*
X1019849D01*
G01X1002771Y-11479D02*
X1006050Y-8200D01*
G01X1032400Y17370D02*
X1034878Y19848D01*
G01X1032400Y7400D02*
Y17370D01*
G01X1026700Y1700D02*
X1032400Y7400D01*
G01X1028844Y-3531D02*
X1034683Y2308D01*
G01X1020369Y-3531D02*
X1028844D01*
G01X1019600Y-4300D02*
X1020369Y-3531D01*
G01X1009900Y-4300D02*
X1019600D01*
G01X1009200Y-3600D02*
X1009900Y-4300D01*
G01X1009200Y-62D02*
Y-3600D01*
G01X1007200Y1938D02*
X1009200Y-62D01*
G01X1029865Y-5035D02*
X1035704Y804D01*
G01X1021468Y-5035D02*
X1029865D01*
G01X1020284Y-6219D02*
X1021468Y-5035D01*
G01X1008055Y-6219D02*
X1020284D01*
G01X1006192Y-4356D02*
X1008055Y-6219D01*
G01X1003398Y-4356D02*
X1006192D01*
G01X999208Y-166D02*
X1003398Y-4356D01*
G01X1034200Y21100D02*
X1020400Y7300D01*
G01X986700Y134228D02*
Y181501D01*
G01X983400Y216300D02*
Y221400D01*
G01X985500Y214200D02*
X983400Y216300D01*
G01X985500Y200700D02*
Y214200D01*
G01X985850Y200350D02*
X985500Y200700D01*
G01X985850Y197950D02*
Y200350D01*
G01X985500Y197600D02*
X985850Y197950D01*
G01X985500Y182701D02*
Y197600D01*
G01X986700Y181501D02*
X985500Y182701D01*
G01X988446Y225446D02*
Y230560D01*
G01X986000Y223000D02*
X988446Y225446D01*
G01X985000Y223000D02*
X986000D01*
G01X983400Y221400D02*
X985000Y223000D01*
G01X1030120Y586593D02*
X1035362Y581351D01*
G01X1030120Y593950D02*
Y586593D01*
G01X1028370Y585936D02*
Y593242D01*
G01X1034657Y579649D02*
X1028370Y585936D01*
G01X1031823Y587297D02*
Y594654D01*
G01X1036067Y583053D02*
X1031823Y587297D01*
G01X1032607Y602793D02*
X1035100Y600300D01*
G01X1023675Y614225D02*
X1036448Y601452D01*
G01X1026878Y597192D02*
X1030120Y593950D01*
G01X1028370Y593242D02*
X1026122Y595490D01*
G01X1030487Y615100D02*
X1035985D01*
G01X1030430Y615157D02*
X1030487Y615100D01*
G01X1029124Y615157D02*
X1030430D01*
G01X1029067Y615100D02*
X1029124Y615157D01*
G01X1034252Y599148D02*
X1031759Y601641D01*
G01X1031823Y594654D02*
X1027583Y598894D01*
G01X1032904Y598396D02*
X1042094D01*
G01X1030411Y600889D02*
X1032904Y598396D01*
G01X1040744Y652D02*
X1268069D01*
G01X1039840Y1556D02*
X1040744Y652D01*
G01X1035392Y1556D02*
X1039840D01*
G01X1049573Y6156D02*
X1260656D01*
G01X1049429Y6300D02*
X1049573Y6156D01*
G01X1047100Y6300D02*
X1049429D01*
G01X1042400Y11000D02*
X1047100Y6300D01*
G01X1042400Y16832D02*
Y11000D01*
G01X1039384Y19848D02*
X1042400Y16832D01*
G01X1034878Y19848D02*
X1039384D01*
G01X1041056Y1404D02*
X1267757D01*
G01X1040152Y2308D02*
X1041056Y1404D01*
G01X1034683Y2308D02*
X1040152D01*
G01X1040432Y-100D02*
X1268381D01*
G01X1039528Y804D02*
X1040432Y-100D01*
G01X1035704Y804D02*
X1039528D01*
G01X1042576Y21100D02*
X1034200D01*
G01X1044217Y19459D02*
X1042576Y21100D01*
G01X1048371Y19459D02*
X1044217D01*
G01X1049286Y18544D02*
X1048371Y19459D01*
G01X1049286Y8214D02*
Y18544D01*
G01X1050092Y7408D02*
X1049286Y8214D01*
G01X1256008Y7408D02*
X1050092D01*
G01X1094254Y367922D02*
X1095455Y366721D01*
G01X1092948Y367922D02*
X1094254D01*
G01X1091747Y366721D02*
X1092948Y367922D01*
G01X1088695Y366721D02*
X1091747D01*
G01X1087494Y367922D02*
X1088695Y366721D01*
G01X1086188Y367922D02*
X1087494D01*
G01X1084987Y366721D02*
X1086188Y367922D01*
G01X1081936Y366721D02*
X1084987D01*
G01X1080735Y367922D02*
X1081936Y366721D01*
G01X1079429Y367922D02*
X1080735D01*
G01X1078228Y366721D02*
X1079429Y367922D01*
G01X1075280Y366721D02*
X1078228D01*
G01X1073741Y368260D02*
X1075280Y366721D01*
G01X1068542Y368260D02*
X1073741D01*
G01X1065843Y370959D02*
X1068542Y368260D01*
G01X1060963Y370959D02*
X1065843D01*
G01X1064440Y363160D02*
X1061055D01*
G01X1067000Y360600D02*
X1064440Y363160D01*
G01X1073990Y360600D02*
X1067000D01*
G01X1075380Y359210D02*
X1073990Y360600D01*
G01X1078852Y360122D02*
X1077940Y359210D01*
G01X1081931Y358926D02*
X1080735Y360122D01*
G01X1084786Y358926D02*
X1081931D01*
G01X1085982Y360122D02*
X1084786Y358926D01*
G01X1088690D02*
X1087494Y360122D01*
G01X1090879Y358926D02*
X1088690D01*
G01X1092386Y360433D02*
X1090879Y358926D01*
G01X1095548Y359322D02*
X1094437Y360433D01*
G01X1067031Y364400D02*
X1064371Y367060D01*
G01X1074100Y364400D02*
X1067031D01*
G01X1075960Y362540D02*
X1074100Y364400D01*
G01X1077386Y362540D02*
X1075960D01*
G01X1079097Y364251D02*
X1077386Y362540D01*
G01X1082548Y362666D02*
X1080963Y364251D01*
G01X1084446Y362666D02*
X1082548D01*
G01X1085871Y364091D02*
X1084446Y362666D01*
G01X1089886Y362230D02*
X1088025Y364091D01*
G01X1090930Y362230D02*
X1089886D01*
G01X1092728Y364028D02*
X1090930Y362230D01*
G01X1095087Y364028D02*
X1092728D01*
G01X1097044Y362071D02*
X1095087Y364028D01*
G01X1035362Y581351D02*
X1122818D01*
G01X1127746Y579649D02*
X1034657D01*
G01X1119281Y583053D02*
X1036067D01*
G01X1043413Y622390D02*
X1043262Y622541D01*
G01X1044252Y622390D02*
X1043413D01*
G01X1044983Y621659D02*
X1044252Y622390D01*
G01X1103659Y621659D02*
X1044983D01*
G01X1044424Y602854D02*
X1265503D01*
G01X1044063Y602493D02*
X1044424Y602854D01*
G01X1043497Y602493D02*
X1044063D01*
G01X1041304Y600300D02*
X1043497Y602493D01*
G01X1035100Y600300D02*
X1041304D01*
G01X1093138Y608288D02*
X1095612D01*
G01X1092558Y608868D02*
X1093138Y608288D01*
G01X1089624Y608868D02*
X1092558D01*
G01X1089044Y608288D02*
X1089624Y608868D01*
G01X1086330Y608288D02*
X1089044D01*
G01X1085750Y608868D02*
X1086330Y608288D01*
G01X1083023Y608868D02*
X1085750D01*
G01X1082443Y608288D02*
X1083023Y608868D01*
G01X1079617Y608288D02*
X1082443D01*
G01X1079037Y608868D02*
X1079617Y608288D01*
G01X1076264Y608868D02*
X1079037D01*
G01X1075684Y608288D02*
X1076264Y608868D01*
G01X1073048Y608288D02*
X1075684D01*
G01X1072468Y608868D02*
X1073048Y608288D01*
G01X1069713Y608868D02*
X1072468D01*
G01X1069133Y608288D02*
X1069713Y608868D01*
G01X1066336Y608288D02*
X1069133D01*
G01X1065756Y608868D02*
X1066336Y608288D01*
G01X1063048Y608868D02*
X1065756D01*
G01X1062468Y608288D02*
X1063048Y608868D01*
G01X1059656Y608288D02*
X1062468D01*
G01X1059076Y608868D02*
X1059656Y608288D01*
G01X1056351Y608868D02*
X1059076D01*
G01X1055771Y608288D02*
X1056351Y608868D01*
G01X1052880Y608288D02*
X1055771D01*
G01X1052300Y608868D02*
X1052880Y608288D01*
G01X1049968Y608868D02*
X1052300D01*
G01X1048223Y607123D02*
X1049968Y608868D01*
G01X1046497Y607123D02*
X1048223D01*
G01X1040826Y601452D02*
X1046497Y607123D01*
G01X1036448Y601452D02*
X1040826D01*
G01X1107299Y615899D02*
X1042320D01*
G01D02*
X1041199Y617020D01*
G01X1041842Y614747D02*
X1107778D01*
G01X1040599Y615990D02*
X1041842Y614747D01*
G01X1043754Y619355D02*
X1105325D01*
G01X1042472Y620637D02*
X1043754Y619355D01*
G01X1092740Y611440D02*
X1095984D01*
G01X1092281Y610981D02*
X1092740Y611440D01*
G01X1089628Y610981D02*
X1092281D01*
G01X1089169Y611440D02*
X1089628Y610981D01*
G01X1086478Y611440D02*
X1089169D01*
G01X1086119Y611081D02*
X1086478Y611440D01*
G01X1083297Y611081D02*
X1086119D01*
G01X1082938Y611440D02*
X1083297Y611081D01*
G01X1079172Y611440D02*
X1082938D01*
G01X1078813Y611081D02*
X1079172Y611440D01*
G01X1076423Y611081D02*
X1078813D01*
G01X1076064Y611440D02*
X1076423Y611081D01*
G01X1072620Y611440D02*
X1076064D01*
G01X1072164Y610984D02*
X1072620Y611440D01*
G01X1069679Y610984D02*
X1072164D01*
G01X1069223Y611440D02*
X1069679Y610984D01*
G01X1066211Y611440D02*
X1069223D01*
G01X1065852Y611081D02*
X1066211Y611440D01*
G01X1062850Y611081D02*
X1065852D01*
G01X1062491Y611440D02*
X1062850Y611081D01*
G01X1059536Y611440D02*
X1062491D01*
G01X1059177Y611081D02*
X1059536Y611440D01*
G01X1056395Y611081D02*
X1059177D01*
G01X1056036Y611440D02*
X1056395Y611081D01*
G01X1052904Y611440D02*
X1056036D01*
G01X1052546Y611082D02*
X1052904Y611440D01*
G01X1048918Y611082D02*
X1052546D01*
G01X1048560Y611440D02*
X1048918Y611082D01*
G01X1045859Y611440D02*
X1048560D01*
G01X1045501Y611082D02*
X1045859Y611440D01*
G01X1043638Y611082D02*
X1045501D01*
G01X1039620Y615100D02*
X1043638Y611082D01*
G01X1039609Y615100D02*
X1039620D01*
G01X1039528Y615181D02*
X1039609Y615100D01*
G01X1036066Y615181D02*
X1039528D01*
G01X1035985Y615100D02*
X1036066Y615181D01*
G01X1041782Y599148D02*
X1034252D01*
G01X1044736Y602102D02*
X1041782Y599148D01*
G01X1265191Y602102D02*
X1044736D01*
G01X1045048Y601350D02*
X1264879D01*
G01X1042094Y598396D02*
X1045048Y601350D01*
G01X1044232Y620507D02*
X1104137D01*
G01X1042950Y621789D02*
X1044232Y620507D01*
G01X1042398Y617451D02*
X1042077Y617772D01*
G01X1106681Y617451D02*
X1042398D01*
G01X1043276Y618203D02*
X1041994Y619485D01*
G01X1105803Y618203D02*
X1043276D01*
G01X1138500Y217500D02*
Y238500D01*
G01X1141500Y214500D02*
X1138500Y217500D01*
G01X1144500Y214500D02*
X1141500D01*
G01X1146813Y212187D02*
X1144500Y214500D01*
G01X1148848Y212187D02*
X1146813D01*
G01X1150100Y210935D02*
X1148848Y212187D01*
G01X1150100Y208831D02*
Y210935D01*
G01X1150763Y208168D02*
X1150100Y208831D01*
G01X1152269Y208168D02*
X1150763D01*
G01X1160087Y200350D02*
X1152269Y208168D01*
G01X1137404Y239596D02*
X1133040D01*
G01X1138500Y238500D02*
X1137404Y239596D01*
G01X1155000Y220000D02*
X1157000Y218000D01*
G01X1153377Y220000D02*
X1155000D01*
G01X1151377Y222000D02*
X1153377Y220000D01*
G01X1149948Y222000D02*
X1151377D01*
G01X1148138Y223810D02*
X1149948Y222000D01*
G01X1147596Y223810D02*
X1148138D01*
G01X1145900Y225506D02*
X1147596Y223810D01*
G01X1145900Y273096D02*
Y225506D01*
G01X1144300Y274696D02*
X1145900Y273096D01*
G01X1144851Y397658D02*
X1155681Y408488D01*
G01X1144028Y397658D02*
X1144851D01*
G01X1142589Y396219D02*
X1144028Y397658D01*
G01X1142589Y373275D02*
Y396219D01*
G01X1141448Y372134D02*
X1142589Y373275D01*
G01X1140213Y372134D02*
X1141448D01*
G01X1139200Y371121D02*
X1140213Y372134D01*
G01X1126453Y364218D02*
X1127968D01*
G01X1124640Y366031D02*
X1126453Y364218D01*
G01X1123311Y366031D02*
X1124640D01*
G01X1121466Y364186D02*
X1123311Y366031D01*
G01X1120151Y364186D02*
X1121466D01*
G01X1118236Y366101D02*
X1120151Y364186D01*
G01X1116699Y366101D02*
X1118236D01*
G01X1115227Y364629D02*
X1116699Y366101D01*
G01X1112696Y364629D02*
X1115227D01*
G01X1111255Y366070D02*
X1112696Y364629D01*
G01X1109877Y366070D02*
X1111255D01*
G01X1107851Y364044D02*
X1109877Y366070D01*
G01X1106314Y364044D02*
X1107851D01*
G01X1104335Y366023D02*
X1106314Y364044D01*
G01X1102766Y366023D02*
X1104335D01*
G01X1101214Y364471D02*
X1102766Y366023D01*
G01X1099505Y364471D02*
X1101214D01*
G01X1097255Y366721D02*
X1099505Y364471D01*
G01X1095455Y366721D02*
X1097255D01*
G01X1149410Y388367D02*
Y370080D01*
G01X1150743Y389700D02*
X1149410Y388367D01*
G01X1151285Y389700D02*
X1150743D01*
G01X1152800Y391215D02*
X1151285Y389700D01*
G01X1152800Y399769D02*
Y391215D01*
G01X1158067Y405036D02*
X1152800Y399769D01*
G01X1098509Y362071D02*
X1097044D01*
G01X1099708Y360872D02*
X1098509Y362071D01*
G01X1101889Y360872D02*
X1099708D01*
G01X1103017Y362000D02*
X1101889Y360872D01*
G01X1106468D02*
X1105340Y362000D01*
G01X1108052Y360872D02*
X1106468D01*
G01X1109280Y362100D02*
X1108052Y360872D01*
G01X1112000Y362100D02*
X1109280D01*
G01X1113228Y360872D02*
X1112000Y362100D01*
G01X1114712Y360872D02*
X1113228D01*
G01X1115911Y362071D02*
X1114712Y360872D01*
G01X1117914Y362071D02*
X1115911D01*
G01X1119113Y360872D02*
X1117914Y362071D01*
G01X1121573Y360872D02*
X1119113D01*
G01X1122772Y362071D02*
X1121573Y360872D01*
G01X1125070Y362071D02*
X1122772D01*
G01X1126787Y360354D02*
X1125070Y362071D01*
G01X1128624Y360354D02*
X1126787D01*
G01X1130080Y358898D02*
X1128624Y360354D01*
G01X1135386Y360570D02*
X1133180D01*
G01X1136887Y362071D02*
X1135386Y360570D01*
G01X1138261Y362071D02*
X1136887D01*
G01X1140962Y364772D02*
X1138261Y362071D01*
G01X1141573Y364772D02*
X1140962D01*
G01X1142725Y365924D02*
X1141573Y364772D01*
G01X1142725Y368949D02*
Y365924D01*
G01X1143647Y369871D02*
X1142725Y368949D01*
G01X1144953Y369871D02*
X1143647D01*
G01X1146000Y370918D02*
X1144953Y369871D01*
G01X1146000Y390700D02*
Y370918D01*
G01X1147000Y391700D02*
X1146000Y390700D01*
G01X1148364Y391700D02*
X1147000D01*
G01X1149350Y392686D02*
X1148364Y391700D01*
G01X1149350Y396650D02*
Y392686D01*
G01X1150790Y398090D02*
X1149350Y396650D01*
G01X1150790Y400858D02*
Y398090D01*
G01X1156584Y406652D02*
X1150790Y400858D01*
G01X1155681Y408488D02*
X1163870D01*
G01X1164441Y406652D02*
X1156584D01*
G01X1122818Y581351D02*
X1129728Y588261D01*
G01X1133075Y584978D02*
X1127746Y579649D01*
G01X1133075Y586450D02*
Y584978D01*
G01X1132869Y586656D02*
X1133075Y586450D01*
G01X1132869Y592150D02*
Y586656D01*
G01X1126176Y589948D02*
X1119281Y583053D01*
G01X1105703Y623703D02*
X1103659Y621659D01*
G01X1295847Y623703D02*
X1105703D01*
G01X1113745Y614233D02*
X1265810D01*
G01X1112300Y612788D02*
X1113745Y614233D01*
G01X1112300Y609851D02*
Y612788D01*
G01X1111173Y608724D02*
X1112300Y609851D01*
G01X1099141Y608724D02*
X1111173D01*
G01X1099069Y608796D02*
X1099141Y608724D01*
G01X1096120Y608796D02*
X1099069D01*
G01X1095612Y608288D02*
X1096120Y608796D01*
G01X1267244Y617689D02*
X1109089D01*
G01D02*
X1107299Y615899D01*
G01X1132505Y597192D02*
X1186808D01*
G01X1129700Y594387D02*
X1132505Y597192D01*
G01X1129700Y592178D02*
Y594387D01*
G01X1129728Y592150D02*
X1129700Y592178D01*
G01X1129728Y588261D02*
Y592150D01*
G01X1109568Y616537D02*
X1266766D01*
G01X1107778Y614747D02*
X1109568Y616537D01*
G01X1136209Y595490D02*
X1132869Y592150D01*
G01X1182578Y595490D02*
X1136209D01*
G01X1107115Y621145D02*
X1285814D01*
G01X1105325Y619355D02*
X1107115Y621145D01*
G01X1112839Y615385D02*
X1266288D01*
G01X1108527Y611073D02*
X1112839Y615385D01*
G01X1106403Y611073D02*
X1108527D01*
G01X1105600Y611876D02*
X1106403Y611073D01*
G01X1103220Y611876D02*
X1105600D01*
G01X1102367Y611023D02*
X1103220Y611876D01*
G01X1096401Y611023D02*
X1102367D01*
G01X1095984Y611440D02*
X1096401Y611023D01*
G01X1126176Y593270D02*
Y589948D01*
G01X1131976Y599070D02*
X1126176Y593270D01*
G01X1190219Y599070D02*
X1131976D01*
G01X1105927Y622297D02*
X1295304D01*
G01X1104137Y620507D02*
X1105927Y622297D01*
G01X1107671Y618441D02*
X1106681Y617451D01*
G01X1267556Y618441D02*
X1107671D01*
G01X1107593Y619993D02*
X1105803Y618203D01*
G01X1285336Y619993D02*
X1107593D01*
G01X1239620Y132810D02*
X1175629Y196801D01*
G01X1168450Y200350D02*
X1160087D01*
G01X1171999Y196801D02*
X1168450Y200350D01*
G01X1175629Y196801D02*
X1171999D01*
G01X1175500Y204500D02*
X1233463Y146537D01*
G01X1173000Y204500D02*
X1175500D01*
G01X1169000Y208500D02*
X1173000Y204500D01*
G01X1167500Y208500D02*
X1169000D01*
G01X1165500Y210500D02*
X1167500Y208500D01*
G01X1164000Y210500D02*
X1165500D01*
G01X1163000Y211500D02*
X1164000Y210500D01*
G01X1163000Y215000D02*
Y211500D01*
G01X1161831Y216169D02*
X1163000Y215000D01*
G01X1160331Y216169D02*
X1161831D01*
G01X1158500Y218000D02*
X1160331Y216169D01*
G01X1170796Y268847D02*
X1170452Y269191D01*
G01X1174719Y268847D02*
X1170796D01*
G01X1157000Y218000D02*
X1158500D01*
G01X1180869Y418702D02*
X1243799Y481632D01*
G01X1174084Y418702D02*
X1180869D01*
G01X1163870Y408488D02*
X1174084Y418702D01*
G01X1165236Y405036D02*
X1158067D01*
G01X1175498Y415298D02*
X1165236Y405036D01*
G01X1182279Y415298D02*
X1175498D01*
G01X1245209Y478228D02*
X1182279Y415298D01*
G01X1174789Y417000D02*
X1164441Y406652D01*
G01X1181574Y417000D02*
X1174789D01*
G01X1244504Y479930D02*
X1181574Y417000D01*
G01X1196027Y580200D02*
X1252800D01*
G01X1190500Y585727D02*
X1196027Y580200D01*
G01X1190500Y593500D02*
Y585727D01*
G01X1185918Y585231D02*
Y592150D01*
G01X1193149Y578000D02*
X1185918Y585231D01*
G01X1250857Y578000D02*
X1193149D01*
G01X1195700Y585730D02*
Y593589D01*
G01X1198930Y582500D02*
X1195700Y585730D01*
G01X1253050Y582500D02*
X1198930D01*
G01X1186808Y597192D02*
X1190500Y593500D01*
G01X1185918Y592150D02*
X1182578Y595490D01*
G01X1195700Y593589D02*
X1190219Y599070D01*
G01X1274039Y6622D02*
Y88239D01*
G01X1268069Y652D02*
X1274039Y6622D01*
G01X1275100Y-7300D02*
X1267465Y-14935D01*
G01X1275100Y-1571D02*
Y-7300D01*
G01X1278247Y1576D02*
X1275100Y-1571D01*
G01X1278247Y73723D02*
Y1576D01*
G01X1279399Y1098D02*
Y73245D01*
G01X1276600Y-1701D02*
X1279399Y1098D01*
G01X1276600Y-7500D02*
Y-1701D01*
G01X1267860Y-16240D02*
X1276600Y-7500D01*
G01X1272600Y-6540D02*
X1266564Y-12576D01*
G01X1272600Y-800D02*
Y-6540D01*
G01X1275943Y2543D02*
X1272600Y-800D01*
G01X1275943Y74679D02*
Y2543D01*
G01X1255118Y16999D02*
Y27899D01*
G01X1256800Y29581D02*
Y48900D01*
G01X1255118Y27899D02*
X1256800Y29581D01*
G01X1279200Y-2570D02*
X1284222Y2452D01*
G01X1279200Y-7546D02*
Y-2570D01*
G01X1279152Y-7594D02*
X1279200Y-7546D01*
G01X1279152Y-11548D02*
Y-7594D01*
G01X1277627Y-13073D02*
X1279152Y-11548D01*
G01X1274439Y-13073D02*
X1277627D01*
G01X1268968Y-18544D02*
X1274439Y-13073D01*
G01X1263400Y8900D02*
Y93600D01*
G01X1260656Y6156D02*
X1263400Y8900D01*
G01X1278000Y-2070D02*
X1280551Y481D01*
G01X1278000Y-11070D02*
Y-2070D01*
G01X1277149Y-11921D02*
X1278000Y-11070D01*
G01X1273961Y-11921D02*
X1277149D01*
G01X1268490Y-17392D02*
X1273961Y-11921D01*
G01X1273287Y6934D02*
Y89587D01*
G01X1267757Y1404D02*
X1273287Y6934D01*
G01X1273948Y-6822D02*
X1266987Y-13783D01*
G01X1273948Y-1093D02*
Y-6822D01*
G01X1277095Y2054D02*
X1273948Y-1093D01*
G01X1277095Y74201D02*
Y2054D01*
G01X1280676Y-16824D02*
X1275854Y-21646D01*
G01X1274791Y6310D02*
Y87644D01*
G01X1268381Y-100D02*
X1274791Y6310D01*
G01X1253500Y32500D02*
X1255118Y34118D01*
G01X1253500Y10775D02*
Y32500D01*
G01X1255118Y9157D02*
X1253500Y10775D01*
G01X1256700Y8100D02*
X1256008Y7408D01*
G01X1256700Y12200D02*
Y8100D01*
G01X1260200Y15700D02*
X1256700Y12200D01*
G01X1260200Y94200D02*
Y15700D01*
G01X1274039Y88239D02*
X1285900Y100100D01*
G01X1283150Y78626D02*
X1278247Y73723D01*
G01X1279399Y73245D02*
X1283628Y77474D01*
G01X1282200Y80936D02*
X1275943Y74679D01*
G01X1255118Y93338D02*
X1259780Y98000D01*
G01X1255118Y92599D02*
Y93338D01*
G01Y50582D02*
Y54799D01*
G01X1256800Y48900D02*
X1255118Y50582D01*
G01Y54799D02*
Y65699D01*
G01Y90582D02*
Y92599D01*
G01X1256700Y89000D02*
X1255118Y90582D01*
G01X1256700Y67281D02*
Y89000D01*
G01X1255118Y65699D02*
X1256700Y67281D01*
G01X1263400Y93600D02*
X1264500Y94700D01*
G01X1273287Y89587D02*
X1285000Y101300D01*
G01X1282678Y79784D02*
X1277095Y74201D01*
G01X1274791Y87644D02*
X1286295Y99148D01*
G01X1255118Y73857D02*
Y84757D01*
G01Y34118D02*
Y36057D01*
G01X1253500Y93350D02*
X1259450Y99300D01*
G01X1253500Y86375D02*
Y93350D01*
G01X1255118Y84757D02*
X1253500Y86375D01*
G01X1255118Y68718D02*
Y73857D01*
G01X1253500Y67100D02*
X1255118Y68718D01*
G01X1253500Y48575D02*
Y67100D01*
G01X1255118Y46957D02*
X1253500Y48575D01*
G01X1255118Y36057D02*
Y46957D01*
G01X1262000Y96000D02*
X1260200Y94200D01*
G01X1267400Y98000D02*
X1271500Y102100D01*
G01X1259780Y98000D02*
X1267400D01*
G01X1284640Y106200D02*
X1277600D01*
G01X1245894Y132810D02*
X1239620D01*
G01X1248244Y130460D02*
X1245894Y132810D01*
G01X1249025Y130460D02*
X1248244D01*
G01X1276600Y107800D02*
X1283840D01*
G01X1276000Y107200D02*
X1276600Y107800D01*
G01X1276000Y99920D02*
Y107200D01*
G01X1275470Y99390D02*
X1276000Y99920D01*
G01X1277247Y111266D02*
X1281192Y112900D01*
G01X1275879Y109898D02*
X1277247Y111266D01*
G01X1274848Y107409D02*
X1275879Y109898D01*
G01X1274848Y101248D02*
Y107409D01*
G01X1273400Y99800D02*
X1274848Y101248D01*
G01X1273400Y97100D02*
Y99800D01*
G01X1271000Y94700D02*
X1273400Y97100D01*
G01X1264500Y94700D02*
X1271000D01*
G01X1265700Y99300D02*
X1268500Y102100D01*
G01X1259450Y99300D02*
X1265700D01*
G01X1270499Y96000D02*
X1262000D01*
G01X1271926Y97427D02*
X1270499Y96000D01*
G01X1271926Y100126D02*
Y97427D01*
G01X1273076Y101276D02*
X1271926Y100126D01*
G01X1273076Y105343D02*
Y101276D01*
G01X1272119Y106300D02*
X1273076Y105343D01*
G01X1263100Y106300D02*
X1272119D01*
G01X1262300Y107100D02*
X1263100Y106300D01*
G01X1258600Y107100D02*
X1262300D01*
G01X1255700Y110000D02*
X1258600Y107100D01*
G01X1255700Y117900D02*
Y110000D01*
G01X1256349Y118549D02*
X1255700Y117900D01*
G01X1258049Y118549D02*
X1256349D01*
G01X1259700Y120200D02*
X1258049Y118549D01*
G01X1259700Y130400D02*
Y120200D01*
G01X1250700Y139400D02*
X1259700Y130400D01*
G01X1247637Y139400D02*
X1250700D01*
G01X1240500Y146537D02*
X1247637Y139400D01*
G01X1233463Y146537D02*
X1240500D01*
G01X1271480Y361240D02*
X1300304Y332416D01*
G01X1271480Y391706D02*
Y361240D01*
G01X1271352Y391834D02*
X1271480Y391706D01*
G01X1271352Y453136D02*
Y391834D01*
G01X1274349Y362893D02*
X1303644Y333598D01*
G01X1274349Y452746D02*
Y362893D01*
G01X1268435Y391559D02*
Y453703D01*
G01X1269224Y390770D02*
X1268435Y391559D01*
G01X1269224Y360362D02*
Y390770D01*
G01X1269223Y360361D02*
X1269224Y360362D01*
G01X1269223Y359739D02*
Y360361D01*
G01X1269224Y359737D02*
X1269223Y359739D01*
G01X1269224Y359376D02*
Y359737D01*
G01X1297370Y331230D02*
X1269224Y359376D01*
G01X1279491Y362856D02*
X1307252Y335095D01*
G01X1279491Y453466D02*
Y362856D01*
G01X1243755Y402365D02*
X1246010Y400110D01*
G01X1243755Y440036D02*
Y402365D01*
G01X1277387Y361983D02*
X1305148Y334222D01*
G01X1277387Y453490D02*
Y361983D01*
G01X1241550Y400188D02*
Y440587D01*
G01X1243399Y398339D02*
X1241550Y400188D01*
G01X1276635Y361671D02*
X1304396Y333910D01*
G01X1276635Y453935D02*
Y361671D01*
G01X1273597Y360753D02*
Y453350D01*
G01X1301456Y332894D02*
X1273597Y360753D01*
G01X1278539Y362461D02*
X1306300Y334700D01*
G01X1278539Y453578D02*
Y362461D01*
G01X1270600Y391522D02*
Y453448D01*
G01X1270728Y391394D02*
X1270600Y391522D01*
G01X1270728Y360362D02*
Y391394D01*
G01X1299153Y331937D02*
X1270728Y360362D01*
G01X1249230Y402039D02*
X1245513Y405756D01*
G01X1249230Y402022D02*
Y402039D01*
G01X1239698Y397515D02*
Y470097D01*
G01X1241113Y396100D02*
X1239698Y397515D01*
G01X1245100Y396100D02*
X1241113D01*
G01X1248900Y399900D02*
X1245100Y396100D01*
G01X1257400Y399900D02*
X1248900D01*
G01X1267320Y389980D02*
X1257400Y399900D01*
G01X1267320Y361152D02*
Y389980D01*
G01X1267319Y361151D02*
X1267320Y361152D01*
G01X1267319Y359289D02*
Y361151D01*
G01X1267320Y359287D02*
X1267319Y359289D01*
G01X1267320Y358472D02*
Y359287D01*
G01X1293985Y331807D02*
X1267320Y358472D01*
G01X1268472Y358951D02*
X1295974Y331448D01*
G01X1268472Y359559D02*
Y358951D01*
G01X1268471Y359561D02*
X1268472Y359559D01*
G01X1268471Y360673D02*
Y359561D01*
G01X1268472Y360674D02*
X1268471Y360673D01*
G01X1268472Y390458D02*
Y360674D01*
G01X1266979Y391951D02*
X1268472Y390458D01*
G01X1266979Y453311D02*
Y391951D01*
G01X1269976Y359961D02*
X1298400Y331537D01*
G01X1269976Y391082D02*
Y359961D01*
G01X1269848Y391210D02*
X1269976Y391082D01*
G01X1269848Y453760D02*
Y391210D01*
G01X1277257Y459041D02*
X1271352Y453136D01*
G01X1277257Y466146D02*
Y459041D01*
G01X1279419Y457816D02*
X1274349Y452746D01*
G01X1279419Y465828D02*
Y457816D01*
G01X1274493Y459761D02*
Y467083D01*
G01X1268435Y453703D02*
X1274493Y459761D01*
G01X1282638Y456613D02*
X1279491Y453466D01*
G01X1252918Y449199D02*
X1243755Y440036D01*
G01X1252918Y449697D02*
Y449199D01*
G01X1251328Y451287D02*
X1252918Y449697D01*
G01X1251328Y451785D02*
Y451287D01*
G01X1251826Y452283D02*
X1251328Y451785D01*
G01X1252324Y452283D02*
X1251826D01*
G01X1253914Y450693D02*
X1252324Y452283D01*
G01X1254412Y450693D02*
X1253914D01*
G01X1254910Y451191D02*
X1254412Y450693D01*
G01X1254910Y451689D02*
Y451191D01*
G01X1253320Y453279D02*
X1254910Y451689D01*
G01X1253320Y453777D02*
Y453279D01*
G01X1253818Y454275D02*
X1253320Y453777D01*
G01X1254316Y454275D02*
X1253818D01*
G01X1255906Y452685D02*
X1254316Y454275D01*
G01X1256404Y452685D02*
X1255906D01*
G01X1256902Y453183D02*
X1256404Y452685D01*
G01X1256902Y453681D02*
Y453183D01*
G01X1255312Y455271D02*
X1256902Y453681D01*
G01X1255312Y455769D02*
Y455271D01*
G01X1255810Y456267D02*
X1255312Y455769D01*
G01X1256308Y456267D02*
X1255810D01*
G01X1257898Y454677D02*
X1256308Y456267D01*
G01X1258396Y454677D02*
X1257898D01*
G01X1258894Y455175D02*
X1258396Y454677D01*
G01X1258894Y455673D02*
Y455175D01*
G01X1257304Y457263D02*
X1258894Y455673D01*
G01X1257304Y457761D02*
Y457263D01*
G01X1257802Y458259D02*
X1257304Y457761D01*
G01X1258300Y458259D02*
X1257802D01*
G01X1259890Y456669D02*
X1258300Y458259D01*
G01X1260388Y456669D02*
X1259890D01*
G01X1260886Y457167D02*
X1260388Y456669D01*
G01X1260886Y457665D02*
Y457167D01*
G01X1259296Y459255D02*
X1260886Y457665D01*
G01X1259296Y459753D02*
Y459255D01*
G01X1259794Y460251D02*
X1259296Y459753D01*
G01X1260292Y460251D02*
X1259794D01*
G01X1261882Y458661D02*
X1260292Y460251D01*
G01X1262380Y458661D02*
X1261882D01*
G01X1268998Y465279D02*
X1262380Y458661D01*
G01X1281134Y457237D02*
X1277387Y453490D01*
G01X1256139Y464005D02*
X1265234Y473100D01*
G01X1256139Y463507D02*
Y464005D01*
G01X1258134Y461512D02*
X1256139Y463507D01*
G01X1258134Y461014D02*
Y461512D01*
G01X1257636Y460516D02*
X1258134Y461014D01*
G01X1257138Y460516D02*
X1257636D01*
G01X1255143Y462511D02*
X1257138Y460516D01*
G01X1254645Y462511D02*
X1255143D01*
G01X1254147Y462013D02*
X1254645Y462511D01*
G01X1254147Y461515D02*
Y462013D01*
G01X1256142Y459520D02*
X1254147Y461515D01*
G01X1256142Y459022D02*
Y459520D01*
G01X1255644Y458524D02*
X1256142Y459022D01*
G01X1255146Y458524D02*
X1255644D01*
G01X1253151Y460519D02*
X1255146Y458524D01*
G01X1252653Y460519D02*
X1253151D01*
G01X1252155Y460021D02*
X1252653Y460519D01*
G01X1252155Y459523D02*
Y460021D01*
G01X1254150Y457528D02*
X1252155Y459523D01*
G01X1254150Y457030D02*
Y457528D01*
G01X1253652Y456532D02*
X1254150Y457030D01*
G01X1253154Y456532D02*
X1253652D01*
G01X1251159Y458527D02*
X1253154Y456532D01*
G01X1250661Y458527D02*
X1251159D01*
G01X1250163Y458029D02*
X1250661Y458527D01*
G01X1250163Y457531D02*
Y458029D01*
G01X1252158Y455536D02*
X1250163Y457531D01*
G01X1252158Y455038D02*
Y455536D01*
G01X1251660Y454540D02*
X1252158Y455038D01*
G01X1251162Y454540D02*
X1251660D01*
G01X1249167Y456535D02*
X1251162Y454540D01*
G01X1248669Y456535D02*
X1249167D01*
G01X1248171Y456037D02*
X1248669Y456535D01*
G01X1248171Y455539D02*
Y456037D01*
G01X1250166Y453544D02*
X1248171Y455539D01*
G01X1250166Y453046D02*
Y453544D01*
G01X1248916Y451796D02*
X1250166Y453046D01*
G01X1248916Y447953D02*
Y451796D01*
G01X1241550Y440587D02*
X1248916Y447953D01*
G01X1280382Y457682D02*
X1276635Y453935D01*
G01X1278009Y457762D02*
Y465618D01*
G01X1273597Y453350D02*
X1278009Y457762D01*
G01X1281886Y456925D02*
X1278539Y453578D01*
G01X1276505Y459353D02*
Y466665D01*
G01X1270600Y453448D02*
X1276505Y459353D01*
G01X1270700Y464574D02*
Y467050D01*
G01X1245513Y439387D02*
X1270700Y464574D01*
G01X1245513Y405756D02*
Y439387D01*
G01X1273700Y460032D02*
X1266979Y453311D01*
G01X1273700Y467430D02*
Y460032D01*
G01X1275753Y459665D02*
X1269848Y453760D01*
G01X1275753Y467113D02*
Y459665D01*
G01X1267306Y503680D02*
X1269209Y501777D01*
G01X1261384Y503680D02*
X1267306D01*
G01X1255102Y497398D02*
X1261384Y503680D01*
G01X1255102Y495882D02*
Y497398D01*
G01X1255101Y495881D02*
X1255102Y495882D01*
G01X1255101Y495481D02*
Y495881D01*
G01X1253790Y494170D02*
X1255101Y495481D01*
G01X1253790Y484960D02*
Y494170D01*
G01X1250462Y481632D02*
X1253790Y484960D01*
G01X1243799Y481632D02*
X1250462D01*
G01X1279475Y468364D02*
X1277257Y466146D01*
G01X1279475Y485564D02*
Y468364D01*
G01X1284790Y490879D02*
X1279475Y485564D01*
G01X1278521Y506474D02*
X1280562Y504433D01*
G01X1278521Y515679D02*
Y506474D01*
G01X1274988Y519212D02*
X1278521Y515679D01*
G01X1274988Y534120D02*
Y519212D01*
G01X1280979Y467388D02*
X1279419Y465828D01*
G01X1280025Y507098D02*
X1282066Y505057D01*
G01X1280025Y517137D02*
Y507098D01*
G01X1281101Y518213D02*
X1280025Y517137D01*
G01X1276492Y528403D02*
X1281101Y523794D01*
G01X1277987Y491571D02*
X1277978D01*
G01X1277987Y491562D02*
Y491571D01*
G01X1277175Y490750D02*
X1277987Y491562D01*
G01X1277175Y469765D02*
Y490750D01*
G01X1274493Y467083D02*
X1277175Y469765D01*
G01X1249193Y494693D02*
Y491308D01*
G01X1251500Y497000D02*
X1249193Y494693D01*
G01X1251500Y501500D02*
Y497000D01*
G01X1253347Y503347D02*
X1251500Y501500D01*
G01X1253347Y511347D02*
Y503347D01*
G01X1255120Y513120D02*
X1253347Y511347D01*
G01X1255120Y518000D02*
Y513120D01*
G01X1268998Y470902D02*
Y465279D01*
G01X1266936Y472964D02*
X1268998Y470902D01*
G01X1266936Y488984D02*
Y472964D01*
G01X1274437Y496485D02*
X1266936Y488984D01*
G01X1274437Y502178D02*
Y496485D01*
G01X1268033Y508582D02*
X1274437Y502178D01*
G01X1265249Y508582D02*
X1268033D01*
G01X1265248Y508581D02*
X1265249Y508582D01*
G01X1264504Y508581D02*
X1265248D01*
G01X1263581Y509504D02*
X1264504Y508581D01*
G01X1263581Y548416D02*
Y509504D01*
G01X1260235D02*
Y548415D01*
G01X1262860Y506879D02*
X1260235Y509504D01*
G01X1267293Y506879D02*
X1262860D01*
G01X1272714Y501458D02*
X1267293Y506879D01*
G01X1272714Y497169D02*
Y501458D01*
G01X1265234Y489689D02*
X1272714Y497169D01*
G01X1265234Y473100D02*
Y489689D01*
G01X1277244Y528715D02*
X1281853Y524106D01*
G01X1280349Y523482D02*
X1275740Y528091D01*
G01X1279273Y517449D02*
X1280349Y518525D01*
G01X1279273Y506786D02*
Y517449D01*
G01X1281314Y504745D02*
X1279273Y506786D01*
G01X1280227Y485252D02*
X1285542Y490567D01*
G01X1278009Y465618D02*
X1280227Y467836D01*
G01X1274236Y518264D02*
Y533808D01*
G01X1276991Y515509D02*
X1274236Y518264D01*
G01X1276991Y506940D02*
Y515509D01*
G01X1279810Y504121D02*
X1276991Y506940D01*
G01X1279810Y501880D02*
Y504121D01*
G01X1284038Y497652D02*
X1279810Y501880D01*
G01X1278691Y485844D02*
X1284038Y491191D01*
G01X1278691Y468851D02*
Y485844D01*
G01X1276505Y466665D02*
X1278691Y468851D01*
G01X1266800Y512314D02*
Y548581D01*
G01X1276161Y502953D02*
X1266800Y512314D01*
G01X1276161Y495802D02*
Y502953D01*
G01X1274240Y493881D02*
X1276161Y495802D01*
G01X1274240Y490790D02*
Y493881D01*
G01X1274406Y490624D02*
X1274240Y490790D01*
G01X1274406Y470756D02*
Y490624D01*
G01X1270700Y467050D02*
X1274406Y470756D01*
G01X1263382Y497014D02*
X1262843Y497553D01*
G01X1263382Y482028D02*
Y497014D01*
G01X1257729Y476375D02*
X1263382Y482028D01*
G01X1256195Y476375D02*
X1257729D01*
G01X1256194Y476376D02*
X1256195Y476375D01*
G01X1245977Y476376D02*
X1256194D01*
G01X1239698Y470097D02*
X1245977Y476376D01*
G01X1276258Y469988D02*
X1273700Y467430D01*
G01X1276258Y491392D02*
Y469988D01*
G01X1276092Y491558D02*
X1276258Y491392D01*
G01X1276092Y493113D02*
Y491558D01*
G01X1277079Y494100D02*
X1276092Y493113D01*
G01X1281175Y494100D02*
X1277079D01*
G01X1278306Y501256D02*
X1282534Y497028D01*
G01X1278306Y503497D02*
Y501256D01*
G01X1273000Y508803D02*
X1278306Y503497D01*
G01X1273000Y512000D02*
Y508803D01*
G01X1272068Y512932D02*
X1273000Y512000D01*
G01X1272068Y533768D02*
Y512932D01*
G01X1277939Y469299D02*
X1275753Y467113D01*
G01X1277939Y486156D02*
Y469299D01*
G01X1283286Y491503D02*
X1277939Y486156D01*
G01X1279058Y501568D02*
X1283286Y497340D01*
G01X1279058Y503809D02*
Y501568D01*
G01X1276239Y506628D02*
X1279058Y503809D01*
G01X1276239Y515197D02*
Y506628D01*
G01X1273484Y517952D02*
X1276239Y515197D01*
G01X1273484Y533416D02*
Y517952D01*
G01X1249414Y488913D02*
X1248474D01*
G01X1250769Y490268D02*
X1249414Y488913D01*
G01X1250769Y493769D02*
Y490268D01*
G01X1253249Y496249D02*
X1250769Y493769D01*
G01X1253249Y501619D02*
Y496249D01*
G01X1255120Y503490D02*
X1253249Y501619D01*
G01X1255120Y510158D02*
Y503490D01*
G01X1256962Y478228D02*
X1245209D01*
G01X1261530Y482796D02*
X1256962Y478228D01*
G01X1261530Y494690D02*
Y482796D01*
G01X1261032Y495188D02*
X1261530Y494690D01*
G01X1261032Y498387D02*
Y495188D01*
G01X1262526Y499881D02*
X1261032Y498387D01*
G01X1264418Y499881D02*
X1262526D01*
G01X1266272Y498027D02*
X1264418Y499881D01*
G01X1270616Y498027D02*
X1266272D01*
G01X1271105Y498516D02*
X1270616Y498027D01*
G01X1256257Y479930D02*
X1244504D01*
G01X1259828Y483501D02*
X1256257Y479930D01*
G01X1259828Y493762D02*
Y483501D01*
G01X1259237Y494353D02*
X1259828Y493762D01*
G01X1259237Y499119D02*
Y494353D01*
G01X1261923Y501805D02*
X1259237Y499119D01*
G01X1264901Y501805D02*
X1261923D01*
G01X1266472Y500234D02*
X1264901Y501805D01*
G01X1267044Y500234D02*
X1266472D01*
G01X1267584Y499694D02*
X1267044Y500234D01*
G01X1271224Y537884D02*
X1274988Y534120D01*
G01X1271224Y582453D02*
Y537884D01*
G01X1273480Y584709D02*
X1271224Y582453D01*
G01X1273480Y594877D02*
Y584709D01*
G01X1276492Y534744D02*
Y528403D01*
G01X1274726Y536510D02*
X1276492Y534744D01*
G01X1274726Y540590D02*
Y536510D01*
G01X1275948Y541812D02*
X1274726Y540590D01*
G01X1275948Y543161D02*
Y541812D01*
G01X1273657Y545452D02*
X1275948Y543161D01*
G01X1273657Y580077D02*
Y545452D01*
G01X1274776Y581196D02*
X1273657Y580077D01*
G01X1274776Y605267D02*
Y581196D01*
G01X1285586Y542197D02*
X1277032Y550751D01*
G01D02*
Y607901D01*
G01X1279600Y529687D02*
X1284187Y525100D01*
G01X1279600Y536200D02*
Y529687D01*
G01X1281600Y538200D02*
X1279600Y536200D01*
G01X1279318Y544047D02*
X1281600Y541765D01*
G01X1279318Y545212D02*
Y544047D01*
G01X1256888Y555109D02*
X1263581Y548416D01*
G01X1256888Y576112D02*
Y555109D01*
G01X1252800Y580200D02*
X1256888Y576112D01*
G01X1278096Y529063D02*
X1283863Y523296D01*
G01X1278096Y536824D02*
Y529063D01*
G01X1280096Y538824D02*
X1278096Y536824D01*
G01X1280096Y541141D02*
Y538824D01*
G01X1275161Y546076D02*
X1280096Y541141D01*
G01X1275161Y578321D02*
Y546076D01*
G01X1276280Y579440D02*
X1275161Y578321D01*
G01X1276280Y607023D02*
Y579440D01*
G01X1253347Y575510D02*
X1250857Y578000D01*
G01X1253347Y554688D02*
Y575510D01*
G01X1258502Y549533D02*
X1253347Y554688D01*
G01X1259117Y549533D02*
X1258502D01*
G01X1260235Y548415D02*
X1259117Y549533D01*
G01X1279552Y562753D02*
X1283800Y558505D01*
G01X1279552Y573722D02*
Y562753D01*
G01X1283630Y577800D02*
X1279552Y573722D01*
G01X1277244Y535056D02*
Y528715D01*
G01X1275478Y536822D02*
X1277244Y535056D01*
G01X1275478Y540278D02*
Y536822D01*
G01X1276700Y541500D02*
X1275478Y540278D01*
G01X1276700Y543473D02*
Y541500D01*
G01X1274409Y545764D02*
X1276700Y543473D01*
G01X1274409Y579199D02*
Y545764D01*
G01X1275528Y580318D02*
X1274409Y579199D01*
G01X1275528Y606145D02*
Y580318D01*
G01X1272085Y581085D02*
X1273200Y582200D01*
G01X1272085Y545715D02*
Y581085D01*
G01X1274900Y542900D02*
X1272085Y545715D01*
G01X1274900Y541828D02*
Y542900D01*
G01X1273974Y540902D02*
X1274900Y541828D01*
G01X1273974Y536198D02*
Y540902D01*
G01X1275740Y534432D02*
X1273974Y536198D01*
G01X1275740Y528091D02*
Y534432D01*
G01X1278848Y529375D02*
X1284075Y524148D01*
G01X1278848Y536512D02*
Y529375D01*
G01X1280848Y538512D02*
X1278848Y536512D01*
G01X1277137Y545164D02*
X1280848Y541453D01*
G01X1277137Y547393D02*
Y545164D01*
G01X1272728Y585587D02*
Y594565D01*
G01X1270472Y583331D02*
X1272728Y585587D01*
G01X1270472Y537572D02*
Y583331D01*
G01X1274236Y533808D02*
X1270472Y537572D01*
G01X1260200Y575350D02*
X1253050Y582500D01*
G01X1260200Y555181D02*
Y575350D01*
G01X1266800Y548581D02*
X1260200Y555181D01*
G01X1268652Y537184D02*
X1272068Y533768D01*
G01X1268652Y549349D02*
Y537184D01*
G01X1263581Y554420D02*
X1268652Y549349D01*
G01X1263581Y586781D02*
Y554420D01*
G01X1270400Y593600D02*
X1263581Y586781D01*
G01X1269404Y537496D02*
X1273484Y533416D01*
G01X1269404Y549661D02*
Y537496D01*
G01X1266924Y552141D02*
X1269404Y549661D01*
G01X1266924Y570324D02*
Y552141D01*
G01X1269720Y573120D02*
X1266924Y570324D01*
G01X1269720Y583643D02*
Y573120D01*
G01X1271976Y585899D02*
X1269720Y583643D01*
G01X1271976Y594253D02*
Y585899D01*
G01X1277784Y551063D02*
Y608213D01*
G01X1285498Y543349D02*
X1277784Y551063D01*
G01X1278536Y574336D02*
X1283152Y578952D01*
G01X1278536Y551375D02*
Y574336D01*
G01X1285410Y544501D02*
X1278536Y551375D01*
G01X1265503Y602854D02*
X1273480Y594877D01*
G01X1265810Y614233D02*
X1274776Y605267D01*
G01X1277032Y607901D02*
X1267244Y617689D01*
G01X1266766Y616537D02*
X1276280Y607023D01*
G01X1266288Y615385D02*
X1275528Y606145D01*
G01X1272728Y594565D02*
X1265191Y602102D01*
G01X1264879Y601350D02*
X1271976Y594253D01*
G01X1277784Y608213D02*
X1267556Y618441D01*
G01X1294150Y26020D02*
Y62850D01*
G01X1292900Y24770D02*
X1294150Y26020D01*
G01X1292900Y17094D02*
Y24770D01*
G01X1294348Y15646D02*
X1292900Y17094D01*
G01X1294348Y8448D02*
Y15646D01*
G01X1288352Y2452D02*
X1294348Y8448D01*
G01X1284222Y2452D02*
X1288352D01*
G01X1280551Y481D02*
Y58751D01*
G01X1280676Y-14064D02*
Y-16824D01*
G01X1280352Y-13740D02*
X1280676Y-14064D01*
G01X1280352Y-3048D02*
Y-13740D01*
G01X1284700Y1300D02*
X1280352Y-3048D01*
G01X1289100Y1300D02*
X1284700D01*
G01X1295500Y7700D02*
X1289100Y1300D01*
G01X1295500Y16124D02*
Y7700D01*
G01X1294052Y17572D02*
X1295500Y16124D01*
G01X1294052Y24292D02*
Y17572D01*
G01X1295302Y25542D02*
X1294052Y24292D01*
G01X1295302Y62002D02*
Y25542D01*
G01X1291848Y78626D02*
X1283150D01*
G01X1298381Y85159D02*
X1291848Y78626D01*
G01X1306959Y85159D02*
X1298381D01*
G01X1308898Y87098D02*
X1306959Y85159D01*
G01X1317195Y87098D02*
X1308898D01*
G01X1292995Y77474D02*
X1298754Y83233D01*
G01X1283628Y77474D02*
X1292995D01*
G01X1290898Y80936D02*
X1282200D01*
G01X1297425Y87463D02*
X1290898Y80936D01*
G01X1305062Y87463D02*
X1297425D01*
G01X1311551Y93952D02*
X1305062Y87463D01*
G01X1332576Y84160D02*
X1312560Y104176D01*
G01X1332576Y80909D02*
Y84160D01*
G01X1333200Y80285D02*
X1332576Y80909D01*
G01X1333200Y75500D02*
Y80285D01*
G01X1335100Y73600D02*
X1333200Y75500D01*
G01X1347100Y73600D02*
X1335100D01*
G01X1335500Y74400D02*
X1344900D01*
G01X1334352Y75548D02*
X1335500Y74400D01*
G01X1334352Y81248D02*
Y75548D01*
G01X1333328Y82272D02*
X1334352Y81248D01*
G01X1333328Y84472D02*
Y82272D01*
G01X1312872Y104928D02*
X1333328Y84472D01*
G01X1318885Y84385D02*
X1320000Y85500D01*
G01X1318885Y83785D02*
Y84385D01*
G01X1316400Y81300D02*
X1318885Y83785D01*
G01X1302100Y81300D02*
X1316400D01*
G01X1295450Y74650D02*
X1302100Y81300D01*
G01X1295450Y64150D02*
Y74650D01*
G01X1294150Y62850D02*
X1295450Y64150D01*
G01X1316100Y85800D02*
X1317300Y84600D01*
G01X1309400Y85800D02*
X1316100D01*
G01X1307607Y84007D02*
X1309400Y85800D01*
G01X1302207Y84007D02*
X1307607D01*
G01X1294200Y76000D02*
X1302207Y84007D01*
G01X1294200Y66900D02*
Y76000D01*
G01X1290000Y62700D02*
X1294200Y66900D01*
G01X1284500Y62700D02*
X1290000D01*
G01X1280551Y58751D02*
X1284500Y62700D01*
G01X1291376Y79784D02*
X1282678D01*
G01X1297903Y86311D02*
X1291376Y79784D01*
G01X1306439Y86311D02*
X1297903D01*
G01X1311559Y91431D02*
X1306439Y86311D01*
G01X1296602Y63302D02*
X1295302Y62002D01*
G01X1296602Y72278D02*
Y63302D01*
G01X1298324Y74000D02*
X1296602Y72278D01*
G01X1298422Y74000D02*
X1298324D01*
G01X1307767Y95030D02*
X1308983Y93814D01*
G01X1308112Y95882D02*
X1308972Y96742D01*
G01X1300618Y95882D02*
X1308112D01*
G01X1296400Y100100D02*
X1300618Y95882D01*
G01X1285900Y100100D02*
X1296400D01*
G01X1287140Y108700D02*
X1284640Y106200D01*
G01X1293500Y108700D02*
X1287140D01*
G01X1300200Y115400D02*
X1293500Y108700D01*
G01X1300200Y120600D02*
Y115400D01*
G01X1300700Y121100D02*
X1300200Y120600D01*
G01X1302850Y121100D02*
X1300700D01*
G01X1304750Y119200D02*
X1302850Y121100D01*
G01X1304750Y107785D02*
Y119200D01*
G01X1308359Y104176D02*
X1304750Y107785D01*
G01X1312560Y104176D02*
X1308359D01*
G01X1309784Y104928D02*
X1312872D01*
G01X1305824Y108888D02*
X1309784Y104928D01*
G01X1305824Y119675D02*
Y108888D01*
G01X1303246Y122253D02*
X1305824Y119675D01*
G01X1300223Y122253D02*
X1303246D01*
G01X1299048Y121078D02*
X1300223Y122253D01*
G01X1299048Y116648D02*
Y121078D01*
G01X1293300Y110900D02*
X1299048Y116648D01*
G01X1286940Y110900D02*
X1293300D01*
G01X1283840Y107800D02*
X1286940Y110900D01*
G01X1300740Y124400D02*
X1301900D01*
G01X1297896Y121556D02*
X1300740Y124400D01*
G01X1297896Y118800D02*
Y121556D01*
G01X1291996Y112900D02*
X1297896Y118800D01*
G01X1281192Y112900D02*
X1291996D01*
G01X1285000Y101300D02*
X1301770D01*
G01X1300371Y95030D02*
X1307767D01*
G01X1296253Y99148D02*
X1300371Y95030D01*
G01X1286295Y99148D02*
X1296253D01*
G01X1338956Y276035D02*
X1359560D01*
G01X1334987Y280004D02*
X1338956Y276035D01*
G01X1359447Y279340D02*
X1338843D01*
G01D02*
X1335923Y282260D01*
G01X1338731Y278388D02*
X1359335D01*
G01X1335611Y281508D02*
X1338731Y278388D01*
G01X1338419Y277636D02*
X1359023D01*
G01X1335299Y280756D02*
X1338419Y277636D01*
G01X1332948Y279252D02*
X1326848Y285352D01*
G01X1334675Y279252D02*
X1332948D01*
G01X1338644Y275283D02*
X1334675Y279252D01*
G01X1359248Y275283D02*
X1338644D01*
G01X1322282Y277861D02*
X1319852Y280291D01*
G01X1334435Y277861D02*
X1322282D01*
G01X1338165Y274131D02*
X1334435Y277861D01*
G01X1353314Y274131D02*
X1338165D01*
G01X1315197Y340703D02*
X1292263Y363637D01*
G01X1315197Y333722D02*
Y340703D01*
G01X1327417Y321469D02*
X1315197Y333722D01*
G01X1327417Y309589D02*
Y321469D01*
G01X1329951Y307055D02*
X1327417Y309589D01*
G01X1329951Y298076D02*
Y307055D01*
G01X1334077Y293950D02*
X1329951Y298076D01*
G01X1335250Y293950D02*
X1334077D01*
G01X1337200Y292000D02*
X1335250Y293950D01*
G01X1337200Y292012D02*
Y292000D01*
G01X1330039Y280662D02*
Y279618D01*
G01X1326101Y284600D02*
X1330039Y280662D01*
G01X1319008Y284600D02*
X1326101D01*
G01X1311808Y291800D02*
X1319008Y284600D01*
G01X1311808Y313331D02*
Y291800D01*
G01X1300304Y324835D02*
X1311808Y313331D01*
G01X1300304Y332416D02*
Y324835D01*
G01X1333260Y280004D02*
X1334987D01*
G01X1326564Y286700D02*
X1333260Y280004D01*
G01X1319036Y286700D02*
X1326564D01*
G01X1313312Y292424D02*
X1319036Y286700D01*
G01X1313312Y313955D02*
Y292424D01*
G01X1303644Y323623D02*
X1313312Y313955D01*
G01X1303644Y333598D02*
Y323623D01*
G01X1336816Y288884D02*
X1343352Y282348D01*
G01X1331951Y288884D02*
X1336816D01*
G01X1327695Y293140D02*
X1331951Y288884D01*
G01X1327695Y306119D02*
Y293140D01*
G01X1323894Y309920D02*
X1327695Y306119D01*
G01X1323894Y314237D02*
Y309920D01*
G01X1312141Y325990D02*
X1323894Y314237D01*
G01X1312141Y338566D02*
Y325990D01*
G01X1290007Y360700D02*
X1312141Y338566D01*
G01X1297370Y324189D02*
Y331230D01*
G01X1307655Y313904D02*
X1297370Y324189D01*
G01X1307655Y308316D02*
Y313904D01*
G01X1305950Y306611D02*
X1307655Y308316D01*
G01X1340715Y297615D02*
X1344839Y293491D01*
G01X1335302Y297615D02*
X1340715D01*
G01X1333648Y299269D02*
X1335302Y297615D01*
G01X1333648Y313071D02*
Y299269D01*
G01X1331052Y315674D02*
X1333648Y313071D01*
G01X1330997Y315674D02*
X1331052D01*
G01X1330074Y316597D02*
X1330997Y315674D01*
G01X1330074Y324992D02*
Y316597D01*
G01X1318254Y336842D02*
X1330074Y324992D01*
G01X1318254Y342645D02*
Y336842D01*
G01X1324482Y336413D02*
Y341994D01*
G01X1333626Y327269D02*
X1324482Y336413D01*
G01X1333626Y326728D02*
Y327269D01*
G01X1334400Y325954D02*
X1333626Y326728D01*
G01X1334400Y299581D02*
Y325954D01*
G01X1335214Y298767D02*
X1334400Y299581D01*
G01X1341193Y298767D02*
X1335214D01*
G01X1345317Y294643D02*
X1341193Y298767D01*
G01X1335923Y282260D02*
X1334240D01*
G01D02*
X1323475Y293025D01*
G01D02*
Y306083D01*
G01D02*
X1320358Y309200D01*
G01D02*
Y313328D01*
G01D02*
X1308404Y325282D01*
G01D02*
Y336349D01*
G01D02*
X1280643Y364110D01*
G01X1322642Y290205D02*
X1323688D01*
G01X1316926Y295921D02*
X1322642Y290205D01*
G01X1316926Y302250D02*
Y295921D01*
G01X1319206Y304530D02*
X1316926Y302250D01*
G01X1319206Y313201D02*
Y304530D01*
G01X1307252Y325155D02*
X1319206Y313201D01*
G01X1307252Y335095D02*
Y325155D01*
G01X1333884Y281508D02*
X1335611D01*
G01X1327188Y288204D02*
X1333884Y281508D01*
G01X1319660Y288204D02*
X1327188D01*
G01X1314816Y293048D02*
X1319660Y288204D01*
G01X1314816Y314614D02*
Y293048D01*
G01X1305148Y324282D02*
X1314816Y314614D01*
G01X1305148Y334222D02*
Y324282D01*
G01X1337128Y289636D02*
X1343664Y283100D01*
G01X1332263Y289636D02*
X1337128D01*
G01X1328447Y293452D02*
X1332263Y289636D01*
G01X1328447Y306431D02*
Y293452D01*
G01X1324646Y310232D02*
X1328447Y306431D01*
G01X1324646Y314549D02*
Y310232D01*
G01X1312893Y326302D02*
X1324646Y314549D01*
G01X1312893Y338878D02*
Y326302D01*
G01X1290759Y361012D02*
X1312893Y338878D01*
G01X1340237Y296463D02*
X1344361Y292339D01*
G01X1334258Y296463D02*
X1340237D01*
G01X1331455Y299266D02*
X1334258Y296463D01*
G01X1331455Y307679D02*
Y299266D01*
G01X1329321Y309813D02*
X1331455Y307679D01*
G01X1329321Y323278D02*
Y309813D01*
G01X1317102Y335497D02*
X1329321Y323278D01*
G01X1317102Y342167D02*
Y335497D01*
G01X1340327Y280844D02*
X1360071D01*
G01X1336976Y284195D02*
X1340327Y280844D01*
G01X1336976Y286325D02*
Y284195D01*
G01X1335201Y288100D02*
X1336976Y286325D01*
G01X1331671Y288100D02*
X1335201D01*
G01X1325731Y294040D02*
X1331671Y288100D01*
G01X1325731Y307019D02*
Y294040D01*
G01X1323142Y309608D02*
X1325731Y307019D01*
G01X1323142Y313925D02*
Y309608D01*
G01X1311389Y325678D02*
X1323142Y313925D01*
G01X1311389Y338254D02*
Y325678D01*
G01X1289185Y360458D02*
X1311389Y338254D01*
G01X1333572Y280756D02*
X1335299D01*
G01X1326876Y287452D02*
X1333572Y280756D01*
G01X1319348Y287452D02*
X1326876D01*
G01X1314064Y292736D02*
X1319348Y287452D01*
G01X1314064Y314267D02*
Y292736D01*
G01X1304396Y323935D02*
X1314064Y314267D01*
G01X1304396Y333910D02*
Y323935D01*
G01X1301456Y324747D02*
Y332894D01*
G01X1312560Y313643D02*
X1301456Y324747D01*
G01X1312560Y292112D02*
Y313643D01*
G01X1319320Y285352D02*
X1312560Y292112D01*
G01X1326848Y285352D02*
X1319320D01*
G01X1319888Y291612D02*
Y290205D01*
G01X1315974Y295526D02*
X1319888Y291612D01*
G01X1315974Y302645D02*
Y295526D01*
G01X1318254Y304925D02*
X1315974Y302645D01*
G01X1318254Y312806D02*
Y304925D01*
G01X1306300Y324760D02*
X1318254Y312806D01*
G01X1306300Y334700D02*
Y324760D01*
G01X1299153Y331315D02*
Y331937D01*
G01X1299152Y331314D02*
X1299153Y331315D01*
G01X1299152Y324923D02*
Y331314D01*
G01X1311056Y313019D02*
X1299152Y324923D01*
G01X1311056Y291207D02*
Y313019D01*
G01X1314792Y287471D02*
X1311056Y291207D01*
G01X1314792Y286427D02*
Y287471D01*
G01X1293985Y323003D02*
Y331807D01*
G01X1300012Y316976D02*
X1293985Y323003D01*
G01X1300012Y309470D02*
Y316976D01*
G01X1308900Y300582D02*
X1300012Y309470D01*
G01X1308900Y289700D02*
Y300582D01*
G01X1311600Y287000D02*
X1308900Y289700D01*
G01X1311600Y284354D02*
Y287000D01*
G01X1315663Y280291D02*
X1311600Y284354D01*
G01X1319852Y280291D02*
X1315663D01*
G01X1305873Y313286D02*
Y309245D01*
G01X1295974Y323185D02*
X1305873Y313286D01*
G01X1295974Y331448D02*
Y323185D01*
G01X1312901Y285451D02*
X1314490Y283862D01*
G01X1312901Y287837D02*
Y285451D01*
G01X1310304Y290434D02*
X1312901Y287837D01*
G01X1310304Y312706D02*
Y290434D01*
G01X1298400Y324610D02*
X1310304Y312706D01*
G01X1298400Y331537D02*
Y324610D01*
G01X1339925Y295711D02*
X1344049Y291587D01*
G01X1334570Y295711D02*
X1339925D01*
G01X1334569Y295710D02*
X1334570Y295711D01*
G01X1333947Y295710D02*
X1334569D01*
G01X1330703Y298954D02*
X1333947Y295710D01*
G01X1330703Y307367D02*
Y298954D01*
G01X1328569Y309501D02*
X1330703Y307367D01*
G01X1328569Y322118D02*
Y309501D01*
G01X1316349Y334371D02*
X1328569Y322118D01*
G01X1316349Y341856D02*
Y334371D01*
G01X1329199Y297251D02*
X1334400Y292050D01*
G01X1329199Y306743D02*
Y297251D01*
G01X1325798Y310144D02*
X1329199Y306743D01*
G01X1325798Y321391D02*
Y310144D01*
G01X1314045Y333177D02*
X1325798Y321391D01*
G01X1314045Y339356D02*
Y333177D01*
G01X1291511Y361890D02*
X1314045Y339356D01*
G01X1329277Y341023D02*
Y342332D01*
G01X1336336Y333964D02*
X1329277Y341023D01*
G01X1336336Y333825D02*
Y333964D01*
G01X1309156Y337227D02*
X1283299Y363084D01*
G01X1309156Y325684D02*
Y337227D01*
G01X1321576Y313264D02*
X1309156Y325684D01*
G01X1321576Y309046D02*
Y313264D01*
G01X1324227Y306395D02*
X1321576Y309046D01*
G01X1324227Y293337D02*
Y306395D01*
G01X1334552Y283012D02*
X1324227Y293337D01*
G01X1336235Y283012D02*
X1334552D01*
G01X1339155Y280092D02*
X1336235Y283012D01*
G01X1359759Y280092D02*
X1339155D01*
G01X1341804Y281596D02*
X1360383D01*
G01X1338700Y284700D02*
X1341804Y281596D01*
G01X1310308Y337705D02*
X1288433Y359580D01*
G01X1310308Y325596D02*
Y337705D01*
G01X1322364Y313540D02*
X1310308Y325596D01*
G01X1322364Y309322D02*
Y313540D01*
G01X1324979Y306707D02*
X1322364Y309322D01*
G01X1324979Y293649D02*
Y306707D01*
G01X1333728Y284900D02*
X1324979Y293649D01*
G01X1335400Y284900D02*
X1333728D01*
G01X1292263Y363637D02*
Y430404D01*
G01X1316212Y379359D02*
Y403215D01*
G01X1330647Y364924D02*
X1316212Y379359D01*
G01X1372156Y364924D02*
X1330647D01*
G01X1290007Y440368D02*
Y360700D01*
G01X1312755Y378882D02*
Y404648D01*
G01X1312754Y378881D02*
X1312755Y378882D01*
G01X1312754Y377927D02*
Y378881D01*
G01X1331081Y359600D02*
X1312754Y377927D01*
G01X1339500Y359600D02*
X1331081D01*
G01X1342396Y356704D02*
X1339500Y359600D01*
G01X1330594Y348436D02*
X1332613Y346417D01*
G01X1329535Y348436D02*
X1330594D01*
G01X1328524Y349447D02*
X1329535Y348436D01*
G01X1328524Y349518D02*
Y349447D01*
G01X1318324Y359718D02*
X1328524Y349518D01*
G01X1318324Y360606D02*
Y359718D01*
G01X1305191Y373739D02*
X1318324Y360606D01*
G01X1305191Y374789D02*
Y373739D01*
G01X1305190Y374790D02*
X1305191Y374789D01*
G01X1305190Y382018D02*
Y374790D01*
G01X1305191Y382019D02*
X1305190Y382018D01*
G01X1305191Y420211D02*
Y382019D01*
G01X1294653Y366246D02*
X1318254Y342645D01*
G01X1294653Y438630D02*
Y366246D01*
G01X1329689Y346511D02*
X1329757D01*
G01X1317890Y358310D02*
X1329689Y346511D01*
G01X1316147Y358310D02*
X1317890D01*
G01X1303939Y370518D02*
X1316147Y358310D01*
G01X1303939Y374270D02*
Y370518D01*
G01X1303938Y374271D02*
X1303939Y374270D01*
G01X1303938Y382537D02*
Y374271D01*
G01X1303939Y382538D02*
X1303938Y382537D01*
G01X1303939Y420730D02*
Y382538D01*
G01X1341748Y355552D02*
X1374856D01*
G01X1339000Y358300D02*
X1341748Y355552D01*
G01X1330751Y358300D02*
X1339000D01*
G01X1311602Y377449D02*
X1330751Y358300D01*
G01X1311602Y379359D02*
Y377449D01*
G01X1311603Y379360D02*
X1311602Y379359D01*
G01X1311603Y405126D02*
Y379360D01*
G01X1298545Y367931D02*
Y431108D01*
G01X1324482Y341994D02*
X1298545Y367931D01*
G01X1309199Y380357D02*
Y417779D01*
G01X1309198Y380356D02*
X1309199Y380357D01*
G01X1309198Y376452D02*
Y380356D01*
G01X1329850Y355800D02*
X1309198Y376452D01*
G01X1337600Y355800D02*
X1329850D01*
G01X1340252Y353148D02*
X1337600Y355800D01*
G01X1370642Y353148D02*
X1340252D01*
G01X1280643Y364110D02*
Y453554D01*
G01X1290759Y440056D02*
Y361012D01*
G01X1293853Y365416D02*
X1317102Y342167D01*
G01X1293853Y438894D02*
Y365416D01*
G01X1289185Y440610D02*
Y360458D01*
G01X1330100Y350601D02*
Y350100D01*
G01X1306443Y374258D02*
X1330100Y350601D01*
G01X1306443Y375308D02*
Y374258D01*
G01X1306442Y375309D02*
X1306443Y375308D01*
G01X1306442Y381499D02*
Y375309D01*
G01X1306443Y381500D02*
X1306442Y381499D01*
G01X1306443Y419206D02*
Y381500D01*
G01X1307195Y375305D02*
X1332600Y349900D01*
G01X1307195Y375620D02*
Y375305D01*
G01X1307194Y375621D02*
X1307195Y375620D01*
G01X1307194Y381187D02*
Y375621D01*
G01X1307195Y381188D02*
X1307194Y381187D01*
G01X1307195Y418894D02*
Y381188D01*
G01X1341100Y354400D02*
X1372126D01*
G01X1338400Y357100D02*
X1341100Y354400D01*
G01X1330321Y357100D02*
X1338400D01*
G01X1310450Y376971D02*
X1330321Y357100D01*
G01X1310450Y379837D02*
Y376971D01*
G01X1310451Y379838D02*
X1310450Y379837D01*
G01X1310451Y405604D02*
Y379838D01*
G01X1337282Y354300D02*
X1363144Y328438D01*
G01X1329579Y354300D02*
X1337282D01*
G01X1307946Y375933D02*
X1329579Y354300D01*
G01X1307946Y380875D02*
Y375933D01*
G01X1307947Y380876D02*
X1307946Y380875D01*
G01X1307947Y418298D02*
Y380876D01*
G01X1330647Y362620D02*
X1370516D01*
G01X1330646Y362619D02*
X1330647Y362620D01*
G01X1329692Y362619D02*
X1330646D01*
G01X1313907Y378404D02*
X1329692Y362619D01*
G01X1313907Y404170D02*
Y378404D01*
G01X1293053Y365152D02*
X1316349Y341856D01*
G01X1293053Y439158D02*
Y365152D01*
G01X1291511Y439744D02*
Y361890D01*
G01X1301049Y368969D02*
Y423280D01*
G01X1325087Y344931D02*
X1301049Y368969D01*
G01X1326678Y344931D02*
X1325087D01*
G01X1329277Y342332D02*
X1326678Y344931D01*
G01X1324768Y347732D02*
X1326014D01*
G01X1302787Y369713D02*
X1324768Y347732D01*
G01X1302787Y373792D02*
Y369713D01*
G01X1302786Y373793D02*
X1302787Y373792D01*
G01X1302786Y383015D02*
Y373793D01*
G01X1302787Y383016D02*
X1302786Y383015D01*
G01X1302787Y421208D02*
Y383016D01*
G01X1283299Y363084D02*
Y455146D01*
G01X1288433Y359580D02*
Y440922D01*
G01X1330169Y363772D02*
X1371286D01*
G01X1315060Y378881D02*
X1330169Y363772D01*
G01X1315060Y403693D02*
Y378881D01*
G01X1295858Y443027D02*
Y484651D01*
G01X1292263Y439432D02*
X1295858Y443027D01*
G01X1292263Y433174D02*
Y439432D01*
G01X1292264Y433173D02*
X1292263Y433174D01*
G01X1292264Y430405D02*
Y433173D01*
G01X1292263Y430404D02*
X1292264Y430405D01*
G01X1321376Y408379D02*
X1342470D01*
G01X1316212Y403215D02*
X1321376Y408379D01*
G01X1293552Y443913D02*
X1290007Y440368D01*
G01X1293552Y489962D02*
Y443913D01*
G01X1341037Y411836D02*
X1347828Y418627D01*
G01X1319943Y411836D02*
X1341037D01*
G01X1312755Y404648D02*
X1319943Y411836D01*
G01X1311815Y426835D02*
X1305191Y420211D01*
G01X1311815Y436600D02*
Y426835D01*
G01X1312928Y437713D02*
X1311815Y436600D01*
G01X1312928Y445072D02*
Y437713D01*
G01X1317928Y450072D02*
X1312928Y445072D01*
G01X1317928Y458152D02*
Y450072D01*
G01X1319630Y459854D02*
X1317928Y458152D01*
G01X1319630Y461160D02*
Y459854D01*
G01X1315253Y465537D02*
X1319630Y461160D01*
G01X1298114Y442091D02*
X1294653Y438630D01*
G01X1298114Y479322D02*
Y442091D01*
G01X1308425Y425216D02*
X1303939Y420730D01*
G01X1308425Y434981D02*
Y425216D01*
G01X1311676Y438232D02*
X1308425Y434981D01*
G01X1311676Y445591D02*
Y438232D01*
G01X1316676Y450591D02*
X1311676Y445591D01*
G01X1316676Y458153D02*
Y450591D01*
G01X1314001Y460828D02*
X1316676Y458153D01*
G01X1314001Y479377D02*
Y460828D01*
G01X1319465Y412988D02*
X1311603Y405126D01*
G01X1340559Y412988D02*
X1319465D01*
G01X1346676Y419105D02*
X1340559Y412988D01*
G01X1298545Y431108D02*
X1300438Y433001D01*
G01X1341676Y452305D02*
X1349239Y459868D01*
G01X1341676Y446847D02*
Y452305D01*
G01X1335009Y440180D02*
X1341676Y446847D01*
G01X1328780Y440180D02*
X1335009D01*
G01X1321900Y433300D02*
X1328780Y440180D01*
G01X1321900Y427071D02*
Y433300D01*
G01X1318063Y423234D02*
X1321900Y427071D01*
G01X1314654Y423234D02*
X1318063D01*
G01X1309199Y417779D02*
X1314654Y423234D01*
G01X1280643Y453554D02*
X1283390Y456301D01*
G01D02*
Y463660D01*
G01D02*
X1285138Y465408D01*
G01X1282638Y464038D02*
Y456613D01*
G01X1284318Y465718D02*
X1282638Y464038D01*
G01X1281134Y465135D02*
Y457237D01*
G01X1294354Y443651D02*
X1290759Y440056D01*
G01X1294354Y485275D02*
Y443651D01*
G01X1297362Y442403D02*
X1293853Y438894D01*
G01X1297362Y482862D02*
Y442403D01*
G01X1292800Y444225D02*
X1289185Y440610D01*
G01X1292800Y489650D02*
Y444225D01*
G01X1313113Y425876D02*
X1306443Y419206D01*
G01X1313113Y435603D02*
Y425876D01*
G01X1316676Y439166D02*
X1313113Y435603D01*
G01X1316676Y443153D02*
Y439166D01*
G01X1315753Y444076D02*
X1316676Y443153D01*
G01X1315753Y445924D02*
Y444076D01*
G01X1322048Y452219D02*
X1315753Y445924D01*
G01X1322048Y456677D02*
Y452219D01*
G01X1325766Y460395D02*
X1322048Y456677D01*
G01X1330212Y460395D02*
X1325766D01*
G01X1336086Y466269D02*
X1330212Y460395D01*
G01X1314224Y425923D02*
X1307195Y418894D01*
G01X1316133Y425923D02*
X1314224D01*
G01X1317428Y427218D02*
X1316133Y425923D01*
G01X1317428Y442057D02*
Y427218D01*
G01X1340659Y465288D02*
X1317428Y442057D01*
G01X1280382Y465631D02*
Y457682D01*
G01X1318987Y414140D02*
X1310451Y405604D01*
G01X1340081Y414140D02*
X1318987D01*
G01X1342928Y416987D02*
X1340081Y414140D01*
G01X1281886Y464465D02*
Y456925D01*
G01X1283366Y465945D02*
X1281886Y464465D01*
G01X1314135Y424486D02*
X1307947Y418298D01*
G01X1316643Y424486D02*
X1314135D01*
G01X1318524Y426367D02*
X1316643Y424486D01*
G01X1318524Y433153D02*
Y426367D01*
G01X1318661Y433290D02*
X1318524Y433153D01*
G01X1318661Y438290D02*
Y433290D01*
G01X1339677Y459306D02*
X1318661Y438290D01*
G01X1343740Y459306D02*
X1339677D01*
G01X1320421Y410684D02*
X1313907Y404170D01*
G01X1341515Y410684D02*
X1320421D01*
G01X1349000Y418169D02*
X1341515Y410684D01*
G01X1296610Y442715D02*
X1293053Y439158D01*
G01X1296610Y484339D02*
Y442715D01*
G01X1295106Y443339D02*
X1291511Y439744D01*
G01X1295106Y484963D02*
Y443339D01*
G01X1311596Y462275D02*
Y480373D01*
G01X1308450Y459129D02*
X1311596Y462275D01*
G01X1308450Y449500D02*
Y459129D01*
G01X1303524Y444574D02*
X1308450Y449500D01*
G01X1303524Y425755D02*
Y444574D01*
G01X1301049Y423280D02*
X1303524Y425755D01*
G01X1307273Y425694D02*
X1302787Y421208D01*
G01X1307273Y435459D02*
Y425694D01*
G01X1307313Y435499D02*
X1307273Y435459D01*
G01X1307313Y436344D02*
Y435499D01*
G01X1308107Y437138D02*
X1307313Y436344D01*
G01X1308107Y443652D02*
Y437138D01*
G01X1312849Y448394D02*
X1308107Y443652D01*
G01X1312849Y479855D02*
Y448394D01*
G01X1284142Y463302D02*
X1285890Y465050D01*
G01X1284142Y455989D02*
Y463302D01*
G01X1283299Y455146D02*
X1284142Y455989D01*
G01X1291994Y444483D02*
Y476205D01*
G01X1288433Y440922D02*
X1291994Y444483D01*
G01X1320899Y409532D02*
X1315060Y403693D01*
G01X1341993Y409532D02*
X1320899D01*
G01X1315040Y521638D02*
Y536700D01*
G01X1318000Y518678D02*
X1315040Y521638D01*
G01X1318000Y509666D02*
Y518678D01*
G01X1304355Y496021D02*
X1318000Y509666D01*
G01X1304355Y490829D02*
Y496021D01*
G01X1300804Y487278D02*
X1304355Y490829D01*
G01X1298485Y487278D02*
X1300804D01*
G01X1295858Y484651D02*
X1298485Y487278D01*
G01X1284790Y497964D02*
Y490879D01*
G01X1280562Y502192D02*
X1284790Y497964D01*
G01X1280562Y504433D02*
Y502192D01*
G01X1280979Y484940D02*
Y467388D01*
G01X1286294Y490255D02*
X1280979Y484940D01*
G01X1286294Y498928D02*
Y490255D01*
G01X1282066Y503156D02*
X1286294Y498928D01*
G01X1282066Y505057D02*
Y503156D01*
G01X1281101Y523794D02*
Y518213D01*
G01X1293222Y490292D02*
X1293552Y489962D01*
G01X1293222Y495872D02*
Y490292D01*
G01X1306888Y509538D02*
X1293222Y495872D01*
G01X1306888Y530948D02*
Y509538D01*
G01X1315253Y478540D02*
Y465537D01*
G01X1330294Y493581D02*
X1315253Y478540D01*
G01X1330294Y529441D02*
Y493581D01*
G01X1304677Y476228D02*
X1301240D01*
G01X1308936Y480487D02*
X1304677Y476228D01*
G01X1308936Y481476D02*
Y480487D01*
G01X1323630Y496170D02*
X1308936Y481476D01*
G01X1323630Y516670D02*
Y496170D01*
G01X1317200Y523100D02*
X1323630Y516670D01*
G01X1317200Y538688D02*
Y523100D01*
G01X1301774Y482982D02*
X1298114Y479322D01*
G01X1308450Y482982D02*
X1301774D01*
G01X1321926Y496458D02*
X1308450Y482982D01*
G01X1321926Y516382D02*
Y496458D01*
G01X1315792Y522516D02*
X1321926Y516382D01*
G01X1315792Y538104D02*
Y522516D01*
G01X1329042Y494418D02*
X1314001Y479377D01*
G01X1329042Y529960D02*
Y494418D01*
G01X1332172Y522544D02*
X1352949Y543321D01*
G01X1332172Y512722D02*
Y522544D01*
G01X1335618Y509276D02*
X1332172Y512722D01*
G01X1335753Y509276D02*
X1335618D01*
G01X1336657Y508372D02*
X1335753Y509276D01*
G01X1336900Y508372D02*
X1336657D01*
G01X1346337Y498935D02*
X1336900Y508372D01*
G01X1285138Y465408D02*
Y482302D01*
G01D02*
X1290187Y487351D01*
G01D02*
Y497093D01*
G01D02*
X1303880Y510786D01*
G01D02*
Y529700D01*
G01X1284318Y483174D02*
Y465718D01*
G01X1289400Y488256D02*
X1284318Y483174D01*
G01X1289400Y497370D02*
Y488256D01*
G01X1303128Y511098D02*
X1289400Y497370D01*
G01X1303128Y521015D02*
Y511098D01*
G01X1299043Y525100D02*
X1303128Y521015D01*
G01X1284187Y525100D02*
X1299043D01*
G01X1282483Y466484D02*
X1281134Y465135D01*
G01X1282483Y484316D02*
Y466484D01*
G01X1287850Y489683D02*
X1282483Y484316D01*
G01X1287850Y497967D02*
Y489683D01*
G01X1301624Y511741D02*
X1287850Y497967D01*
G01X1301624Y520326D02*
Y511741D01*
G01X1298654Y523296D02*
X1301624Y520326D01*
G01X1283863Y523296D02*
X1298654D01*
G01X1297862Y488783D02*
X1294354Y485275D01*
G01X1300181Y488783D02*
X1297862D01*
G01X1302851Y491453D02*
X1300181Y488783D01*
G01X1302851Y496651D02*
Y491453D01*
G01X1315700Y509500D02*
X1302851Y496651D01*
G01X1315700Y518088D02*
Y509500D01*
G01X1313448Y520340D02*
X1315700Y518088D01*
G01X1313448Y535400D02*
Y520340D01*
G01X1299450Y484950D02*
X1297362Y482862D01*
G01X1292450Y490000D02*
X1292800Y489650D01*
G01X1292450Y496164D02*
Y490000D01*
G01X1306136Y509850D02*
X1292450Y496164D01*
G01X1306136Y530636D02*
Y509850D01*
G01X1344085Y466269D02*
X1336086D01*
G01X1342432Y465288D02*
X1340659D01*
G01X1281731Y466980D02*
X1280382Y465631D01*
G01X1281731Y484628D02*
Y466980D01*
G01X1287046Y489943D02*
X1281731Y484628D01*
G01X1287046Y499298D02*
Y489943D01*
G01X1282818Y503526D02*
X1287046Y499298D01*
G01X1282818Y505369D02*
Y503526D01*
G01X1280777Y507410D02*
X1282818Y505369D01*
G01X1280777Y516825D02*
Y507410D01*
G01X1281853Y517901D02*
X1280777Y516825D01*
G01X1281853Y524106D02*
Y517901D01*
G01X1280349Y518525D02*
Y523482D01*
G01X1281314Y502504D02*
Y504745D01*
G01X1285542Y498276D02*
X1281314Y502504D01*
G01X1285542Y490567D02*
Y498276D01*
G01X1280227Y467836D02*
Y485252D01*
G01X1337419Y509624D02*
X1347589Y499454D01*
G01X1337176Y509624D02*
X1337419D01*
G01X1336272Y510528D02*
X1337176Y509624D01*
G01X1336137Y510528D02*
X1336272D01*
G01X1333424Y513241D02*
X1336137Y510528D01*
G01X1333424Y522025D02*
Y513241D01*
G01X1353468Y542069D02*
X1333424Y522025D01*
G01X1283366Y484135D02*
Y465945D01*
G01X1288602Y489371D02*
X1283366Y484135D01*
G01X1288602Y497655D02*
Y489371D01*
G01X1302376Y511429D02*
X1288602Y497655D01*
G01X1302376Y520703D02*
Y511429D01*
G01X1298931Y524148D02*
X1302376Y520703D01*
G01X1284075Y524148D02*
X1298931D01*
G01X1284038Y491191D02*
Y497652D01*
G01X1282534Y495459D02*
X1281175Y494100D01*
G01X1282534Y497028D02*
Y495459D01*
G01X1283286Y497340D02*
Y491503D01*
G01X1338700Y476993D02*
X1350505Y465188D01*
G01X1338700Y504100D02*
Y476993D01*
G01X1335100Y507700D02*
X1338700Y504100D01*
G01X1298797Y486526D02*
X1296610Y484339D01*
G01X1308526Y486526D02*
X1298797D01*
G01X1320300Y498300D02*
X1308526Y486526D01*
G01X1298174Y488031D02*
X1295106Y484963D01*
G01X1298796Y488031D02*
X1298174D01*
G01X1298797Y488030D02*
X1298796Y488031D01*
G01X1300492Y488030D02*
X1298797D01*
G01X1303603Y491141D02*
X1300492Y488030D01*
G01X1303603Y496333D02*
Y491141D01*
G01X1316848Y509578D02*
X1303603Y496333D01*
G01X1316848Y518004D02*
Y509578D01*
G01X1314200Y520652D02*
X1316848Y518004D01*
G01X1314200Y536000D02*
Y520652D01*
G01X1326628Y495405D02*
Y533858D01*
G01X1311596Y480373D02*
X1326628Y495405D01*
G01X1327890Y494896D02*
X1312849Y479855D01*
G01X1327890Y530438D02*
Y494896D01*
G01X1304632Y510474D02*
Y530012D01*
G01X1290939Y496781D02*
X1304632Y510474D01*
G01X1290939Y487039D02*
Y496781D01*
G01X1285890Y481990D02*
X1290939Y487039D01*
G01X1285890Y465050D02*
Y481990D01*
G01X1305384Y510162D02*
Y530324D01*
G01X1291691Y496469D02*
X1305384Y510162D01*
G01X1291691Y486727D02*
Y496469D01*
G01X1288100Y483136D02*
X1291691Y486727D01*
G01X1288100Y480099D02*
Y483136D01*
G01X1291994Y476205D02*
X1288100Y480099D01*
G01X1301300Y587670D02*
Y604300D01*
G01X1298079Y584449D02*
X1301300Y587670D01*
G01X1298079Y550956D02*
Y584449D01*
G01X1300256Y548779D02*
X1298079Y550956D01*
G01X1309192Y548779D02*
X1300256D01*
G01X1313785Y544186D02*
X1309192Y548779D01*
G01X1313785Y537955D02*
Y544186D01*
G01X1315040Y536700D02*
X1313785Y537955D01*
G01X1303900Y533936D02*
X1306888Y530948D01*
G01X1303900Y540075D02*
Y533936D01*
G01X1294781Y549194D02*
X1303900Y540075D01*
G01X1294781Y554936D02*
Y549194D01*
G01X1290460Y559257D02*
X1294781Y554936D01*
G01X1287143Y559257D02*
X1290460D01*
G01X1285400Y561000D02*
X1287143Y559257D01*
G01X1341487Y540634D02*
X1330294Y529441D01*
G01X1348491Y540634D02*
X1341487D01*
G01X1316724Y539164D02*
X1317200Y538688D01*
G01X1316724Y541124D02*
Y539164D01*
G01X1324390Y548790D02*
X1316724Y541124D01*
G01X1344902Y548790D02*
X1324390D01*
G01X1315316Y538580D02*
X1315792Y538104D01*
G01X1315316Y542616D02*
Y538580D01*
G01X1316100Y543400D02*
X1315316Y542616D01*
G01X1340968Y541886D02*
X1329042Y529960D01*
G01X1347972Y541886D02*
X1340968D01*
G01X1303880Y529700D02*
X1300444Y533136D01*
G01D02*
Y536945D01*
G01D02*
X1295192Y542197D01*
G01D02*
X1285586D01*
G01X1281600Y541765D02*
Y538200D01*
G01X1311350Y537498D02*
X1313448Y535400D01*
G01X1311350Y543150D02*
Y537498D01*
G01X1308025Y546475D02*
X1311350Y543150D01*
G01X1299130Y546475D02*
X1308025D01*
G01X1295775Y549830D02*
X1299130Y546475D01*
G01X1295775Y555006D02*
Y549830D01*
G01X1290772Y560009D02*
X1295775Y555006D01*
G01X1290091Y560009D02*
X1290772D01*
G01X1288100Y562000D02*
X1290091Y560009D01*
G01X1303100Y533672D02*
X1306136Y530636D01*
G01X1303100Y539430D02*
Y533672D01*
G01X1294029Y548501D02*
X1303100Y539430D01*
G01X1294029Y548882D02*
Y548501D01*
G01X1294028Y548883D02*
X1294029Y548882D01*
G01X1294028Y549505D02*
Y548883D01*
G01X1294029Y549506D02*
X1294028Y549505D01*
G01X1294029Y554624D02*
Y549506D01*
G01X1290148Y558505D02*
X1294029Y554624D01*
G01X1283800Y558505D02*
X1290148D01*
G01X1286525Y577800D02*
X1283630D01*
G01X1295181Y586456D02*
X1286525Y577800D01*
G01X1295181Y611778D02*
Y586456D01*
G01X1280848Y541453D02*
Y538512D01*
G01X1312570Y537630D02*
X1314200Y536000D01*
G01X1312570Y543771D02*
Y537630D01*
G01X1308714Y547627D02*
X1312570Y543771D01*
G01X1299775Y547627D02*
X1308714D01*
G01X1296927Y550475D02*
X1299775Y547627D01*
G01X1296927Y584927D02*
Y550475D01*
G01X1299676Y587676D02*
X1296927Y584927D01*
G01X1299676Y604294D02*
Y587676D01*
G01X1337648Y544878D02*
X1346524D01*
G01X1326628Y533858D02*
X1337648Y544878D01*
G01X1333453Y536001D02*
X1327890Y530438D01*
G01X1333453Y538912D02*
Y536001D01*
G01X1338167Y543626D02*
X1333453Y538912D01*
G01X1348082Y543626D02*
X1338167D01*
G01X1334481Y547382D02*
X1344318D01*
G01X1330628Y543529D02*
X1334481Y547382D01*
G01X1322129Y543529D02*
X1330628D01*
G01X1318500Y539900D02*
X1322129Y543529D01*
G01X1295104Y543349D02*
X1285498D01*
G01X1301376Y537077D02*
X1295104Y543349D01*
G01X1301376Y533268D02*
Y537077D01*
G01X1304632Y530012D02*
X1301376Y533268D01*
G01X1294029Y586934D02*
Y611300D01*
G01X1286047Y578952D02*
X1294029Y586934D01*
G01X1283152Y578952D02*
X1286047D01*
G01X1296148Y544501D02*
X1285410D01*
G01X1302300Y538349D02*
X1296148Y544501D01*
G01X1302300Y533408D02*
Y538349D01*
G01X1305384Y530324D02*
X1302300Y533408D01*
G01X1299652Y619898D02*
X1295847Y623703D01*
G01X1299652Y605948D02*
Y619898D01*
G01X1301300Y604300D02*
X1299652Y605948D01*
G01X1285814Y621145D02*
X1295181Y611778D01*
G01X1298500Y605470D02*
X1299676Y604294D01*
G01X1298500Y619101D02*
Y605470D01*
G01X1295304Y622297D02*
X1298500Y619101D01*
G01X1294029Y611300D02*
X1285336Y619993D01*
G01X1353500Y80000D02*
X1347100Y73600D01*
G01X1353500Y83600D02*
Y80000D01*
G01X1354600Y84700D02*
X1353500Y83600D01*
G01X1370600Y84700D02*
X1354600D01*
G01X1372300Y86400D02*
X1370600Y84700D01*
G01X1351812Y86640D02*
X1357000D01*
G01X1349400Y84228D02*
X1351812Y86640D01*
G01X1349400Y78900D02*
Y84228D01*
G01X1344900Y74400D02*
X1349400Y78900D01*
G01X1394379Y272486D02*
X1408326D01*
G01X1394375Y272490D02*
X1394379Y272486D01*
G01X1394374Y272490D02*
X1394375D01*
G01X1392104Y274760D02*
X1394374Y272490D01*
G01X1389226Y274760D02*
X1392104D01*
G01X1388333Y273867D02*
X1389226Y274760D01*
G01X1361728Y273867D02*
X1388333D01*
G01X1359560Y276035D02*
X1361728Y273867D01*
G01X1396563Y277750D02*
X1406142D01*
G01X1394288Y280025D02*
X1396563Y277750D01*
G01X1386274Y279256D02*
X1387043Y280025D01*
G01X1363787Y279256D02*
X1386274D01*
G01X1360695Y282348D02*
X1363787Y279256D01*
G01X1407390Y274742D02*
X1395315D01*
G01D02*
X1395311Y274746D01*
G01D02*
X1395310D01*
G01D02*
X1393040Y277016D01*
G01D02*
X1388290D01*
G01D02*
X1387522Y276248D01*
G01D02*
X1362539D01*
G01D02*
X1359447Y279340D01*
G01X1395003Y273990D02*
X1407702D01*
G01X1394999Y273994D02*
X1395003Y273990D01*
G01X1394998Y273994D02*
X1394999D01*
G01X1392728Y276264D02*
X1394998Y273994D01*
G01X1388602Y276264D02*
X1392728D01*
G01X1387834Y275496D02*
X1388602Y276264D01*
G01X1362227Y275496D02*
X1387834D01*
G01X1359335Y278388D02*
X1362227Y275496D01*
G01X1396875Y278502D02*
X1405830D01*
G01X1394600Y280777D02*
X1396875Y278502D01*
G01X1395939Y276246D02*
X1406766D01*
G01X1395935Y276250D02*
X1395939Y276246D01*
G01X1395934Y276250D02*
X1395935D01*
G01X1393664Y278520D02*
X1395934Y276250D01*
G01X1387666Y278520D02*
X1393664D01*
G01X1386898Y277752D02*
X1387666Y278520D01*
G01X1363163Y277752D02*
X1386898D01*
G01X1360071Y280844D02*
X1363163Y277752D01*
G01X1394691Y273238D02*
X1408014D01*
G01X1394687Y273242D02*
X1394691Y273238D01*
G01X1394686Y273242D02*
X1394687D01*
G01X1392416Y275512D02*
X1394686Y273242D01*
G01X1388914Y275512D02*
X1392416D01*
G01X1388146Y274744D02*
X1388914Y275512D01*
G01X1361915Y274744D02*
X1388146D01*
G01X1359023Y277636D02*
X1361915Y274744D01*
G01X1361416Y273115D02*
X1359248Y275283D01*
G01X1392681Y273115D02*
X1361416D01*
G01X1394058Y271738D02*
X1392681Y273115D01*
G01X1394063Y271738D02*
X1394058D01*
G01X1394067Y271734D02*
X1394063Y271738D01*
G01X1408638Y271734D02*
X1394067D01*
G01X1357969Y269476D02*
X1353314Y274131D01*
G01X1387884Y269476D02*
X1357969D01*
G01X1387885Y269477D02*
X1387884Y269476D01*
G01X1406764Y269477D02*
X1387885D01*
G01X1397187Y279254D02*
X1405518D01*
G01X1394912Y281529D02*
X1397187Y279254D01*
G01X1362851Y277000D02*
X1359759Y280092D01*
G01X1387210Y277000D02*
X1362851D01*
G01X1387978Y277768D02*
X1387210Y277000D01*
G01X1393352Y277768D02*
X1387978D01*
G01X1395622Y275498D02*
X1393352Y277768D01*
G01X1395623Y275498D02*
X1395622D01*
G01X1395627Y275494D02*
X1395623Y275498D01*
G01X1407078Y275494D02*
X1395627D01*
G01X1396251Y276998D02*
X1406454D01*
G01X1393977Y279272D02*
X1396251Y276998D01*
G01X1387354Y279272D02*
X1393977D01*
G01X1386586Y278504D02*
X1387354Y279272D01*
G01X1363475Y278504D02*
X1386586D01*
G01X1360383Y281596D02*
X1363475Y278504D01*
G01X1387043Y280025D02*
X1394288D01*
G01X1343352Y282348D02*
X1360695D01*
G01X1396800Y336771D02*
Y351708D01*
G01X1399747Y333824D02*
X1396800Y336771D01*
G01X1403604Y333824D02*
X1399747D01*
G01X1406216Y336436D02*
X1403604Y333824D01*
G01X1386900Y285799D02*
X1428203D01*
G01X1386239Y285668D02*
X1386900Y285799D01*
G01X1382841Y282270D02*
X1386239Y285668D01*
G01X1366158Y282270D02*
X1382841D01*
G01X1359079Y289349D02*
X1366158Y282270D01*
G01X1353498Y289349D02*
X1359079D01*
G01X1349356Y293491D02*
X1353498Y289349D01*
G01X1344839Y293491D02*
X1349356D01*
G01X1397965Y323336D02*
X1405720D01*
G01X1395791Y325510D02*
X1397965Y323336D01*
G01X1385376Y325510D02*
X1395791D01*
G01X1382523Y322657D02*
X1385376Y325510D01*
G01X1375998Y322657D02*
X1382523D01*
G01X1374102Y324553D02*
X1375998Y322657D01*
G01X1357125Y324553D02*
X1374102D01*
G01X1355300Y322728D02*
X1357125Y324553D01*
G01X1355300Y321675D02*
Y322728D01*
G01X1398890Y332672D02*
X1404265D01*
G01X1394752Y336810D02*
X1398890Y332672D01*
G01X1381730Y336810D02*
X1394752D01*
G01X1379950Y338590D02*
X1381730Y336810D01*
G01X1379950Y350458D02*
Y338590D01*
G01X1349834Y294643D02*
X1345317D01*
G01X1353576Y290901D02*
X1349834Y294643D01*
G01X1360392Y290901D02*
X1353576D01*
G01X1363728Y287565D02*
X1360392Y290901D01*
G01X1370835Y287565D02*
X1363728D01*
G01X1374141Y284259D02*
X1370835Y287565D01*
G01X1381431Y284259D02*
X1374141D01*
G01X1373800Y337710D02*
Y349990D01*
G01X1377510Y334000D02*
X1373800Y337710D01*
G01X1389200Y334000D02*
X1377510D01*
G01X1392400Y330800D02*
X1389200Y334000D01*
G01X1386731Y280777D02*
X1394600D01*
G01X1385962Y280008D02*
X1386731Y280777D01*
G01X1364100Y280008D02*
X1385962D01*
G01X1361008Y283100D02*
X1364100Y280008D01*
G01X1343664Y283100D02*
X1361008D01*
G01X1397499Y280006D02*
X1405206D01*
G01X1395224Y282281D02*
X1397499Y280006D01*
G01X1385961Y282281D02*
X1395224D01*
G01X1385192Y281512D02*
X1385961Y282281D01*
G01X1364725Y281512D02*
X1385192D01*
G01X1361552Y284685D02*
X1364725Y281512D01*
G01X1361552Y285812D02*
Y284685D01*
G01X1358767Y288597D02*
X1361552Y285812D01*
G01X1352620Y288597D02*
X1358767D01*
G01X1348878Y292339D02*
X1352620Y288597D01*
G01X1344361Y292339D02*
X1348878D01*
G01X1390984Y335500D02*
X1396470Y330014D01*
G01X1378030Y335500D02*
X1390984D01*
G01X1375100Y338430D02*
X1378030Y335500D01*
G01X1375100Y351426D02*
Y338430D01*
G01X1363144Y328438D02*
X1411258D01*
G01X1400400Y349738D02*
Y335400D01*
G01X1386419Y281529D02*
X1394912D01*
G01X1385650Y280760D02*
X1386419Y281529D01*
G01X1364412Y280760D02*
X1385650D01*
G01X1360800Y284372D02*
X1364412Y280760D01*
G01X1360800Y285500D02*
Y284372D01*
G01X1358455Y287845D02*
X1360800Y285500D01*
G01X1352308Y287845D02*
X1358455D01*
G01X1348566Y291587D02*
X1352308Y287845D01*
G01X1346820Y291587D02*
X1348566D01*
G01X1346819Y291586D02*
X1346820Y291587D01*
G01X1346197Y291586D02*
X1346819D01*
G01X1346196Y291587D02*
X1346197Y291586D01*
G01X1344049Y291587D02*
X1346196D01*
G01X1375667Y361413D02*
X1372156Y364924D01*
G01X1385852Y361413D02*
X1375667D01*
G01X1389537Y357728D02*
X1385852Y361413D01*
G01X1395670Y357728D02*
X1389537D01*
G01X1410489Y342909D02*
X1395670Y357728D01*
G01X1380984Y356704D02*
X1342396D01*
G01X1384278Y353410D02*
X1380984Y356704D01*
G01X1395098Y353410D02*
X1384278D01*
G01X1396800Y351708D02*
X1395098Y353410D01*
G01X1384845Y415948D02*
X1408310Y392483D01*
G01X1384757Y417100D02*
X1409169Y392688D01*
G01X1374856Y355552D02*
X1379950Y350458D01*
G01X1373800Y349990D02*
X1370642Y353148D01*
G01X1372126Y354400D02*
X1375100Y351426D01*
G01X1395007Y355131D02*
X1400400Y349738D01*
G01X1385111Y355131D02*
X1395007D01*
G01X1382386Y357856D02*
X1385111Y355131D01*
G01X1375280Y357856D02*
X1382386D01*
G01X1370516Y362620D02*
X1375280Y357856D01*
G01X1395485Y356283D02*
X1408376Y343392D01*
G01X1385589Y356283D02*
X1395485D01*
G01X1382781Y359091D02*
X1385589Y356283D01*
G01X1375967Y359091D02*
X1382781D01*
G01X1371286Y363772D02*
X1375967Y359091D01*
G01X1359494Y459896D02*
Y477777D01*
G01X1357519Y457921D02*
X1359494Y459896D01*
G01X1357519Y437689D02*
Y457921D01*
G01X1353100Y433270D02*
X1357519Y437689D01*
G01X1353100Y419009D02*
Y433270D01*
G01X1342470Y408379D02*
X1353100Y419009D01*
G01X1385100Y450050D02*
Y447500D01*
G01X1382250Y452900D02*
X1385100Y450050D01*
G01X1382250Y467200D02*
Y452900D01*
G01X1356038Y461330D02*
Y476343D01*
G01X1354061Y459353D02*
X1356038Y461330D01*
G01X1354061Y456972D02*
Y459353D01*
G01X1351409Y454320D02*
X1354061Y456972D01*
G01X1349691Y454320D02*
X1351409D01*
G01X1347828Y452457D02*
X1349691Y454320D01*
G01X1347828Y418627D02*
Y452457D01*
G01X1373359Y415948D02*
X1384845D01*
G01X1361676Y427631D02*
X1373359Y415948D01*
G01X1361676Y459072D02*
Y427631D01*
G01X1360772Y459976D02*
X1361676Y459072D01*
G01X1360772Y478129D02*
Y459976D01*
G01X1373271Y417100D02*
X1384757D01*
G01X1362428Y427943D02*
X1373271Y417100D01*
G01X1362428Y457773D02*
Y427943D01*
G01X1364711Y460056D02*
X1362428Y457773D01*
G01X1364711Y475254D02*
Y460056D01*
G01X1346676Y452935D02*
Y419105D01*
G01X1349213Y455472D02*
X1346676Y452935D01*
G01X1350931Y455472D02*
X1349213D01*
G01X1352909Y457450D02*
X1350931Y455472D01*
G01X1352909Y459831D02*
Y457450D01*
G01X1354161Y461083D02*
X1352909Y459831D01*
G01X1354161Y472213D02*
Y461083D01*
G01X1351757Y462371D02*
Y466151D01*
G01X1349254Y459868D02*
X1351757Y462371D01*
G01X1349239Y459868D02*
X1349254D01*
G01X1346739Y463615D02*
X1344085Y466269D01*
G01X1344090Y463630D02*
X1342432Y465288D01*
G01X1342928Y450817D02*
Y416987D01*
G01X1348735Y456624D02*
X1342928Y450817D01*
G01X1350453Y456624D02*
X1348735D01*
G01X1351757Y457928D02*
X1350453Y456624D01*
G01X1351757Y460309D02*
Y457928D01*
G01X1353009Y461561D02*
X1351757Y460309D01*
G01X1353009Y469357D02*
Y461561D01*
G01X1345554Y461120D02*
X1343740Y459306D01*
G01X1348735Y461120D02*
X1345554D01*
G01X1350505Y462890D02*
X1348735Y461120D01*
G01X1350505Y465188D02*
Y462890D01*
G01X1349000Y434170D02*
Y418169D01*
G01X1351676Y436846D02*
X1349000Y434170D01*
G01X1351676Y452957D02*
Y436846D01*
G01X1355215Y456496D02*
X1351676Y452957D01*
G01X1355215Y458877D02*
Y456496D01*
G01X1357190Y460852D02*
X1355215Y458877D01*
G01X1357190Y476821D02*
Y460852D01*
G01X1383450Y454150D02*
X1385100Y452500D01*
G01X1383450Y467700D02*
Y454150D01*
G01X1350160Y417699D02*
X1341993Y409532D01*
G01X1350160Y433690D02*
Y417699D01*
G01X1352828Y436358D02*
X1350160Y433690D01*
G01X1352828Y452479D02*
Y436358D01*
G01X1356367Y456018D02*
X1352828Y452479D01*
G01X1356367Y458399D02*
Y456018D01*
G01X1358342Y460374D02*
X1356367Y458399D01*
G01X1358342Y477299D02*
Y460374D01*
G01X1361876Y523006D02*
X1365350Y526480D01*
G01X1361876Y503976D02*
Y523006D01*
G01X1357061Y499161D02*
X1361876Y503976D01*
G01X1357061Y480210D02*
Y499161D01*
G01X1359494Y477777D02*
X1357061Y480210D01*
G01X1376898Y472552D02*
X1382250Y467200D01*
G01X1376898Y496445D02*
Y472552D01*
G01X1387999Y507546D02*
X1376898Y496445D01*
G01X1401852Y507546D02*
X1387999D01*
G01X1402950Y508644D02*
X1401852Y507546D01*
G01X1402950Y510650D02*
Y508644D01*
G01X1357852Y523872D02*
X1364152Y530172D01*
G01X1357852Y507626D02*
Y523872D01*
G01X1353605Y503379D02*
X1357852Y507626D01*
G01X1353605Y478776D02*
Y503379D01*
G01X1356038Y476343D02*
X1353605Y478776D01*
G01X1358213Y480688D02*
X1360772Y478129D01*
G01X1358213Y496465D02*
Y480688D01*
G01X1375789Y514041D02*
X1358213Y496465D01*
G01X1390558Y514041D02*
X1375789D01*
G01X1395242Y518725D02*
X1390558Y514041D01*
G01X1395242Y520301D02*
Y518725D01*
G01X1358965Y481000D02*
X1364711Y475254D01*
G01X1358965Y496153D02*
Y481000D01*
G01X1375408Y512596D02*
X1358965Y496153D01*
G01X1393768Y512596D02*
X1375408D01*
G01X1396035Y514863D02*
X1393768Y512596D01*
G01X1352453Y473921D02*
X1354161Y472213D01*
G01X1352453Y509912D02*
Y473921D01*
G01X1355940Y513399D02*
X1352453Y509912D01*
G01X1355940Y523590D02*
Y513399D01*
G01X1363920Y531570D02*
X1355940Y523590D01*
G01X1346337Y494245D02*
Y498935D01*
G01X1344718Y492626D02*
X1346337Y494245D01*
G01X1344718Y473190D02*
Y492626D01*
G01X1351757Y466151D02*
X1344718Y473190D01*
G01X1347849Y474517D02*
X1353009Y469357D01*
G01X1347697Y474517D02*
X1347849D01*
G01X1345970Y476244D02*
X1347697Y474517D01*
G01X1345970Y492107D02*
Y476244D01*
G01X1347589Y493726D02*
X1345970Y492107D01*
G01X1347589Y499454D02*
Y493726D01*
G01X1354757Y479254D02*
X1357190Y476821D01*
G01X1354757Y500315D02*
Y479254D01*
G01X1359572Y505130D02*
X1354757Y500315D01*
G01X1359572Y523962D02*
Y505130D01*
G01X1364630Y529020D02*
X1359572Y523962D01*
G01X1377850Y473300D02*
X1383450Y467700D01*
G01X1377850Y496050D02*
Y473300D01*
G01X1388394Y506594D02*
X1377850Y496050D01*
G01X1402247Y506594D02*
X1388394D01*
G01X1403902Y508249D02*
X1402247Y506594D01*
G01X1355909Y479732D02*
X1358342Y477299D01*
G01X1355909Y499687D02*
Y479732D01*
G01X1360724Y504502D02*
X1355909Y499687D01*
G01X1360724Y523484D02*
Y504502D01*
G01X1364900Y527660D02*
X1360724Y523484D01*
G01X1378508Y528437D02*
X1406257D01*
G01X1376551Y526480D02*
X1378508Y528437D01*
G01X1365350Y526480D02*
X1376551D01*
G01X1382331Y534865D02*
Y543818D01*
G01X1379503Y532037D02*
X1382331Y534865D01*
G01X1377218Y532037D02*
X1379503D01*
G01X1375353Y530172D02*
X1377218Y532037D01*
G01X1364152Y530172D02*
X1375353D01*
G01X1352430Y544573D02*
X1348491Y540634D01*
G01X1367552Y544573D02*
X1352430D01*
G01X1372171Y549192D02*
X1367552Y544573D01*
G01X1387202Y549192D02*
X1372171D01*
G01X1389783Y551773D02*
X1387202Y549192D01*
G01X1413989Y551773D02*
X1389783D01*
G01X1352872Y556760D02*
X1344902Y548790D01*
G01X1384064Y556760D02*
X1352872D01*
G01X1395424Y568120D02*
X1384064Y556760D01*
G01X1414040Y568120D02*
X1395424D01*
G01X1351911Y545825D02*
X1347972Y541886D01*
G01X1352918Y545825D02*
X1351911D01*
G01X1352958Y545865D02*
X1352918Y545825D01*
G01X1366965Y545865D02*
X1352958D01*
G01X1371544Y550444D02*
X1366965Y545865D01*
G01X1386683Y550444D02*
X1371544D01*
G01X1389264Y553025D02*
X1386683Y550444D01*
G01X1413470Y553025D02*
X1389264D01*
G01X1370930Y531570D02*
X1363920D01*
G01X1373320Y533960D02*
X1370930Y531570D01*
G01X1373320Y540179D02*
Y533960D01*
G01X1376997Y543856D02*
X1373320Y540179D01*
G01X1378704Y543856D02*
X1376997D01*
G01X1380785Y545937D02*
X1378704Y543856D01*
G01X1388477Y545937D02*
X1380785D01*
G01X1389066Y545348D02*
X1388477Y545937D01*
G01X1412736Y545348D02*
X1389066D01*
G01X1389496Y547752D02*
X1411739D01*
G01X1389308Y547940D02*
X1389496Y547752D01*
G01X1372861Y547940D02*
X1389308D01*
G01X1368242Y543321D02*
X1372861Y547940D01*
G01X1352949Y543321D02*
X1368242D01*
G01X1368761Y542069D02*
X1353468D01*
G01X1373380Y546688D02*
X1368761Y542069D01*
G01X1388789Y546688D02*
X1373380D01*
G01X1388977Y546500D02*
X1388789Y546688D01*
G01X1412258Y546500D02*
X1388977D01*
G01X1375831Y529020D02*
X1364630D01*
G01X1377570Y530759D02*
X1375831Y529020D01*
G01X1405319Y530759D02*
X1377570D01*
G01X1395098Y562260D02*
X1412230D01*
G01X1385686Y552848D02*
X1395098Y562260D01*
G01X1372744Y552848D02*
X1385686D01*
G01X1371880Y553712D02*
X1372744Y552848D01*
G01X1355358Y553712D02*
X1371880D01*
G01X1346524Y544878D02*
X1355358Y553712D01*
G01X1356916Y552460D02*
X1348082Y543626D01*
G01X1371361Y552460D02*
X1356916D01*
G01X1372225Y551596D02*
X1371361Y552460D01*
G01X1386205Y551596D02*
X1372225D01*
G01X1388786Y554177D02*
X1386205Y551596D01*
G01X1412478Y554177D02*
X1388786D01*
G01X1395906Y566610D02*
X1414630D01*
G01X1384648Y555352D02*
X1395906Y566610D01*
G01X1353456Y555352D02*
X1384648D01*
G01X1345485Y547381D02*
X1353456Y555352D01*
G01X1344319Y547381D02*
X1345485D01*
G01X1344318Y547382D02*
X1344319Y547381D01*
G01X1376101Y527660D02*
X1364900D01*
G01X1378030Y529589D02*
X1376101Y527660D01*
G01X1405779Y529589D02*
X1378030D01*
G01X1457900Y-9100D02*
X1452000Y-15000D01*
G01X1495300Y-9100D02*
X1457900D01*
G01X1456379Y141261D02*
X1451228D01*
G01X1460579Y145461D02*
X1456379Y141261D01*
G01X1469862Y145461D02*
X1460579D01*
G01X1455228Y150400D02*
X1451233Y146405D01*
G01X1472737Y150400D02*
X1455228D01*
G01X1459078Y171402D02*
X1478402D01*
G01X1454480Y176000D02*
X1459078Y171402D01*
G01X1451379Y176000D02*
X1454480D01*
G01X1451365Y176014D02*
X1451379Y176000D01*
G01X1449644Y178372D02*
X1450532D01*
G01X1448832Y177560D02*
X1449644Y178372D01*
G01X1448832Y173823D02*
Y177560D01*
G01X1450761Y171894D02*
X1448832Y173823D01*
G01X1455095Y171894D02*
X1450761D01*
G01X1456739Y170250D02*
X1455095Y171894D01*
G01X1478880Y170250D02*
X1456739D01*
G01X1465087Y249513D02*
X1479013D01*
G01X1460800Y253800D02*
X1465087Y249513D01*
G01X1460800Y255844D02*
Y253800D01*
G01X1459272Y257372D02*
X1460800Y255844D01*
G01X1451164Y257372D02*
X1459272D01*
G01X1447989Y260547D02*
X1451164Y257372D01*
G01X1442724Y260547D02*
X1447989D01*
G01X1430166Y273105D02*
X1442724Y260547D01*
G01X1430166Y274294D02*
Y273105D01*
G01X1427221Y277239D02*
X1430166Y274294D01*
G01X1413079Y277239D02*
X1427221D01*
G01X1408326Y272486D02*
X1413079Y277239D01*
G01X1450105Y278400D02*
X1448603Y279902D01*
G01X1474230Y278400D02*
X1450105D01*
G01X1406142Y277750D02*
X1410982Y282590D01*
G01X1448847Y276753D02*
X1448603D01*
G01X1450317Y275283D02*
X1448847Y276753D01*
G01X1471717Y275283D02*
X1450317D01*
G01X1462526Y272133D02*
X1469220Y265439D01*
G01X1459522Y272133D02*
X1462526D01*
G01X1458052Y273603D02*
X1459522Y272133D01*
G01X1461348Y245988D02*
Y244350D01*
G01X1458603Y248733D02*
X1461348Y245988D01*
G01X1447887Y248733D02*
X1458603D01*
G01X1445200Y251420D02*
X1447887Y248733D01*
G01X1445200Y255747D02*
Y251420D01*
G01X1434381Y266566D02*
X1445200Y255747D01*
G01X1432134Y266566D02*
X1434381D01*
G01X1426658Y272042D02*
X1432134Y266566D01*
G01X1426658Y274252D02*
Y272042D01*
G01X1458551Y269953D02*
X1458102Y270402D01*
G01X1458551Y265050D02*
Y269953D01*
G01X1459099Y264502D02*
X1458551Y265050D01*
G01X1459099Y264501D02*
Y264502D01*
G01X1460857Y262743D02*
X1459099Y264501D01*
G01X1471328Y262743D02*
X1460857D01*
G01X1451850Y262200D02*
X1450314Y263736D01*
G01D02*
X1443351D01*
G01D02*
X1443350Y263735D01*
G01D02*
X1442728D01*
G01D02*
X1432422Y274041D01*
G01D02*
Y275230D01*
G01D02*
X1428070Y279582D01*
G01X1412230D02*
X1407390Y274742D01*
G01X1460545Y261991D02*
X1471640D01*
G01X1458347Y264189D02*
X1460545Y261991D01*
G01X1458347Y264190D02*
Y264189D01*
G01X1453553Y268984D02*
X1458347Y264190D01*
G01X1447994Y268984D02*
X1453553D01*
G01X1447133Y269845D02*
X1447994Y268984D01*
G01X1447133Y270968D02*
Y269845D01*
G01X1445968Y272133D02*
X1447133Y270968D01*
G01X1441695Y272133D02*
X1445968D01*
G01X1440834Y272994D02*
X1441695Y272133D01*
G01X1440834Y280511D02*
Y272994D01*
G01X1451650Y259700D02*
X1454000D01*
G01X1448366Y262984D02*
X1451650Y259700D01*
G01X1443663Y262984D02*
X1448366D01*
G01X1443662Y262983D02*
X1443663Y262984D01*
G01X1442416Y262983D02*
X1443662D01*
G01X1431670Y273729D02*
X1442416Y262983D01*
G01X1431670Y274918D02*
Y273729D01*
G01X1427758Y278830D02*
X1431670Y274918D01*
G01X1412542Y278830D02*
X1427758D01*
G01X1407702Y273990D02*
X1412542Y278830D01*
G01X1405830Y278502D02*
X1410670Y283342D01*
G01X1447830Y239750D02*
X1476560D01*
G01X1444850Y242730D02*
X1447830Y239750D01*
G01X1463938Y248761D02*
X1479325D01*
G01X1460052Y252647D02*
X1463938Y248761D01*
G01X1454053Y252647D02*
X1460052D01*
G01X1452200Y254500D02*
X1454053Y252647D01*
G01X1448500Y255924D02*
Y257700D01*
G01X1452822Y251602D02*
X1448500Y255924D01*
G01X1459681Y251602D02*
X1452822D01*
G01X1463274Y248009D02*
X1459681Y251602D01*
G01X1479637Y248009D02*
X1463274D01*
G01X1406766Y276246D02*
X1411606Y281086D01*
G01X1455576Y260974D02*
X1454350Y262200D01*
G01X1455576Y259047D02*
Y260974D01*
G01X1454653Y258124D02*
X1455576Y259047D01*
G01X1451476Y258124D02*
X1454653D01*
G01X1448300Y261300D02*
X1451476Y258124D01*
G01X1443035Y261300D02*
X1448300D01*
G01X1430918Y273417D02*
X1443035Y261300D01*
G01X1430918Y274606D02*
Y273417D01*
G01X1427475Y278049D02*
X1430918Y274606D01*
G01X1412825Y278049D02*
X1427475D01*
G01X1408014Y273238D02*
X1412825Y278049D01*
G01X1413391Y276487D02*
X1408638Y271734D01*
G01X1426909Y276487D02*
X1413391D01*
G01X1429413Y273983D02*
X1426909Y276487D01*
G01X1429413Y272598D02*
Y273983D01*
G01X1451562Y250449D02*
X1429413Y272598D01*
G01X1459015Y250449D02*
X1451562D01*
G01X1465690Y243774D02*
X1459015Y250449D01*
G01X1412717Y270473D02*
X1410979D01*
G01X1412856Y270612D02*
X1412717Y270473D01*
G01X1419768Y270612D02*
X1412856D01*
G01X1425165Y265215D02*
X1419768Y270612D01*
G01X1434668Y265215D02*
X1425165D01*
G01X1442980Y256903D02*
X1434668Y265215D01*
G01X1442980Y241969D02*
Y256903D01*
G01X1446894Y238055D02*
X1442980Y241969D01*
G01X1474002Y238055D02*
X1446894D01*
G01X1410832Y265409D02*
X1406764Y269477D01*
G01X1417191Y265409D02*
X1410832D01*
G01X1431000Y251600D02*
X1417191Y265409D01*
G01X1434300Y251600D02*
X1431000D01*
G01X1405518Y279254D02*
X1410358Y284094D01*
G01X1462297Y273603D02*
X1466916Y268984D01*
G01X1461202Y273603D02*
X1462297D01*
G01X1446552Y237230D02*
X1473660D01*
G01X1442093Y241689D02*
X1446552Y237230D01*
G01X1442093Y256726D02*
Y241689D01*
G01X1434554Y264265D02*
X1442093Y256726D01*
G01X1424771Y264265D02*
X1434554D01*
G01X1419374Y269662D02*
X1424771Y264265D01*
G01X1412970Y269662D02*
X1419374D01*
G01X1412579Y269271D02*
X1412970Y269662D01*
G01X1412579Y268273D02*
Y269271D01*
G01X1463196Y270400D02*
X1469245Y264351D01*
G01X1461300Y270400D02*
X1463196D01*
G01X1458704Y249696D02*
X1465378Y243022D01*
G01X1449168Y249696D02*
X1458704D01*
G01X1447154Y251710D02*
X1449168Y249696D01*
G01X1443375Y273603D02*
X1442304D01*
G01X1444845Y275073D02*
X1443375Y273603D01*
G01X1446063Y275073D02*
X1444845D01*
G01X1446924Y274212D02*
X1446063Y275073D01*
G01X1446924Y273203D02*
Y274212D01*
G01X1448127Y272000D02*
X1446924Y273203D01*
G01X1458583Y272000D02*
X1448127D01*
G01X1459600Y270983D02*
X1458583Y272000D01*
G01X1459600Y269101D02*
Y270983D01*
G01X1465206Y263495D02*
X1459600Y269101D01*
G01X1471016Y263495D02*
X1465206D01*
G01X1440083Y270595D02*
Y280823D01*
G01X1441904Y268774D02*
X1440083Y270595D01*
G01X1446063Y268774D02*
X1441904D01*
G01X1447133Y267704D02*
X1446063Y268774D01*
G01X1447133Y266695D02*
Y267704D01*
G01X1448588Y265240D02*
X1447133Y266695D01*
G01X1450938Y265240D02*
X1448588D01*
G01X1451598Y264580D02*
X1450938Y265240D01*
G01X1456226Y264580D02*
X1451598D01*
G01X1462078Y258728D02*
X1456226Y264580D01*
G01X1470957Y258728D02*
X1462078D01*
G01X1411918Y280334D02*
X1407078Y275494D01*
G01X1433424Y275292D02*
X1428382Y280334D01*
G01X1433424Y274103D02*
Y275292D01*
G01X1443039Y264488D02*
X1433424Y274103D01*
G01X1450626Y264488D02*
X1443039D01*
G01X1451286Y263828D02*
X1450626Y264488D01*
G01X1455348Y263828D02*
X1451286D01*
G01X1461276Y257900D02*
X1455348Y263828D01*
G01X1465929Y257900D02*
X1461276D01*
G01X1406454Y276998D02*
X1411294Y281838D01*
G01X1410489Y337988D02*
Y342909D01*
G01X1446924Y303419D02*
X1448603Y305098D01*
G01X1446924Y301339D02*
Y303419D01*
G01X1446063Y300478D02*
X1446924Y301339D01*
G01X1445055Y300478D02*
X1446063D01*
G01X1443773Y299196D02*
X1445055Y300478D01*
G01X1443773Y297113D02*
Y299196D01*
G01X1429250Y282590D02*
X1443773Y297113D01*
G01X1410982Y282590D02*
X1429250D01*
G01X1459522Y303628D02*
X1458052Y305098D01*
G01X1471258Y303628D02*
X1459522D01*
G01X1408348Y336436D02*
X1406216D01*
G01X1414101Y337399D02*
X1416000Y335500D01*
G01X1414101Y346405D02*
Y337399D01*
G01X1458663Y322805D02*
X1468503D01*
G01X1454928Y319070D02*
X1458663Y322805D01*
G01X1454928Y317723D02*
Y319070D01*
G01X1457123Y293428D02*
X1454902Y295649D01*
G01X1489349Y293428D02*
X1457123D01*
G01X1463991Y332673D02*
X1471440D01*
G01X1451718Y320400D02*
X1463991Y332673D01*
G01X1448800Y320400D02*
X1451718D01*
G01X1447133Y318733D02*
X1448800Y320400D01*
G01X1447133Y317094D02*
Y318733D01*
G01X1443439Y313400D02*
X1447133Y317094D01*
G01X1441500Y313400D02*
X1443439D01*
G01X1436797Y308697D02*
X1441500Y313400D01*
G01X1436797Y294393D02*
Y308697D01*
G01X1428203Y285799D02*
X1436797Y294393D01*
G01X1417838Y331937D02*
Y341662D01*
G01X1416522Y330621D02*
X1417838Y331937D01*
G01X1414505Y330621D02*
X1416522D01*
G01X1410238Y326354D02*
X1414505Y330621D01*
G01X1408738Y326354D02*
X1410238D01*
G01X1405720Y323336D02*
X1408738Y326354D01*
G01X1416000Y346150D02*
Y338100D01*
G01X1404593Y333000D02*
X1408250D01*
G01X1404265Y332672D02*
X1404593Y333000D01*
G01X1462160Y316730D02*
X1466916D01*
G01X1460390Y318500D02*
X1462160Y316730D01*
G01X1458400Y318500D02*
X1460390D01*
G01X1464351Y305098D02*
X1467299D01*
G01X1428070Y279582D02*
X1412230D01*
G01X1459701Y297149D02*
X1458052Y298798D01*
G01X1459701Y295071D02*
Y297149D01*
G01X1460593Y294179D02*
X1459701Y295071D01*
G01X1474407Y294179D02*
X1460593D01*
G01X1443376Y283053D02*
X1440834Y280511D01*
G01X1448603Y283053D02*
X1443376D01*
G01X1460593Y312867D02*
X1465828D01*
G01X1459732Y312006D02*
X1460593Y312867D01*
G01X1459732Y310998D02*
Y312006D01*
G01X1458661Y309927D02*
X1459732Y310998D01*
G01X1447134Y309927D02*
X1458661D01*
G01X1445454Y308247D02*
X1447134Y309927D01*
G01X1443773Y303417D02*
X1445454Y305098D01*
G01X1443773Y301340D02*
Y303417D01*
G01X1442912Y300479D02*
X1443773Y301340D01*
G01X1441904Y300479D02*
X1442912D01*
G01X1440680Y299255D02*
X1441904Y300479D01*
G01X1440680Y295084D02*
Y299255D01*
G01X1428938Y283342D02*
X1440680Y295084D01*
G01X1410670Y283342D02*
X1428938D01*
G01X1438293Y304236D02*
X1442304Y308247D01*
G01X1438293Y294825D02*
Y304236D01*
G01X1428314Y284846D02*
X1438293Y294825D01*
G01X1410046Y284846D02*
X1428314D01*
G01X1405206Y280006D02*
X1410046Y284846D01*
G01X1443301Y287198D02*
X1445454Y289351D01*
G01X1436298Y287198D02*
X1443301D01*
G01X1430186Y281086D02*
X1436298Y287198D01*
G01X1411606Y281086D02*
X1430186D01*
G01X1464295Y319670D02*
X1465541Y318424D01*
G01X1461267Y319670D02*
X1464295D01*
G01X1460479Y320458D02*
X1461267Y319670D01*
G01X1458279Y320458D02*
X1460479D01*
G01X1456450Y318629D02*
X1458279Y320458D01*
G01X1456450Y317166D02*
Y318629D01*
G01X1455300Y316016D02*
X1456450Y317166D01*
G01X1447994Y316016D02*
X1455300D01*
G01X1443774Y311796D02*
X1447994Y316016D01*
G01X1443774Y306568D02*
Y311796D01*
G01X1442304Y305098D02*
X1443774Y306568D01*
G01X1443775Y290821D02*
X1442304Y289350D01*
G01X1452362Y290821D02*
X1443775D01*
G01X1453432Y289751D02*
X1452362Y290821D01*
G01X1453432Y288742D02*
Y289751D01*
G01X1454293Y287881D02*
X1453432Y288742D01*
G01X1455511Y287881D02*
X1454293D01*
G01X1456582Y288952D02*
X1455511Y287881D01*
G01X1456582Y289960D02*
Y288952D01*
G01X1457443Y290821D02*
X1456582Y289960D01*
G01X1474407Y290821D02*
X1457443D01*
G01X1461847Y315979D02*
X1467587D01*
G01X1461810Y316016D02*
X1461847Y315979D01*
G01X1457443Y316016D02*
X1461810D01*
G01X1456372Y314945D02*
X1457443Y316016D01*
G01X1456372Y313937D02*
Y314945D01*
G01X1455302Y312867D02*
X1456372Y313937D01*
G01X1446924Y312867D02*
X1455302D01*
G01X1445454Y311397D02*
X1446924Y312867D01*
G01X1415720Y332900D02*
X1416000D01*
G01X1411258Y328438D02*
X1415720Y332900D01*
G01X1444927Y306650D02*
X1466973D01*
G01X1443984Y305707D02*
X1444927Y306650D01*
G01X1443984Y304699D02*
Y305707D01*
G01X1442785Y303500D02*
X1443984Y304699D01*
G01X1441775Y303500D02*
X1442785D01*
G01X1439045Y300770D02*
X1441775Y303500D01*
G01X1439045Y294513D02*
Y300770D01*
G01X1428626Y284094D02*
X1439045Y294513D01*
G01X1410358Y284094D02*
X1428626D01*
G01X1446924Y281372D02*
X1445454Y279902D01*
G01X1474407Y281372D02*
X1446924D01*
G01X1465821Y284522D02*
X1464351Y283052D01*
G01X1462668Y328611D02*
X1482596D01*
G01X1451753Y317696D02*
X1462668Y328611D01*
G01X1464750Y309717D02*
X1467240Y312207D01*
G01X1459522Y309717D02*
X1464750D01*
G01X1458052Y308247D02*
X1459522Y309717D01*
G01X1455702Y286202D02*
X1454902D01*
G01X1457172Y287672D02*
X1455702Y286202D01*
G01X1474407Y287672D02*
X1457172D01*
G01X1456478Y327900D02*
X1443500D01*
G01X1467978Y339400D02*
X1456478Y327900D01*
G01X1453223Y297328D02*
X1451753Y298798D01*
G01X1455511Y297328D02*
X1453223D01*
G01X1456387Y298204D02*
X1455511Y297328D01*
G01X1456387Y299212D02*
Y298204D01*
G01X1457443Y300268D02*
X1456387Y299212D01*
G01X1458661Y300268D02*
X1457443D01*
G01X1459732Y299197D02*
X1458661Y300268D01*
G01X1459732Y298189D02*
Y299197D01*
G01X1460593Y297328D02*
X1459732Y298189D01*
G01X1474407Y297328D02*
X1460593D01*
G01X1459731Y284523D02*
X1461202Y283052D01*
G01X1443783Y284523D02*
X1459731D01*
G01X1440083Y280823D02*
X1443783Y284523D01*
G01X1428382Y280334D02*
X1411918D01*
G01X1460593Y300478D02*
X1474407D01*
G01X1459732Y301339D02*
X1460593Y300478D01*
G01X1459732Y302347D02*
Y301339D01*
G01X1458660Y303419D02*
X1459732Y302347D01*
G01X1457442Y303419D02*
X1458660D01*
G01X1456456Y302433D02*
X1457442Y303419D01*
G01X1456456Y301423D02*
Y302433D01*
G01X1455433Y300400D02*
X1456456Y301423D01*
G01X1448126Y300400D02*
X1455433D01*
G01X1446924Y299198D02*
X1448126Y300400D01*
G01X1446924Y298189D02*
Y299198D01*
G01X1446063Y297328D02*
X1446924Y298189D01*
G01X1445052Y297328D02*
X1446063D01*
G01X1429562Y281838D02*
X1445052Y297328D01*
G01X1411294Y281838D02*
X1429562D01*
G01X1457902Y292351D02*
X1454902Y289351D01*
G01X1488900Y292351D02*
X1457902D01*
G01X1408376Y343392D02*
Y339882D01*
G01X1463876Y357000D02*
X1470299D01*
G01X1463617Y357259D02*
X1463876Y357000D01*
G01X1408310Y352196D02*
X1414101Y346405D01*
G01X1408310Y392483D02*
Y352196D01*
G01X1417173Y357527D02*
X1413400Y361300D01*
G01X1417173Y342327D02*
Y357527D01*
G01X1417838Y341662D02*
X1417173Y342327D01*
G01X1409169Y352981D02*
X1416000Y346150D01*
G01X1409169Y392688D02*
Y352981D01*
G01X1464361Y385066D02*
Y385275D01*
G01X1471163Y378264D02*
X1464361Y385066D01*
G01X1475380Y470172D02*
X1460661Y484891D01*
G01X1449884Y487592D02*
X1449568Y487276D01*
G01X1449884Y487740D02*
Y487592D01*
G01X1454061Y491917D02*
X1449884Y487740D01*
G01X1462420Y491917D02*
X1454061D01*
G01X1466548Y487789D02*
X1462420Y491917D01*
G01X1463043Y492669D02*
X1467030Y488682D01*
G01X1460411Y492669D02*
X1463043D01*
G01X1458060Y495020D02*
X1460411Y492669D01*
G01X1460965Y486816D02*
X1476132Y471649D01*
G01X1457554Y486816D02*
X1460965D01*
G01X1456602Y485864D02*
X1457554Y486816D01*
G01X1464281Y486776D02*
X1478235D01*
G01X1461267Y489790D02*
X1464281Y486776D01*
G01X1403902Y509290D02*
Y508249D01*
G01X1405262Y510650D02*
X1403902Y509290D01*
G01X1405950Y510650D02*
X1405262D01*
G01X1461638Y487972D02*
X1467154Y482456D01*
G01X1457594Y487972D02*
X1461638D01*
G01X1456590Y488976D02*
X1457594Y487972D01*
G01X1460013Y552153D02*
X1514543D01*
G01X1458408Y553758D02*
X1460013Y552153D01*
G01X1440235Y553758D02*
X1458408D01*
G01X1429079Y542602D02*
X1440235Y553758D01*
G01X1420422Y542602D02*
X1429079D01*
G01X1406257Y528437D02*
X1420422Y542602D01*
G01X1420229Y558013D02*
X1413989Y551773D01*
G01X1425286Y558013D02*
X1420229D01*
G01X1425553Y558280D02*
X1425286Y558013D01*
G01X1427034Y558280D02*
X1425553D01*
G01X1430384Y561630D02*
X1427034Y558280D01*
G01X1430384Y562062D02*
Y561630D01*
G01X1432348Y564026D02*
X1430384Y562062D01*
G01X1442945Y564026D02*
X1432348D01*
G01X1445959Y561012D02*
X1442945Y564026D01*
G01X1461638Y561012D02*
X1445959D01*
G01X1462584Y560066D02*
X1461638Y561012D01*
G01X1504949Y560066D02*
X1462584D01*
G01X1414827Y568907D02*
X1414040Y568120D01*
G01X1423508Y568907D02*
X1414827D01*
G01X1426797Y572196D02*
X1423508Y568907D01*
G01X1432692Y572196D02*
X1426797D01*
G01X1443088Y582592D02*
X1432692Y572196D01*
G01X1453491Y582592D02*
X1443088D01*
G01X1461794Y574289D02*
X1453491Y582592D01*
G01X1462653Y574289D02*
X1461794D01*
G01X1467854Y579490D02*
X1462653Y574289D01*
G01X1419710Y559265D02*
X1413470Y553025D01*
G01X1424767Y559265D02*
X1419710D01*
G01X1425034Y559532D02*
X1424767Y559265D01*
G01X1426515Y559532D02*
X1425034D01*
G01X1429132Y562149D02*
X1426515Y559532D01*
G01X1429132Y562581D02*
Y562149D01*
G01X1432127Y565576D02*
X1429132Y562581D01*
G01X1463223Y565576D02*
X1432127D01*
G01X1464020Y564779D02*
X1463223Y565576D01*
G01X1470817Y564779D02*
X1464020D01*
G01X1421745Y554357D02*
X1412736Y545348D01*
G01X1426802Y554357D02*
X1421745D01*
G01X1426996Y554551D02*
X1426802Y554357D01*
G01X1436138Y554551D02*
X1426996D01*
G01X1438801Y557214D02*
X1436138Y554551D01*
G01X1459842Y557214D02*
X1438801D01*
G01X1461328Y555728D02*
X1459842Y557214D01*
G01X1545183Y555728D02*
X1461328D01*
G01X1461643Y558814D02*
X1506483D01*
G01X1460698Y559759D02*
X1461643Y558814D01*
G01X1445441Y559759D02*
X1460698D01*
G01X1442507Y562693D02*
X1445441Y559759D01*
G01X1440731Y562693D02*
X1442507D01*
G01X1435066Y557028D02*
X1440731Y562693D01*
G01X1426072Y557028D02*
X1435066D01*
G01X1425805Y556761D02*
X1426072Y557028D01*
G01X1420748Y556761D02*
X1425805D01*
G01X1411739Y547752D02*
X1420748Y556761D01*
G01X1421267Y555509D02*
X1412258Y546500D01*
G01X1426324Y555509D02*
X1421267D01*
G01X1426566Y555751D02*
X1426324Y555509D01*
G01X1435708Y555751D02*
X1426566D01*
G01X1438323Y558366D02*
X1435708Y555751D01*
G01X1460320Y558366D02*
X1438323D01*
G01X1461124Y557562D02*
X1460320Y558366D01*
G01X1507002Y557562D02*
X1461124D01*
G01X1427911Y553351D02*
X1405319Y530759D01*
G01X1436568Y553351D02*
X1427911D01*
G01X1439279Y556062D02*
X1436568Y553351D01*
G01X1459364Y556062D02*
X1439279D01*
G01X1460850Y554576D02*
X1459364Y556062D01*
G01X1545661Y554576D02*
X1460850D01*
G01X1464538Y567672D02*
X1466989D01*
G01X1464020Y568190D02*
X1464538Y567672D01*
G01X1429560Y568190D02*
X1464020D01*
G01X1429520Y568150D02*
X1429560Y568190D01*
G01X1428484Y568150D02*
X1429520D01*
G01X1422213Y561879D02*
X1428484Y568150D01*
G01X1420907Y561879D02*
X1422213D01*
G01X1419984Y562802D02*
X1420907Y561879D01*
G01X1419984Y564109D02*
Y562802D01*
G01X1419301Y564792D02*
X1419984Y564109D01*
G01X1414762Y564792D02*
X1419301D01*
G01X1412230Y562260D02*
X1414762Y564792D01*
G01X1418718Y560417D02*
X1412478Y554177D01*
G01X1424289Y560417D02*
X1418718D01*
G01X1424556Y560684D02*
X1424289Y560417D01*
G01X1425896Y560684D02*
X1424556D01*
G01X1427255Y562043D02*
X1425896Y560684D01*
G01X1427255Y563005D02*
Y562043D01*
G01X1431181Y566931D02*
X1427255Y563005D01*
G01X1463498Y566931D02*
X1431181D01*
G01X1464497Y565932D02*
X1463498Y566931D01*
G01X1470340Y565932D02*
X1464497D01*
G01X1463278Y572922D02*
X1465700Y570500D01*
G01X1463237Y572881D02*
X1463278Y572922D01*
G01X1461210Y572881D02*
X1463237D01*
G01X1452907Y581184D02*
X1461210Y572881D01*
G01X1443672Y581184D02*
X1452907D01*
G01X1433276Y570788D02*
X1443672Y581184D01*
G01X1427381Y570788D02*
X1433276D01*
G01X1424092Y567499D02*
X1427381Y570788D01*
G01X1415519Y567499D02*
X1424092D01*
G01X1414630Y566610D02*
X1415519Y567499D01*
G01X1424490Y548300D02*
X1405779Y529589D01*
G01X1433147Y548300D02*
X1424490D01*
G01X1439757Y554910D02*
X1433147Y548300D01*
G01X1458886Y554910D02*
X1439757D01*
G01X1460491Y553305D02*
X1458886Y554910D01*
G01X1515021Y553305D02*
X1460491D01*
G01X1525800Y8800D02*
X1529400D01*
G01X1522500Y5500D02*
X1525800Y8800D01*
G01X1522500Y-1000D02*
Y5500D01*
G01X1520400Y-3100D02*
X1522500Y-1000D01*
G01X1504700Y-3100D02*
X1520400D01*
G01X1501500Y-6300D02*
X1504700Y-3100D01*
G01X1501500Y-8800D02*
Y-6300D01*
G01X1501900Y-9200D02*
X1501500Y-8800D01*
G01X1501900Y-9124D02*
Y-9200D01*
G01X1526376Y5076D02*
X1524800Y3500D01*
G01X1576024Y5076D02*
X1526376D01*
G01X1505150Y750D02*
X1495300Y-9100D01*
G01X1506650Y750D02*
X1505150D01*
G01X1509400Y3500D02*
X1506650Y750D01*
G01X1518427Y84535D02*
X1531424D01*
G01X1514892Y81000D02*
X1518427Y84535D01*
G01X1511900Y81000D02*
X1514892D01*
G01X1492922Y99978D02*
X1511900Y81000D01*
G01X1520709Y90218D02*
X1527527D01*
G01X1516801Y86310D02*
X1520709Y90218D01*
G01X1516801Y84253D02*
Y86310D01*
G01X1515263Y82715D02*
X1516801Y84253D01*
G01X1511348Y82715D02*
X1515263D01*
G01X1494580Y99483D02*
X1511348Y82715D01*
G01X1505864Y75506D02*
X1540647D01*
G01X1487090Y94280D02*
X1505864Y75506D01*
G01X1487090Y101959D02*
Y94280D01*
G01X1504925Y72902D02*
X1541586D01*
G01X1483892Y93935D02*
X1504925Y72902D01*
G01X1483892Y100287D02*
Y93935D01*
G01X1485671Y94069D02*
Y100730D01*
G01X1505486Y74254D02*
X1485671Y94069D01*
G01X1541025Y74254D02*
X1505486D01*
G01X1526464Y86117D02*
X1519599D01*
G01X1534897Y94550D02*
X1526464Y86117D01*
G01X1495894Y150600D02*
X1495848D01*
G01X1497726Y148768D02*
X1495894Y150600D01*
G01X1497726Y147973D02*
Y148768D01*
G01X1500885Y144814D02*
X1497726Y147973D01*
G01X1505300Y144814D02*
X1500885D01*
G01X1505924Y144190D02*
X1505300Y144814D01*
G01X1510837Y144190D02*
X1505924D01*
G01X1511750Y143277D02*
X1510837Y144190D01*
G01X1515836Y143277D02*
X1511750D01*
G01X1517813Y141300D02*
X1515836Y143277D01*
G01X1524971Y141300D02*
X1517813D01*
G01X1525657Y140614D02*
X1524971Y141300D01*
G01X1526963Y140614D02*
X1525657D01*
G01X1527771Y141422D02*
X1526963Y140614D01*
G01X1473649Y149248D02*
X1469862Y145461D01*
G01X1473678Y149248D02*
X1473649D01*
G01X1476298Y151868D02*
X1473678Y149248D01*
G01X1476298Y151897D02*
Y151868D01*
G01X1476722Y152321D02*
X1476298Y151897D01*
G01X1476722Y152621D02*
Y152321D01*
G01X1476826Y152725D02*
X1476722Y152621D01*
G01X1476761Y152725D02*
X1476826D01*
G01X1479800Y149751D02*
X1476826Y152725D01*
G01X1479800Y145668D02*
Y149751D01*
G01X1490353Y135115D02*
X1479800Y145668D01*
G01X1505884Y135115D02*
X1490353D01*
G01X1509436Y131563D02*
X1505884Y135115D01*
G01X1514164Y131563D02*
X1509436D01*
G01X1518201Y135600D02*
X1514164Y131563D01*
G01X1525220Y135600D02*
X1518201D01*
G01X1528604Y138984D02*
X1525220Y135600D01*
G01X1534275Y142190D02*
X1526310D01*
G01X1524755Y122545D02*
X1524000Y123300D01*
G01X1527249Y122545D02*
X1524755D01*
G01X1492922Y105821D02*
Y99978D01*
G01X1490848Y107895D02*
X1492922Y105821D01*
G01X1483906Y107895D02*
X1490848D01*
G01X1477910Y113891D02*
X1483906Y107895D01*
G01X1477910Y116185D02*
Y113891D01*
G01X1473096Y120999D02*
X1477910Y116185D01*
G01X1494580Y105227D02*
Y99483D01*
G01X1491160Y108647D02*
X1494580Y105227D01*
G01X1485456Y108647D02*
X1491160D01*
G01X1478918Y115185D02*
X1485456Y108647D01*
G01X1478918Y122425D02*
Y115185D01*
G01X1475943Y125400D02*
X1478918Y122425D01*
G01X1471200Y125400D02*
X1475943D01*
G01X1470460Y126140D02*
X1471200Y125400D01*
G01X1470460Y129912D02*
Y126140D01*
G01X1472448Y131900D02*
X1470460Y129912D01*
G01X1473100Y131900D02*
X1472448D01*
G01X1526513Y139100D02*
X1527901Y140488D01*
G01X1524900Y139100D02*
X1526513D01*
G01X1500176Y106924D02*
X1498810Y108290D01*
G01X1502256Y106924D02*
X1500176D01*
G01X1507069Y111737D02*
X1502256Y106924D01*
G01X1514496Y111737D02*
X1507069D01*
G01X1520921Y118162D02*
X1514496Y111737D01*
G01X1520921Y123450D02*
Y118162D01*
G01X1523215Y125744D02*
X1520921Y123450D01*
G01X1527381Y125744D02*
X1523215D01*
G01X1512372Y144783D02*
X1527539D01*
G01X1511461Y145694D02*
X1512372Y144783D01*
G01X1508648Y145694D02*
X1511461D01*
G01X1504229Y150113D02*
X1508648Y145694D01*
G01X1498612Y150113D02*
X1504229D01*
G01X1496549Y152176D02*
X1498612Y150113D01*
G01X1494675Y152176D02*
X1496549D01*
G01X1492827Y150328D02*
X1494675Y152176D01*
G01X1492827Y146298D02*
Y150328D01*
G01X1489753Y143224D02*
X1492827Y146298D01*
G01X1488064Y143224D02*
X1489753D01*
G01X1486724Y144564D02*
X1488064Y143224D01*
G01X1486724Y159124D02*
Y144564D01*
G01X1500203Y144062D02*
X1496150Y148115D01*
G01X1504988Y144062D02*
X1500203D01*
G01X1505612Y143438D02*
X1504988Y144062D01*
G01X1505612Y142889D02*
Y143438D01*
G01X1507463Y141038D02*
X1505612Y142889D01*
G01X1510837Y141038D02*
X1507463D01*
G01X1512077Y142278D02*
X1510837Y141038D01*
G01X1515771Y142278D02*
X1512077D01*
G01X1521649Y136400D02*
X1515771Y142278D01*
G01X1524900Y136400D02*
X1521649D01*
G01X1528236Y139736D02*
X1524900Y136400D01*
G01X1475100Y113949D02*
X1487090Y101959D01*
G01X1475100Y116400D02*
Y113949D01*
G01X1473200Y118300D02*
X1475100Y116400D01*
G01X1522543Y128806D02*
X1533189D01*
G01X1520358Y130991D02*
X1522543Y128806D01*
G01X1518514Y130991D02*
X1520358D01*
G01X1520604Y128054D02*
X1520150Y127600D01*
G01X1533501Y128054D02*
X1520604D01*
G01X1522903Y126496D02*
X1527693D01*
G01X1520169Y123762D02*
X1522903Y126496D01*
G01X1520169Y119639D02*
Y123762D01*
G01X1513879Y113349D02*
X1520169Y119639D01*
G01X1522196Y101104D02*
X1530200D01*
G01X1520442Y99350D02*
X1522196Y101104D01*
G01X1517785Y99350D02*
X1520442D01*
G01X1516862Y100273D02*
X1517785Y99350D01*
G01X1516862Y107312D02*
Y100273D01*
G01X1518376Y108826D02*
X1516862Y107312D01*
G01X1518376Y111499D02*
Y108826D01*
G01X1475561Y155453D02*
X1473354Y153246D01*
G01X1477043Y155453D02*
X1475561D01*
G01X1486390Y164800D02*
X1477043Y155453D01*
G01X1475575Y108604D02*
X1483892Y100287D01*
G01X1474206Y108604D02*
X1475575D01*
G01X1472897Y109914D02*
X1474206Y108604D01*
G01X1472897Y115406D02*
Y109914D01*
G01X1471503Y116800D02*
X1472897Y115406D01*
G01X1471503Y122703D02*
Y116800D01*
G01X1472500Y123700D02*
X1471503Y122703D01*
G01X1520671Y100926D02*
X1518438D01*
G01X1521845Y102100D02*
X1520671Y100926D01*
G01X1529849Y102100D02*
X1521845D01*
G01X1524030Y110734D02*
X1528118D01*
G01X1521689Y113075D02*
X1524030Y110734D01*
G01X1517535Y113075D02*
X1521689D01*
G01X1515445Y110985D02*
X1517535Y113075D01*
G01X1507381Y110985D02*
X1515445D01*
G01X1502568Y106172D02*
X1507381Y110985D01*
G01X1498699Y106172D02*
X1502568D01*
G01X1497150Y107721D02*
X1498699Y106172D01*
G01X1497150Y109737D02*
Y107721D01*
G01X1496930Y109957D02*
X1497150Y109737D01*
G01X1496930Y109994D02*
Y109957D01*
G01X1494808Y112116D02*
X1496930Y109994D01*
G01X1494808Y116509D02*
Y112116D01*
G01X1487114Y124222D02*
X1494808Y116509D01*
G01X1482455Y124222D02*
X1487114D01*
G01X1515643Y151743D02*
X1515358D01*
G01X1517924Y154024D02*
X1515643Y151743D01*
G01X1532353Y154024D02*
X1517924D01*
G01X1521521Y151632D02*
X1533618D01*
G01X1518328Y148439D02*
X1521521Y151632D01*
G01X1514170Y148439D02*
X1518328D01*
G01X1513059Y149550D02*
X1514170Y148439D01*
G01X1510246Y149550D02*
X1513059D01*
G01X1505374Y154422D02*
X1510246Y149550D01*
G01X1501040Y154422D02*
X1505374D01*
G01X1500643Y154819D02*
X1501040Y154422D01*
G01X1523296Y130310D02*
X1532565D01*
G01X1520276Y133330D02*
X1523296Y130310D01*
G01X1517211Y133330D02*
X1520276D01*
G01X1514692Y130811D02*
X1517211Y133330D01*
G01X1491807Y130811D02*
X1514692D01*
G01X1480018Y142600D02*
X1491807Y130811D01*
G01X1475200Y142600D02*
X1480018D01*
G01X1505617Y146346D02*
X1505673D01*
G01X1505617Y146116D02*
Y146346D01*
G01X1506791Y144942D02*
X1505617Y146116D01*
G01X1511149Y144942D02*
X1506791D01*
G01X1512062Y144029D02*
X1511149Y144942D01*
G01X1527071Y144029D02*
X1512062D01*
G01X1528158Y142942D02*
X1527071Y144029D01*
G01X1514600Y129655D02*
Y126650D01*
G01X1517523Y132578D02*
X1514600Y129655D01*
G01X1519865Y132578D02*
X1517523D01*
G01X1522885Y129558D02*
X1519865Y132578D01*
G01X1532877Y129558D02*
X1522885D01*
G01X1476031Y110370D02*
X1474717D01*
G01X1485671Y100730D02*
X1476031Y110370D01*
G01X1479053Y128950D02*
X1473100D01*
G01X1481357Y126646D02*
X1479053Y128950D01*
G01X1497451Y126646D02*
X1481357D01*
G01X1499831Y129026D02*
X1497451Y126646D01*
G01X1504454Y129026D02*
X1499831D01*
G01X1510181Y123299D02*
X1504454Y129026D01*
G01X1518449Y123299D02*
X1510181D01*
G01X1522408Y127258D02*
X1518449Y123299D01*
G01X1533769Y127258D02*
X1522408D01*
G01X1521209Y152384D02*
X1533306D01*
G01X1518016Y149191D02*
X1521209Y152384D01*
G01X1514482Y149191D02*
X1518016D01*
G01X1513371Y150302D02*
X1514482Y149191D01*
G01X1511038Y150302D02*
X1513371D01*
G01X1499398Y161942D02*
X1511038Y150302D01*
G01X1513700Y154000D02*
X1513500Y153800D01*
G01X1515599Y154000D02*
X1513700D01*
G01X1525656Y164057D02*
X1515599Y154000D01*
G01X1475146Y152809D02*
X1472737Y150400D01*
G01X1475146Y153339D02*
Y152809D01*
G01X1476108Y154301D02*
X1475146Y153339D01*
G01X1477800Y154301D02*
X1476108D01*
G01X1486775Y163276D02*
X1477800Y154301D01*
G01X1508900Y155284D02*
X1500556Y163628D01*
G01X1508900Y154400D02*
Y155284D01*
G01X1511600Y151700D02*
X1508900Y154400D01*
G01X1513172Y151700D02*
X1511600D01*
G01X1514705Y150167D02*
X1513172Y151700D01*
G01X1516867Y150167D02*
X1514705D01*
G01X1519836Y153136D02*
X1516867Y150167D01*
G01X1532928Y153136D02*
X1519836D01*
G01X1499064Y156085D02*
X1495649Y159500D01*
G01X1499064Y153262D02*
Y156085D01*
G01X1499416Y152910D02*
X1499064Y153262D01*
G01X1505822Y152910D02*
X1499416D01*
G01X1509934Y148798D02*
X1505822Y152910D01*
G01X1512747Y148798D02*
X1509934D01*
G01X1513858Y147687D02*
X1512747Y148798D01*
G01X1527183Y147687D02*
X1513858D01*
G01X1488800Y147012D02*
Y145000D01*
G01X1490237Y148449D02*
X1488800Y147012D01*
G01X1490237Y156756D02*
Y148449D01*
G01X1497614Y155340D02*
X1496444Y156510D01*
G01X1497614Y152759D02*
Y155340D01*
G01X1498664Y151709D02*
X1497614Y152759D01*
G01X1498664Y151691D02*
Y151709D01*
G01X1499090Y151265D02*
X1498664Y151691D01*
G01X1505271Y151265D02*
X1499090D01*
G01X1505534Y151002D02*
X1505271Y151265D01*
G01X1505535Y151002D02*
X1505534D01*
G01X1509291Y147246D02*
X1505535Y151002D01*
G01X1512104Y147246D02*
X1509291D01*
G01X1513015Y146335D02*
X1512104Y147246D01*
G01X1527461Y146335D02*
X1513015D01*
G01X1488300Y160700D02*
X1486724Y159124D01*
G01X1488300Y161700D02*
Y160700D01*
G01X1496356Y164800D02*
X1486390D01*
G01X1496362Y164806D02*
X1496356Y164800D01*
G01X1498624Y164806D02*
X1496362D01*
G01X1498630Y164800D02*
X1498624Y164806D01*
G01X1499516Y164800D02*
X1498630D01*
G01X1501163Y166447D02*
X1499516Y164800D01*
G01X1506053Y166447D02*
X1501163D01*
G01X1508076Y164424D02*
X1506053Y166447D01*
G01X1521013Y164424D02*
X1508076D01*
G01X1525938Y169349D02*
X1521013Y164424D01*
G01X1526802Y169349D02*
X1525938D01*
G01X1528753Y171300D02*
X1526802Y169349D01*
G01X1491131Y178256D02*
X1492500Y176887D01*
G01X1487397Y178256D02*
X1491131D01*
G01X1483491Y174350D02*
X1487397Y178256D01*
G01X1481350Y174350D02*
X1483491D01*
G01X1478402Y171402D02*
X1481350Y174350D01*
G01X1481828Y173198D02*
X1478880Y170250D01*
G01X1483969Y173198D02*
X1481828D01*
G01X1487451Y176680D02*
X1483969Y173198D01*
G01X1489088Y176680D02*
X1487451D01*
G01X1524309Y164809D02*
X1529666D01*
G01X1516581Y157081D02*
X1524309Y164809D01*
G01X1513136Y157081D02*
X1516581D01*
G01X1506673Y162904D02*
X1504706Y164871D01*
G01X1521098Y162904D02*
X1506673D01*
G01X1524005Y165811D02*
X1521098Y162904D01*
G01X1528688Y165811D02*
X1524005D01*
G01X1497629Y161942D02*
X1499398D01*
G01X1497493Y162078D02*
X1497629Y161942D01*
G01X1532006Y164057D02*
X1525656D01*
G01X1489524Y163276D02*
X1486775D01*
G01X1491676Y161124D02*
X1489524Y163276D01*
G01X1494024Y161124D02*
X1491676D01*
G01X1496528Y163628D02*
X1494024Y161124D01*
G01X1496814Y163628D02*
X1496528D01*
G01X1496840Y163654D02*
X1496814Y163628D01*
G01X1498146Y163654D02*
X1496840D01*
G01X1498172Y163628D02*
X1498146Y163654D01*
G01X1500556Y163628D02*
X1498172D01*
G01X1495649Y159500D02*
X1494939D01*
G01X1491409Y157928D02*
X1490237Y156756D01*
G01X1493465Y157928D02*
X1491409D01*
G01X1494883Y156510D02*
X1493465Y157928D01*
G01X1496444Y156510D02*
X1494883D01*
G01X1503132Y254432D02*
X1505946D01*
G01X1500646Y251946D02*
X1503132Y254432D01*
G01X1491464Y251946D02*
X1500646D01*
G01X1491463Y251945D02*
X1491464Y251946D01*
G01X1490841Y251945D02*
X1491463D01*
G01X1490840Y251946D02*
X1490841Y251945D01*
G01X1490175Y251946D02*
X1490840D01*
G01X1487135Y254986D02*
X1490175Y251946D01*
G01X1485843Y254986D02*
X1487135D01*
G01X1485277Y254420D02*
X1485843Y254986D01*
G01X1483920Y254420D02*
X1485277D01*
G01X1479013Y249513D02*
X1483920Y254420D01*
G01X1475478Y277152D02*
X1474230Y278400D01*
G01X1475478Y275877D02*
Y277152D01*
G01X1476143Y275212D02*
X1475478Y275877D01*
G01X1477562Y275212D02*
X1476143D01*
G01X1478508Y274266D02*
X1477562Y275212D01*
G01X1478508Y272895D02*
Y274266D01*
G01X1479357Y272046D02*
X1478508Y272895D01*
G01X1481021Y272046D02*
X1479357D01*
G01X1481620Y271447D02*
X1481021Y272046D01*
G01X1481620Y266852D02*
Y271447D01*
G01X1482935Y265537D02*
X1481620Y266852D01*
G01X1487590Y265537D02*
X1482935D01*
G01X1490007Y267954D02*
X1487590Y265537D01*
G01X1491127Y267954D02*
X1490007D01*
G01X1492308Y269135D02*
X1491127Y267954D01*
G01X1531008Y269135D02*
X1492308D01*
G01X1472328Y274672D02*
X1471717Y275283D01*
G01X1472328Y272994D02*
Y274672D01*
G01X1473275Y272047D02*
X1472328Y272994D01*
G01X1474690Y272047D02*
X1473275D01*
G01X1475395Y271342D02*
X1474690Y272047D01*
G01X1475395Y268613D02*
Y271342D01*
G01X1479493Y264515D02*
X1475395Y268613D01*
G01X1481831Y264515D02*
X1479493D01*
G01X1482312Y264034D02*
X1481831Y264515D01*
G01X1488214Y264034D02*
X1482312D01*
G01X1488636Y264456D02*
X1488214Y264034D01*
G01X1489610Y264456D02*
X1488636D01*
G01X1489611Y264457D02*
X1489610Y264456D01*
G01X1496128Y264457D02*
X1489611D01*
G01X1496443Y264772D02*
X1496128Y264457D01*
G01X1496444Y264772D02*
X1496443D01*
G01X1499185Y267513D02*
X1496444Y264772D01*
G01X1530502Y267513D02*
X1499185D01*
G01X1470649Y272798D02*
Y273603D01*
G01X1472241Y271206D02*
X1470649Y272798D01*
G01X1472241Y269322D02*
Y271206D01*
G01X1477800Y263763D02*
X1472241Y269322D01*
G01X1481519Y263763D02*
X1477800D01*
G01X1482000Y263282D02*
X1481519Y263763D01*
G01X1488526Y263282D02*
X1482000D01*
G01X1488948Y263704D02*
X1488526Y263282D01*
G01X1496440Y263704D02*
X1488948D01*
G01X1499497Y266761D02*
X1496440Y263704D01*
G01X1530190Y266761D02*
X1499497D01*
G01X1493193Y270639D02*
X1531632D01*
G01X1491908Y271924D02*
X1493193Y270639D01*
G01X1487867Y271924D02*
X1491908D01*
G01X1486397Y270454D02*
X1487867Y271924D01*
G01X1500172Y265148D02*
X1529588D01*
G01X1497224Y262200D02*
X1500172Y265148D01*
G01X1489572Y262200D02*
X1497224D01*
G01X1488872Y261500D02*
X1489572Y262200D01*
G01X1481436Y261500D02*
X1488872D01*
G01X1480677Y262259D02*
X1481436Y261500D01*
G01X1476677Y262259D02*
X1480677D01*
G01X1474747Y264189D02*
X1476677Y262259D01*
G01X1474747Y264190D02*
Y264189D01*
G01X1473498Y265439D02*
X1474747Y264190D01*
G01X1469220Y265439D02*
X1473498D01*
G01X1471329Y262744D02*
X1471328Y262743D01*
G01X1471951Y262744D02*
X1471329D01*
G01X1471952Y262743D02*
X1471951Y262744D01*
G01X1472598Y262743D02*
X1471952D01*
G01X1475338Y260003D02*
X1472598Y262743D01*
G01X1479550Y260003D02*
X1475338D01*
G01X1480309Y259244D02*
X1479550Y260003D01*
G01X1489844Y259244D02*
X1480309D01*
G01X1490537Y259937D02*
X1489844Y259244D01*
G01X1498153Y259937D02*
X1490537D01*
G01X1501108Y262892D02*
X1498153Y259937D01*
G01X1516868Y262892D02*
X1501108D01*
G01X1524136Y255624D02*
X1516868Y262892D01*
G01X1535916Y255624D02*
X1524136D01*
G01X1501853Y276738D02*
X1605336D01*
G01X1500409Y275294D02*
X1501853Y276738D01*
G01X1490167Y275294D02*
X1500409D01*
G01X1487006Y272133D02*
X1490167Y275294D01*
G01X1482492Y272133D02*
X1487006D01*
G01X1481673Y272952D02*
X1482492Y272133D01*
G01X1481673Y274697D02*
Y272952D01*
G01X1481273Y275097D02*
X1481673Y274697D01*
G01X1479207Y275097D02*
X1481273D01*
G01X1477551Y276753D02*
X1479207Y275097D01*
G01X1476948Y276753D02*
X1477551D01*
G01X1494677Y271800D02*
X1492753Y273724D01*
G01X1504299Y271800D02*
X1494677D01*
G01X1507725Y275226D02*
X1504299Y271800D01*
G01X1604720Y275226D02*
X1507725D01*
G01X1522459Y252204D02*
X1532890D01*
G01X1515927Y258736D02*
X1522459Y252204D01*
G01X1510374Y258736D02*
X1515927D01*
G01X1508432Y256794D02*
X1510374Y258736D01*
G01X1503366Y256794D02*
X1508432D01*
G01X1500022Y253450D02*
X1503366Y256794D01*
G01X1492030Y253450D02*
X1500022D01*
G01X1488990Y256490D02*
X1492030Y253450D01*
G01X1485219Y256490D02*
X1488990D01*
G01X1484653Y255924D02*
X1485219Y256490D01*
G01X1482374Y255924D02*
X1484653D01*
G01X1479047Y259251D02*
X1482374Y255924D01*
G01X1474380Y259251D02*
X1479047D01*
G01X1471640Y261991D02*
X1474380Y259251D01*
G01X1523250Y239990D02*
X1539190D01*
G01X1520750Y237490D02*
X1523250Y239990D01*
G01X1509630Y237490D02*
X1520750D01*
G01X1505280Y241840D02*
X1509630Y237490D01*
G01X1499150Y241840D02*
X1505280D01*
G01X1497250Y243740D02*
X1499150Y241840D01*
G01X1489470Y243740D02*
X1497250D01*
G01X1486860Y241130D02*
X1489470Y243740D01*
G01X1477940Y241130D02*
X1486860D01*
G01X1476560Y239750D02*
X1477940Y241130D01*
G01X1521575Y250426D02*
X1531856D01*
G01X1515200Y256801D02*
X1521575Y250426D01*
G01X1511391Y256801D02*
X1515200D01*
G01X1503290Y248700D02*
X1511391Y256801D01*
G01X1497824Y248700D02*
X1503290D01*
G01X1496280Y250244D02*
X1497824Y248700D01*
G01X1490711Y250244D02*
X1496280D01*
G01X1486918Y254037D02*
X1490711Y250244D01*
G01X1485958Y254037D02*
X1486918D01*
G01X1485589Y253668D02*
X1485958Y254037D01*
G01X1484232Y253668D02*
X1485589D01*
G01X1479325Y248761D02*
X1484232Y253668D01*
G01X1498873Y268265D02*
X1530814D01*
G01X1495816Y265208D02*
X1498873Y268265D01*
G01X1488324Y265208D02*
X1495816D01*
G01X1487902Y264786D02*
X1488324Y265208D01*
G01X1482623Y264786D02*
X1487902D01*
G01X1482143Y265266D02*
X1482623Y264786D01*
G01X1480057Y265266D02*
X1482143D01*
G01X1478607Y266716D02*
X1480057Y265266D01*
G01X1478607Y271438D02*
Y266716D01*
G01X1477912Y272133D02*
X1478607Y271438D01*
G01X1475900Y272133D02*
X1477912D01*
G01X1474430Y273603D02*
X1475900Y272133D01*
G01X1473798Y273603D02*
X1474430D01*
G01X1481852Y250224D02*
X1479637Y248009D01*
G01X1485353Y250224D02*
X1481852D01*
G01X1485948Y250819D02*
X1485353Y250224D01*
G01X1489072Y250819D02*
X1485948D01*
G01X1490399Y249492D02*
X1489072Y250819D01*
G01X1495968Y249492D02*
X1490399D01*
G01X1497960Y247500D02*
X1495968Y249492D01*
G01X1503214Y247500D02*
X1497960D01*
G01X1511315Y255601D02*
X1503214Y247500D01*
G01X1515299Y255601D02*
X1511315D01*
G01X1522300Y248600D02*
X1515299Y255601D01*
G01X1525550Y248600D02*
X1522300D01*
G01X1525650Y248700D02*
X1525550Y248600D01*
G01X1467764Y243774D02*
X1465690D01*
G01X1468566Y244576D02*
X1467764Y243774D01*
G01X1477454Y244576D02*
X1468566D01*
G01X1479108Y246230D02*
X1477454Y244576D01*
G01X1482989Y246230D02*
X1479108D01*
G01X1486426Y249667D02*
X1482989Y246230D01*
G01X1488532Y249667D02*
X1486426D01*
G01X1491400Y246799D02*
X1488532Y249667D01*
G01X1494801Y246799D02*
X1491400D01*
G01X1495885Y245715D02*
X1494801Y246799D01*
G01X1500326Y245715D02*
X1495885D01*
G01X1502147Y243894D02*
X1500326Y245715D01*
G01X1507189Y243894D02*
X1502147D01*
G01X1507983Y243100D02*
X1507189Y243894D01*
G01X1510796Y243100D02*
X1507983D01*
G01X1511647Y243951D02*
X1510796Y243100D01*
G01X1511647Y250300D02*
Y243951D01*
G01X1512598Y251251D02*
X1511647Y250300D01*
G01X1516951Y251251D02*
X1512598D01*
G01X1521102Y247100D02*
X1516951Y251251D01*
G01X1521106Y247100D02*
X1521102D01*
G01X1522246Y245960D02*
X1521106Y247100D01*
G01X1529121Y245960D02*
X1522246D01*
G01X1475532Y236525D02*
X1474002Y238055D01*
G01X1491888Y236525D02*
X1475532D01*
G01X1495878Y240515D02*
X1491888Y236525D01*
G01X1504162Y240515D02*
X1495878D01*
G01X1507953Y236724D02*
X1504162Y240515D01*
G01X1518006Y236724D02*
X1507953D01*
G01X1519510Y235220D02*
X1518006Y236724D01*
G01X1523692Y235220D02*
X1519510D01*
G01X1526090Y237618D02*
X1523692Y235220D01*
G01X1538652Y237618D02*
X1526090D01*
G01X1517281Y241324D02*
X1516613Y240656D01*
G01X1519614Y241324D02*
X1517281D01*
G01X1522650Y244360D02*
X1519614Y241324D01*
G01X1524850Y244360D02*
X1522650D01*
G01X1527218Y241992D02*
X1524850Y244360D01*
G01X1508800Y244676D02*
X1509800D01*
G01X1507140Y246336D02*
X1508800Y244676D01*
G01X1507140Y249446D02*
Y246336D01*
G01X1510495Y252801D02*
X1507140Y249446D01*
G01X1510495Y253625D02*
Y252801D01*
G01X1511719Y254849D02*
X1510495Y253625D01*
G01X1514987Y254849D02*
X1511719D01*
G01X1522712Y247124D02*
X1514987Y254849D01*
G01X1529666Y247124D02*
X1522712D01*
G01X1517239Y279086D02*
X1520517Y282364D01*
G01X1503148Y279086D02*
X1517239D01*
G01X1499188Y283046D02*
X1503148Y279086D01*
G01X1475334Y279437D02*
Y280445D01*
G01X1476339Y278432D02*
X1475334Y279437D01*
G01X1480932Y278432D02*
X1476339D01*
G01X1481714Y277650D02*
X1480932Y278432D01*
G01X1481714Y275885D02*
Y277650D01*
G01X1482316Y275283D02*
X1481714Y275885D01*
G01X1488883Y275283D02*
X1482316D01*
G01X1489646Y276046D02*
X1488883Y275283D01*
G01X1500062Y276046D02*
X1489646D01*
G01X1501598Y277582D02*
X1500062Y276046D01*
G01X1518283Y277582D02*
X1501598D01*
G01X1521561Y280860D02*
X1518283Y277582D01*
G01X1518780Y265900D02*
X1529900D01*
G01X1518779Y265901D02*
X1518780Y265900D01*
G01X1518157Y265901D02*
X1518779D01*
G01X1518156Y265900D02*
X1518157Y265901D01*
G01X1499700Y265900D02*
X1518156D01*
G01X1496752Y262952D02*
X1499700Y265900D01*
G01X1489260Y262952D02*
X1496752D01*
G01X1488608Y262300D02*
X1489260Y262952D01*
G01X1481700Y262300D02*
X1488608D01*
G01X1480989Y263011D02*
X1481700Y262300D01*
G01X1477089Y263011D02*
X1480989D01*
G01X1471116Y268984D02*
X1477089Y263011D01*
G01X1466916Y268984D02*
X1471116D01*
G01X1482530Y278432D02*
X1480231Y280731D01*
G01X1494214Y278432D02*
X1482530D01*
G01X1495345Y279563D02*
X1494214Y278432D01*
G01X1498944Y278354D02*
X1497735Y279563D01*
G01X1499008Y278354D02*
X1498944D01*
G01X1499028Y278334D02*
X1499008Y278354D01*
G01X1517787Y278334D02*
X1499028D01*
G01X1521065Y281612D02*
X1517787Y278334D01*
G01X1525593Y236057D02*
X1530953D01*
G01X1523946Y234410D02*
X1525593Y236057D01*
G01X1519220Y234410D02*
X1523946D01*
G01X1517658Y235972D02*
X1519220Y234410D01*
G01X1507538Y235972D02*
X1517658D01*
G01X1503820Y239690D02*
X1507538Y235972D01*
G01X1496220Y239690D02*
X1503820D01*
G01X1492230Y235700D02*
X1496220Y239690D01*
G01X1475190Y235700D02*
X1492230D01*
G01X1473660Y237230D02*
X1475190Y235700D01*
G01X1500484Y264396D02*
X1529276D01*
G01X1497536Y261448D02*
X1500484Y264396D01*
G01X1489884Y261448D02*
X1497536D01*
G01X1489184Y260748D02*
X1489884Y261448D01*
G01X1481124Y260748D02*
X1489184D01*
G01X1480365Y261507D02*
X1481124Y260748D01*
G01X1476031Y261507D02*
X1480365D01*
G01X1473187Y264351D02*
X1476031Y261507D01*
G01X1469245Y264351D02*
X1473187D01*
G01X1525209Y245120D02*
X1527585Y242744D01*
G01X1522235Y245120D02*
X1525209D01*
G01X1519867Y242752D02*
X1522235Y245120D01*
G01X1518427Y242752D02*
X1519867D01*
G01X1517379Y243800D02*
X1518427Y242752D01*
G01X1517379Y248704D02*
Y243800D01*
G01X1515830Y250253D02*
X1517379Y248704D01*
G01X1515106Y250253D02*
X1515830D01*
G01X1515067Y250292D02*
X1515106Y250253D01*
G01X1513677Y250292D02*
X1515067D01*
G01X1512500Y249115D02*
X1513677Y250292D01*
G01X1512500Y243565D02*
Y249115D01*
G01X1511297Y242362D02*
X1512500Y243565D01*
G01X1511297Y242302D02*
Y242362D01*
G01X1507507Y242302D02*
X1511297D01*
G01X1506691Y243118D02*
X1507507Y242302D01*
G01X1501785Y243118D02*
X1506691D01*
G01X1499940Y244963D02*
X1501785Y243118D01*
G01X1495573Y244963D02*
X1499940D01*
G01X1494960Y245576D02*
X1495573Y244963D01*
G01X1489387Y245576D02*
X1494960D01*
G01X1488829Y246134D02*
X1489387Y245576D01*
G01X1486513Y246134D02*
X1488829D01*
G01X1485033Y244654D02*
X1486513Y246134D01*
G01X1485033Y243915D02*
Y244654D01*
G01X1484021Y242903D02*
X1485033Y243915D01*
G01X1477003Y242903D02*
X1484021D01*
G01X1475455Y241355D02*
X1477003Y242903D01*
G01X1468465Y241355D02*
X1475455D01*
G01X1466798Y243022D02*
X1468465Y241355D01*
G01X1465378Y243022D02*
X1466798D01*
G01X1521755Y240840D02*
X1520413Y239498D01*
G01X1539645Y240840D02*
X1521755D01*
G01X1497331Y257510D02*
X1495682Y255861D01*
G01X1497854Y257510D02*
X1497331D01*
G01X1501344Y261000D02*
X1497854Y257510D01*
G01X1516357Y261000D02*
X1501344D01*
G01X1523489Y253868D02*
X1516357Y261000D01*
G01X1533500Y253868D02*
X1523489D01*
G01X1525530Y238370D02*
X1539350D01*
G01X1525120Y237960D02*
X1525530Y238370D01*
G01X1523580Y237960D02*
X1525120D01*
G01X1506021Y275986D02*
X1605024D01*
G01X1504461Y274426D02*
X1506021Y275986D01*
G01X1523946Y254654D02*
X1533948D01*
G01X1516600Y262000D02*
X1523946Y254654D01*
G01X1501280Y262000D02*
X1516600D01*
G01X1497641Y258361D02*
X1501280Y262000D01*
G01X1495696Y258361D02*
X1497641D01*
G01X1471017Y263496D02*
X1471016Y263495D01*
G01X1472263Y263496D02*
X1471017D01*
G01X1472264Y263495D02*
X1472263Y263496D01*
G01X1472910Y263495D02*
X1472264D01*
G01X1475650Y260755D02*
X1472910Y263495D01*
G01X1479862Y260755D02*
X1475650D01*
G01X1480617Y260000D02*
X1479862Y260755D01*
G01X1480808Y260000D02*
X1480617D01*
G01X1480812Y259996D02*
X1480808Y260000D01*
G01X1489496Y259996D02*
X1480812D01*
G01X1490196Y260696D02*
X1489496Y259996D01*
G01X1497848Y260696D02*
X1490196D01*
G01X1500796Y263644D02*
X1497848Y260696D01*
G01X1528964Y263644D02*
X1500796D01*
G01X1494425Y254281D02*
X1493199Y255507D01*
G01X1499789Y254281D02*
X1494425D01*
G01X1503132Y257624D02*
X1499789Y254281D01*
G01X1507845Y257624D02*
X1503132D01*
G01X1510109Y259888D02*
X1507845Y257624D01*
G01X1516405Y259888D02*
X1510109D01*
G01X1523212Y253081D02*
X1516405Y259888D01*
G01X1533223Y253081D02*
X1523212D01*
G01X1471186Y258499D02*
X1470957Y258728D01*
G01X1478735Y258499D02*
X1471186D01*
G01X1482062Y255172D02*
X1478735Y258499D01*
G01X1484965Y255172D02*
X1482062D01*
G01X1485531Y255738D02*
X1484965Y255172D01*
G01X1488112Y255738D02*
X1485531D01*
G01X1491152Y252698D02*
X1488112Y255738D01*
G01X1500334Y252698D02*
X1491152D01*
G01X1503678Y256042D02*
X1500334Y252698D01*
G01X1508744Y256042D02*
X1503678D01*
G01X1510255Y257553D02*
X1508744Y256042D01*
G01X1516046Y257553D02*
X1510255D01*
G01X1522302Y251297D02*
X1516046Y257553D01*
G01X1532285Y251297D02*
X1522302D01*
G01X1496188Y269887D02*
X1531320D01*
G01X1496187Y269886D02*
X1496188Y269887D01*
G01X1491996Y269886D02*
X1496187D01*
G01X1491094Y268984D02*
X1491996Y269886D01*
G01X1484927Y268984D02*
X1491094D01*
G01X1483247Y267304D02*
X1484927Y268984D01*
G01X1468939Y254890D02*
X1465929Y257900D01*
G01X1478610Y254890D02*
X1468939D01*
G01X1479000Y254500D02*
X1478610Y254890D01*
G01X1529683Y307015D02*
X1526936D01*
G01X1472328Y304698D02*
X1471258Y303628D01*
G01X1472328Y305707D02*
Y304698D01*
G01X1473380Y306759D02*
X1472328Y305707D01*
G01X1494571Y306759D02*
X1473380D01*
G01X1496528Y304802D02*
X1494571Y306759D01*
G01X1498969Y304802D02*
X1496528D01*
G01X1502758Y301013D02*
X1498969Y304802D01*
G01X1542729Y301013D02*
X1502758D01*
G01X1481568Y300268D02*
X1480098Y298798D01*
G01X1490049Y300268D02*
X1481568D01*
G01X1490987Y299330D02*
X1490049Y300268D01*
G01X1494008Y299330D02*
X1490987D01*
G01X1494199Y299521D02*
X1494008Y299330D01*
G01X1496226Y299521D02*
X1494199D01*
G01X1497969Y297778D02*
X1496226Y299521D01*
G01X1511983Y297778D02*
X1497969D01*
G01X1512562Y298357D02*
X1511983Y297778D01*
G01X1541627Y298357D02*
X1512562D01*
G01X1525846Y323580D02*
X1529734Y319692D01*
G01X1521481Y323580D02*
X1525846D01*
G01X1520809Y324252D02*
X1521481Y323580D01*
G01X1473272Y324252D02*
X1520809D01*
G01X1472525Y323505D02*
X1473272Y324252D01*
G01X1469203Y323505D02*
X1472525D01*
G01X1468503Y322805D02*
X1469203Y323505D01*
G01X1491434Y295513D02*
X1489349Y293428D01*
G01X1518514Y295513D02*
X1491434D01*
G01X1523489Y290538D02*
X1518514Y295513D01*
G01X1527546Y290538D02*
X1523489D01*
G01X1524964Y331811D02*
X1528007D01*
G01X1522253Y329100D02*
X1524964Y331811D01*
G01X1521340Y329100D02*
X1522253D01*
G01X1518430Y332010D02*
X1521340Y329100D01*
G01X1516190Y332010D02*
X1518430D01*
G01X1515430Y331250D02*
X1516190Y332010D01*
G01X1515430Y329920D02*
Y331250D01*
G01X1514610Y329100D02*
X1515430Y329920D01*
G01X1511850Y329100D02*
X1514610D01*
G01X1510600Y327850D02*
X1511850Y329100D01*
G01X1497650Y327850D02*
X1510600D01*
G01X1493800Y331700D02*
X1497650Y327850D01*
G01X1472413Y331700D02*
X1493800D01*
G01X1471440Y332673D02*
X1472413Y331700D01*
G01X1523064Y310171D02*
X1529550D01*
G01X1519762Y306869D02*
X1523064Y310171D01*
G01X1514529Y306869D02*
X1519762D01*
G01X1510187Y311211D02*
X1514529Y306869D01*
G01X1510187Y313538D02*
Y311211D01*
G01X1509108Y314617D02*
X1510187Y313538D01*
G01X1500003Y314617D02*
X1509108D01*
G01X1495454Y319166D02*
X1500003Y314617D01*
G01X1487866Y319166D02*
X1495454D01*
G01X1486396Y317696D02*
X1487866Y319166D01*
G01X1526760Y315260D02*
X1528400Y316900D01*
G01X1517910Y315260D02*
X1526760D01*
G01X1515200Y317970D02*
X1517910Y315260D01*
G01X1511199Y317970D02*
X1515200D01*
G01X1506421Y322748D02*
X1511199Y317970D01*
G01X1477950Y322748D02*
X1506421D01*
G01X1473882Y318680D02*
X1477950Y322748D01*
G01X1473798Y318680D02*
X1473882D01*
G01X1473778Y318660D02*
X1473798Y318680D01*
G01X1468846Y318660D02*
X1473778D01*
G01X1466916Y316730D02*
X1468846Y318660D01*
G01X1521793Y304646D02*
X1529613D01*
G01X1520841Y303694D02*
X1521793Y304646D01*
G01X1503835Y303694D02*
X1520841D01*
G01X1501711Y305818D02*
X1503835Y303694D01*
G01X1501711Y308300D02*
Y305818D01*
G01X1496994Y313017D02*
X1501711Y308300D01*
G01X1476489Y313017D02*
X1496994D01*
G01X1475450Y311978D02*
X1476489Y313017D01*
G01X1475450Y310970D02*
Y311978D01*
G01X1474369Y309889D02*
X1475450Y310970D01*
G01X1473361Y309889D02*
X1474369D01*
G01X1472192Y308720D02*
X1473361Y309889D01*
G01X1472192Y307711D02*
Y308720D01*
G01X1471049Y306568D02*
X1472192Y307711D01*
G01X1468769Y306568D02*
X1471049D01*
G01X1467299Y305098D02*
X1468769Y306568D01*
G01X1490098Y305098D02*
X1486397D01*
G01X1490870Y305870D02*
X1490098Y305098D01*
G01X1494109Y305870D02*
X1490870D01*
G01X1496033Y303946D02*
X1494109Y305870D01*
G01X1496033Y302509D02*
Y303946D01*
G01X1496898Y301644D02*
X1496033Y302509D01*
G01X1498121Y301644D02*
X1496898D01*
G01X1498159Y301682D02*
X1498121Y301644D01*
G01X1500393Y301682D02*
X1498159D01*
G01X1502214Y299861D02*
X1500393Y301682D01*
G01X1542251Y299861D02*
X1502214D01*
G01X1523304Y309347D02*
X1529790D01*
G01X1520074Y306117D02*
X1523304Y309347D01*
G01X1512729Y306117D02*
X1520074D01*
G01X1506765Y312081D02*
X1512729Y306117D01*
G01X1501379Y312081D02*
X1506765D01*
G01X1495764Y317696D02*
X1501379Y312081D01*
G01X1489546Y317696D02*
X1495764D01*
G01X1475478Y295250D02*
X1474407Y294179D01*
G01X1475478Y296258D02*
Y295250D01*
G01X1476548Y297328D02*
X1475478Y296258D01*
G01X1493070Y297328D02*
X1476548D01*
G01X1494512Y298770D02*
X1493070Y297328D01*
G01X1495913Y298770D02*
X1494512D01*
G01X1497843Y296840D02*
X1495913Y298770D01*
G01X1518817Y296840D02*
X1497843D01*
G01X1519582Y297605D02*
X1518817Y296840D01*
G01X1541315Y297605D02*
X1519582D01*
G01X1523167Y313566D02*
X1535437D01*
G01X1518774Y309173D02*
X1523167Y313566D01*
G01X1515485Y309173D02*
X1518774D01*
G01X1512491Y312167D02*
X1515485Y309173D01*
G01X1512491Y314550D02*
Y312167D01*
G01X1506831Y320210D02*
X1512491Y314550D01*
G01X1503409Y320210D02*
X1506831D01*
G01X1501493Y318294D02*
X1503409Y320210D01*
G01X1500187Y318294D02*
X1501493D01*
G01X1497361Y321120D02*
X1500187Y318294D01*
G01X1478665Y321120D02*
X1497361D01*
G01X1474627Y317082D02*
X1478665Y321120D01*
G01X1470043Y317082D02*
X1474627D01*
G01X1465828Y312867D02*
X1470043Y317082D01*
G01X1475325Y309774D02*
X1473798Y308247D01*
G01X1491121Y309774D02*
X1475325D01*
G01X1492208Y308687D02*
X1491121Y309774D01*
G01X1497955Y308687D02*
X1492208D01*
G01X1498947Y307695D02*
X1497955Y308687D01*
G01X1498947Y307694D02*
Y307695D01*
G01X1499698Y306943D02*
X1498947Y307694D01*
G01X1499699Y306943D02*
X1499698D01*
G01X1500206Y306436D02*
X1499699Y306943D01*
G01X1500206Y305195D02*
Y306436D01*
G01X1503236Y302165D02*
X1500206Y305195D01*
G01X1543207Y302165D02*
X1503236D01*
G01X1479197Y291600D02*
X1476948Y289351D01*
G01X1488500Y291600D02*
X1479197D01*
G01X1489100Y291000D02*
X1488500Y291600D01*
G01X1502371Y291000D02*
X1489100D01*
G01X1503171Y290200D02*
X1502371Y291000D01*
G01X1519036Y290200D02*
X1503171D01*
G01X1520585Y288651D02*
X1519036Y290200D01*
G01X1527787Y288651D02*
X1520585D01*
G01X1494644Y328250D02*
X1492540D01*
G01X1497890Y325004D02*
X1494644Y328250D01*
G01X1521222Y325004D02*
X1497890D01*
G01X1521834Y324392D02*
X1521222Y325004D01*
G01X1528043Y324392D02*
X1521834D01*
G01X1526720Y316600D02*
X1527772Y317652D01*
G01X1522230Y316600D02*
X1526720D01*
G01X1519510Y319320D02*
X1522230Y316600D01*
G01X1510913Y319320D02*
X1519510D01*
G01X1506733Y323500D02*
X1510913Y319320D01*
G01X1474260Y323500D02*
X1506733D01*
G01X1470575Y319815D02*
X1474260Y323500D01*
G01X1468812Y319815D02*
X1470575D01*
G01X1467421Y318424D02*
X1468812Y319815D01*
G01X1465541Y318424D02*
X1467421D01*
G01X1521481Y305398D02*
X1529301D01*
G01X1520698Y304615D02*
X1521481Y305398D01*
G01X1504738Y304615D02*
X1520698D01*
G01X1502786Y306567D02*
X1504738Y304615D01*
G01X1502786Y308363D02*
Y306567D01*
G01X1496603Y314546D02*
X1502786Y308363D01*
G01X1495699Y314546D02*
X1496603D01*
G01X1481568Y284732D02*
X1480098Y286202D01*
G01X1499830Y284732D02*
X1481568D01*
G01X1500443Y284119D02*
X1499830Y284732D01*
G01X1549489Y284119D02*
X1500443D01*
G01X1475300Y289928D02*
X1474407Y290821D01*
G01X1475300Y288920D02*
Y289928D01*
G01X1476339Y287881D02*
X1475300Y288920D01*
G01X1477557Y287881D02*
X1476339D01*
G01X1478600Y288924D02*
X1477557Y287881D01*
G01X1478600Y289932D02*
Y288924D01*
G01X1479489Y290821D02*
X1478600Y289932D01*
G01X1487679Y290821D02*
X1479489D01*
G01X1488400Y290100D02*
X1487679Y290821D01*
G01X1502207Y290100D02*
X1488400D01*
G01X1502907Y289400D02*
X1502207Y290100D01*
G01X1518772Y289400D02*
X1502907D01*
G01X1520273Y287899D02*
X1518772Y289400D01*
G01X1528099Y287899D02*
X1520273D01*
G01X1516301Y315670D02*
Y313244D01*
G01X1514761Y317210D02*
X1516301Y315670D01*
G01X1510895Y317210D02*
X1514761D01*
G01X1506109Y321996D02*
X1510895Y317210D01*
G01X1478262Y321996D02*
X1506109D01*
G01X1474174Y317908D02*
X1478262Y321996D01*
G01X1469516Y317908D02*
X1474174D01*
G01X1467587Y315979D02*
X1469516Y317908D01*
G01X1472944Y311397D02*
X1473798D01*
G01X1471264Y309717D02*
X1472944Y311397D01*
G01X1470040Y309717D02*
X1471264D01*
G01X1466973Y306650D02*
X1470040Y309717D01*
G01X1520517Y282364D02*
X1549862D01*
G01X1492690Y283046D02*
X1499188D01*
G01X1489546Y279902D02*
X1492690Y283046D01*
G01X1475334Y280445D02*
X1474407Y281372D01*
G01X1552060Y280860D02*
X1521561D01*
G01X1474407Y284522D02*
X1465821D01*
G01X1475278Y283651D02*
X1474407Y284522D01*
G01X1475278Y282643D02*
Y283651D01*
G01X1476375Y281546D02*
X1475278Y282643D01*
G01X1477383Y281546D02*
X1476375D01*
G01X1478198Y280731D02*
X1477383Y281546D01*
G01X1480231Y280731D02*
X1478198D01*
G01X1497735Y279563D02*
X1495345D01*
G01X1550321Y281612D02*
X1521065D01*
G01X1468399Y325661D02*
Y324930D01*
G01X1470597Y327859D02*
X1468399Y325661D01*
G01X1487629Y327859D02*
X1470597D01*
G01X1490070Y330300D02*
X1487629Y327859D01*
G01X1494100Y330300D02*
X1490070D01*
G01X1498644Y325756D02*
X1494100Y330300D01*
G01X1521534Y325756D02*
X1498644D01*
G01X1522146Y325144D02*
X1521534Y325756D01*
G01X1528355Y325144D02*
X1522146D01*
G01X1482596Y328611D02*
X1484100Y330115D01*
G01X1487349Y289351D02*
X1483247D01*
G01X1488100Y288600D02*
X1487349Y289351D01*
G01X1490253Y288600D02*
X1488100D01*
G01X1492453Y286400D02*
X1490253Y288600D01*
G01X1505900Y286400D02*
X1492453D01*
G01X1507155Y285145D02*
X1505900Y286400D01*
G01X1517338Y285145D02*
X1507155D01*
G01X1517353Y285130D02*
X1517338Y285145D01*
G01X1518659Y285130D02*
X1517353D01*
G01X1518674Y285145D02*
X1518659Y285130D01*
G01X1527945Y285145D02*
X1518674D01*
G01X1523098Y311835D02*
X1525677D01*
G01X1519284Y308021D02*
X1523098Y311835D01*
G01X1515007Y308021D02*
X1519284D01*
G01X1511339Y311689D02*
X1515007Y308021D01*
G01X1511339Y314051D02*
Y311689D01*
G01X1509510Y315880D02*
X1511339Y314051D01*
G01X1500510Y315880D02*
X1509510D01*
G01X1496371Y320019D02*
X1500510Y315880D01*
G01X1482247Y320019D02*
X1496371D01*
G01X1479434Y317206D02*
X1482247Y320019D01*
G01X1477772Y317206D02*
X1479434D01*
G01X1476697Y316131D02*
X1477772Y317206D01*
G01X1470155Y316131D02*
X1476697D01*
G01X1467240Y313216D02*
X1470155Y316131D01*
G01X1467240Y312207D02*
Y313216D01*
G01X1522855Y314318D02*
X1535749D01*
G01X1519286Y310749D02*
X1522855Y314318D01*
G01X1516138Y310749D02*
X1519286D01*
G01X1514163Y333732D02*
X1528654D01*
G01X1513731Y334164D02*
X1514163Y333732D01*
G01X1513731Y334662D02*
Y334164D01*
G01X1514934Y335865D02*
X1513731Y334662D01*
G01X1514934Y336362D02*
Y335865D01*
G01X1514434Y336862D02*
X1514934Y336362D01*
G01X1513938Y336862D02*
X1514434D01*
G01X1512734Y335657D02*
X1513938Y336862D01*
G01X1512238Y335657D02*
X1512734D01*
G01X1511739Y336156D02*
X1512238Y335657D01*
G01X1511739Y336654D02*
Y336156D01*
G01X1512942Y337857D02*
X1511739Y336654D01*
G01X1512942Y338354D02*
Y337857D01*
G01X1512442Y338854D02*
X1512942Y338354D01*
G01X1511946Y338854D02*
X1512442D01*
G01X1511372Y338280D02*
X1511946Y338854D01*
G01X1509819Y338280D02*
X1511372D01*
G01X1507150Y340949D02*
X1509819Y338280D01*
G01X1507150Y341800D02*
Y340949D01*
G01X1475333Y286746D02*
X1474407Y287672D01*
G01X1475333Y285738D02*
Y286746D01*
G01X1476550Y284521D02*
X1475333Y285738D01*
G01X1477558Y284521D02*
X1476550D01*
G01X1478628Y283451D02*
X1477558Y284521D01*
G01X1478628Y282443D02*
Y283451D01*
G01X1479489Y281582D02*
X1478628Y282443D01*
G01X1487440Y281582D02*
X1479489D01*
G01X1489656Y283798D02*
X1487440Y281582D01*
G01X1499500Y283798D02*
X1489656D01*
G01X1499931Y283367D02*
X1499500Y283798D01*
G01X1549801Y283367D02*
X1499931D01*
G01X1474800Y339400D02*
X1467978D01*
G01X1478900Y335300D02*
X1474800Y339400D01*
G01X1488492Y335300D02*
X1478900D01*
G01X1490792Y333000D02*
X1488492Y335300D01*
G01X1494300Y333000D02*
X1490792D01*
G01X1498298Y329002D02*
X1494300Y333000D01*
G01X1508946Y329002D02*
X1498298D01*
G01X1510584Y330640D02*
X1508946Y329002D01*
G01X1475440Y298361D02*
X1474407Y297328D01*
G01X1475440Y299369D02*
Y298361D01*
G01X1476471Y300400D02*
X1475440Y299369D01*
G01X1477479Y300400D02*
X1476471D01*
G01X1478500Y301421D02*
X1477479Y300400D01*
G01X1478500Y302429D02*
Y301421D01*
G01X1479489Y303418D02*
X1478500Y302429D01*
G01X1492403Y303418D02*
X1479489D01*
G01X1492891Y302930D02*
X1492403Y303418D01*
G01X1494006Y302930D02*
X1492891D01*
G01X1498406Y298530D02*
X1494006Y302930D01*
G01X1511170Y298530D02*
X1498406D01*
G01X1511749Y299109D02*
X1511170Y298530D01*
G01X1541939Y299109D02*
X1511749D01*
G01X1513077Y332980D02*
X1528095D01*
G01X1511597Y334460D02*
X1513077Y332980D01*
G01X1506520Y334460D02*
X1511597D01*
G01X1503490Y337490D02*
X1506520Y334460D01*
G01X1503490Y339990D02*
Y337490D01*
G01X1498828Y344652D02*
X1503490Y339990D01*
G01X1494196Y309880D02*
X1492700Y311376D01*
G01X1497825Y309880D02*
X1494196D01*
G01X1500010Y307695D02*
X1497825Y309880D01*
G01X1500011Y307695D02*
X1500010D01*
G01X1500959Y306747D02*
X1500011Y307695D01*
G01X1500959Y306130D02*
Y306747D01*
G01X1500958Y306129D02*
X1500959Y306130D01*
G01X1500958Y305507D02*
Y306129D01*
G01X1503523Y302942D02*
X1500958Y305507D01*
G01X1521153Y302942D02*
X1503523D01*
G01X1522105Y303894D02*
X1521153Y302942D01*
G01X1529925Y303894D02*
X1522105D01*
G01X1526504Y328100D02*
X1533529D01*
G01X1525051Y329553D02*
X1526504Y328100D01*
G01X1475268Y303628D02*
X1473798Y305098D01*
G01X1475268Y301339D02*
Y303628D01*
G01X1474407Y300478D02*
X1475268Y301339D01*
G01X1489301Y291950D02*
X1488900Y292351D01*
G01X1502550Y291950D02*
X1489301D01*
G01X1503400Y291100D02*
X1502550Y291950D01*
G01X1519200Y291100D02*
X1503400D01*
G01X1520514Y289786D02*
X1519200Y291100D01*
G01X1527858Y289786D02*
X1520514D01*
G01X1526307Y392682D02*
X1538798D01*
G01X1524575Y394414D02*
X1526307Y392682D01*
G01X1499605Y401825D02*
X1500795Y403015D01*
G01X1499605Y400523D02*
Y401825D01*
G01X1501555Y398573D02*
X1499605Y400523D01*
G01X1501555Y397143D02*
Y398573D01*
G01X1502474Y396224D02*
X1501555Y397143D01*
G01X1503776Y396224D02*
X1502474D01*
G01X1504558Y397006D02*
X1503776Y396224D01*
G01X1507022Y397006D02*
X1504558D01*
G01X1507405Y396623D02*
X1507022Y397006D01*
G01X1507405Y393763D02*
Y396623D01*
G01X1508324Y392844D02*
X1507405Y393763D01*
G01X1511336Y392844D02*
X1508324D01*
G01X1513255Y390925D02*
X1511336Y392844D01*
G01X1513255Y390383D02*
Y390925D01*
G01X1515205Y388433D02*
X1513255Y390383D01*
G01X1515205Y387003D02*
Y388433D01*
G01X1517155Y385053D02*
X1515205Y387003D01*
G01X1517155Y383623D02*
Y385053D01*
G01X1518314Y382464D02*
X1517155Y383623D01*
G01X1529126Y382464D02*
X1518314D01*
G01X1470299Y357000D02*
X1479149Y348150D01*
G01X1517367Y349633D02*
Y349964D01*
G01X1520827Y346173D02*
X1517367Y349633D01*
G01X1531500Y346173D02*
X1520827D01*
G01X1491045Y402655D02*
X1489800Y403900D01*
G01X1491045Y400004D02*
Y402655D01*
G01X1489855Y398814D02*
X1491045Y400004D01*
G01X1489855Y396762D02*
Y398814D01*
G01X1491045Y395572D02*
X1489855Y396762D01*
G01X1491045Y392875D02*
Y395572D01*
G01X1489855Y391685D02*
X1491045Y392875D01*
G01X1489855Y390383D02*
Y391685D01*
G01X1491045Y389193D02*
X1489855Y390383D01*
G01X1491045Y386115D02*
Y389193D01*
G01X1489855Y384925D02*
X1491045Y386115D01*
G01X1489855Y383623D02*
Y384925D01*
G01X1491805Y381673D02*
X1489855Y383623D01*
G01X1491805Y380243D02*
Y381673D01*
G01X1492724Y379324D02*
X1491805Y380243D01*
G01X1507436Y379324D02*
X1492724D01*
G01X1509000Y377760D02*
X1507436Y379324D01*
G01X1509000Y376700D02*
Y377760D01*
G01X1515328Y370372D02*
X1509000Y376700D01*
G01X1515328Y363389D02*
Y370372D01*
G01X1521055Y375944D02*
X1522625Y377514D01*
G01X1514174Y375944D02*
X1521055D01*
G01X1513255Y376863D02*
X1514174Y375944D01*
G01X1513255Y378293D02*
Y376863D01*
G01X1510545Y381003D02*
X1513255Y378293D01*
G01X1510545Y381545D02*
Y381003D01*
G01X1509626Y382464D02*
X1510545Y381545D01*
G01X1498814Y382464D02*
X1509626D01*
G01X1496895Y384383D02*
X1498814Y382464D01*
G01X1496895Y384925D02*
Y384383D01*
G01X1495705Y386115D02*
X1496895Y384925D01*
G01X1495705Y388305D02*
Y386115D01*
G01X1496895Y389495D02*
X1495705Y388305D01*
G01X1496895Y391685D02*
Y389495D01*
G01X1494945Y393635D02*
X1496895Y391685D01*
G01X1494945Y395065D02*
Y393635D01*
G01X1493755Y396255D02*
X1494945Y395065D01*
G01X1493755Y399333D02*
Y396255D01*
G01X1494945Y400523D02*
X1493755Y399333D01*
G01X1494945Y403255D02*
Y400523D01*
G01X1498854Y401816D02*
X1494945Y405725D01*
G01X1498854Y399644D02*
Y401816D01*
G01X1497655Y398445D02*
X1498854Y399644D01*
G01X1497655Y397015D02*
Y398445D01*
G01X1499605Y395065D02*
X1497655Y397015D01*
G01X1499605Y393763D02*
Y395065D01*
G01X1500524Y392844D02*
X1499605Y393763D01*
G01X1503856Y392844D02*
X1500524D01*
G01X1505455Y391245D02*
X1503856Y392844D01*
G01X1505455Y390383D02*
Y391245D01*
G01X1506374Y389464D02*
X1505455Y390383D01*
G01X1509386Y389464D02*
X1506374D01*
G01X1511305Y387545D02*
X1509386Y389464D01*
G01X1511305Y387003D02*
Y387545D01*
G01X1513255Y385053D02*
X1511305Y387003D01*
G01X1513255Y383623D02*
Y385053D01*
G01X1515205Y381673D02*
X1513255Y383623D01*
G01X1515205Y380243D02*
Y381673D01*
G01X1516124Y379324D02*
X1515205Y380243D01*
G01X1523036Y379324D02*
X1516124D01*
G01X1524955Y377405D02*
X1523036Y379324D01*
G01X1524955Y376863D02*
Y377405D01*
G01X1526400Y375418D02*
X1524955Y376863D01*
G01X1526400Y354566D02*
Y375418D01*
G01X1536214Y344752D02*
X1526400Y354566D01*
G01X1507000Y402358D02*
X1505455Y403903D01*
G01X1507000Y399498D02*
Y402358D01*
G01X1507989Y398509D02*
X1507000Y399498D01*
G01X1509419Y398509D02*
X1507989D01*
G01X1510274Y399364D02*
X1509419Y398509D01*
G01X1515476Y399364D02*
X1510274D01*
G01X1516395Y398445D02*
X1515476Y399364D01*
G01X1516395Y397015D02*
Y398445D01*
G01X1518345Y395065D02*
X1516395Y397015D01*
G01X1518345Y393763D02*
Y395065D01*
G01X1519504Y392604D02*
X1518345Y393763D01*
G01X1523276Y392604D02*
X1519504D01*
G01X1524195Y391685D02*
X1523276Y392604D01*
G01X1524195Y391143D02*
Y391685D01*
G01X1525988Y389350D02*
X1524195Y391143D01*
G01X1536800Y389350D02*
X1525988D01*
G01X1471163Y376125D02*
Y378264D01*
G01X1472604Y374684D02*
X1471163Y376125D01*
G01X1474915Y374684D02*
X1472604D01*
G01X1482251Y367348D02*
X1474915Y374684D01*
G01X1488733Y367348D02*
X1482251D01*
G01X1490803Y365278D02*
X1488733Y367348D01*
G01X1490803Y353525D02*
Y365278D01*
G01X1489915Y352637D02*
X1490803Y353525D01*
G01X1505252Y343698D02*
X1507150Y341800D01*
G01X1502280Y343698D02*
X1505252D01*
G01X1500360Y345618D02*
X1502280Y343698D01*
G01X1491551Y345618D02*
X1500360D01*
G01X1486631Y350538D02*
X1491551Y345618D01*
G01X1486631Y358519D02*
Y350538D01*
G01X1488479Y360367D02*
X1486631Y358519D01*
G01X1491453Y344652D02*
X1498828D01*
G01X1485879Y350226D02*
X1491453Y344652D01*
G01X1485879Y359884D02*
Y350226D01*
G01X1484637Y361126D02*
X1485879Y359884D01*
G01X1479156Y361126D02*
X1484637D01*
G01X1478612Y361670D02*
X1479156Y361126D01*
G01X1479034Y451337D02*
Y473094D01*
G01X1481929Y448442D02*
X1479034Y451337D01*
G01X1483832Y448442D02*
X1481929D01*
G01X1487518Y444756D02*
X1483832Y448442D01*
G01X1487518Y442624D02*
Y444756D01*
G01X1489407Y440735D02*
X1487518Y442624D01*
G01X1489407Y439341D02*
Y440735D01*
G01X1487163Y437097D02*
X1489407Y439341D01*
G01X1487163Y427158D02*
Y437097D01*
G01X1489070Y425251D02*
X1487163Y427158D01*
G01X1489070Y423270D02*
Y425251D01*
G01X1487905Y422105D02*
X1489070Y423270D01*
G01X1487905Y420803D02*
Y422105D01*
G01X1489855Y418853D02*
X1487905Y420803D01*
G01X1489855Y417423D02*
Y418853D01*
G01X1491014Y416264D02*
X1489855Y417423D01*
G01X1494026Y416264D02*
X1491014D01*
G01X1494945Y415345D02*
X1494026Y416264D01*
G01X1494945Y413915D02*
Y415345D01*
G01X1496895Y411965D02*
X1494945Y413915D01*
G01X1496895Y410220D02*
Y411965D01*
G01X1499000Y408115D02*
X1496895Y410220D01*
G01X1499000Y407000D02*
Y408115D01*
G01X1500795Y405205D02*
X1499000Y407000D01*
G01X1500795Y403015D02*
Y405205D01*
G01X1526826Y453018D02*
X1527542D01*
G01X1525315Y454529D02*
X1526826Y453018D01*
G01X1516181Y454529D02*
X1525315D01*
G01X1514434Y452782D02*
X1516181Y454529D01*
G01X1508720Y452782D02*
X1514434D01*
G01X1508122Y452184D02*
X1508720Y452782D01*
G01X1499944Y452184D02*
X1508122D01*
G01X1499876Y452116D02*
X1499944Y452184D01*
G01X1492068Y452116D02*
X1499876D01*
G01X1491073Y451121D02*
X1492068Y452116D01*
G01X1491073Y447278D02*
Y451121D01*
G01X1491425Y446926D02*
X1491073Y447278D01*
G01X1475380Y444987D02*
Y470172D01*
G01X1477624Y442743D02*
X1475380Y444987D01*
G01X1477624Y440183D02*
Y442743D01*
G01X1479317Y438490D02*
X1477624Y440183D01*
G01X1479317Y419182D02*
Y438490D01*
G01X1481399Y417100D02*
X1479317Y419182D01*
G01X1481904Y417100D02*
X1481399D01*
G01X1483900Y415104D02*
X1481904Y417100D01*
G01X1483900Y411600D02*
Y415104D01*
G01X1486900Y408600D02*
X1483900Y411600D01*
G01X1486900Y408100D02*
Y408600D01*
G01X1489800Y405200D02*
X1486900Y408100D01*
G01X1489800Y403900D02*
Y405200D01*
G01X1491500Y406700D02*
X1494945Y403255D01*
G01X1491500Y408130D02*
Y406700D01*
G01X1490126Y409504D02*
X1491500Y408130D01*
G01X1487114Y409504D02*
X1490126D01*
G01X1485700Y410918D02*
X1487114Y409504D01*
G01X1485700Y414794D02*
Y410918D01*
G01X1483750Y416744D02*
X1485700Y414794D01*
G01X1483750Y419191D02*
Y416744D01*
G01X1482441Y420500D02*
X1483750Y419191D01*
G01X1481937Y420500D02*
X1482441D01*
G01X1480068Y422369D02*
X1481937Y420500D01*
G01X1480068Y438802D02*
Y422369D01*
G01X1478375Y440495D02*
X1480068Y438802D01*
G01X1478375Y443055D02*
Y440495D01*
G01X1476132Y445298D02*
X1478375Y443055D01*
G01X1476132Y471649D02*
Y445298D01*
G01X1478283Y444517D02*
Y476616D01*
G01X1479438Y443362D02*
X1478283Y444517D01*
G01X1479438Y440495D02*
Y443362D01*
G01X1480819Y439114D02*
X1479438Y440495D01*
G01X1480819Y429997D02*
Y439114D01*
G01X1483570Y427246D02*
X1480819Y429997D01*
G01X1483570Y422809D02*
Y427246D01*
G01X1485388Y420991D02*
X1483570Y422809D01*
G01X1485388Y416560D02*
Y420991D01*
G01X1489064Y412884D02*
X1485388Y416560D01*
G01X1492076Y412884D02*
X1489064D01*
G01X1492995Y411965D02*
X1492076Y412884D01*
G01X1492995Y410535D02*
Y411965D01*
G01X1494945Y408585D02*
X1492995Y410535D01*
G01X1494945Y405725D02*
Y408585D01*
G01X1485125Y456625D02*
X1483375Y458375D01*
G01X1485125Y450987D02*
Y456625D01*
G01X1491146Y444966D02*
X1485125Y450987D01*
G01X1491146Y443420D02*
Y444966D01*
G01X1493149Y441417D02*
X1491146Y443420D01*
G01X1493149Y439461D02*
Y441417D01*
G01X1495201Y437409D02*
X1493149Y439461D01*
G01X1495201Y435986D02*
Y437409D01*
G01X1493173Y433958D02*
X1495201Y435986D01*
G01X1493173Y432558D02*
Y433958D01*
G01X1494945Y430786D02*
X1493173Y432558D01*
G01X1494945Y427769D02*
Y430786D01*
G01X1497084Y425630D02*
X1494945Y427769D01*
G01X1497084Y423537D02*
Y425630D01*
G01X1498770Y421851D02*
X1497084Y423537D01*
G01X1498770Y420549D02*
Y421851D01*
G01X1498058Y419837D02*
X1498770Y420549D01*
G01X1498058Y417228D02*
Y419837D01*
G01X1504193Y411093D02*
X1498058Y417228D01*
G01X1504193Y410471D02*
Y411093D01*
G01X1503505Y409783D02*
X1504193Y410471D01*
G01X1503505Y407155D02*
Y409783D01*
G01X1505455Y405205D02*
X1503505Y407155D01*
G01X1505455Y403903D02*
Y405205D01*
G01X1481564Y475624D02*
X1535345D01*
G01X1479034Y473094D02*
X1481564Y475624D01*
G01X1486261Y485916D02*
X1568964D01*
G01X1484459Y487718D02*
X1486261Y485916D01*
G01X1480240Y487718D02*
X1484459D01*
G01X1477622Y485100D02*
X1480240Y487718D01*
G01X1472250Y485100D02*
X1477622D01*
G01X1477700Y487789D02*
X1466548D01*
G01X1481828Y491917D02*
X1477700Y487789D01*
G01X1485548Y491917D02*
X1481828D01*
G01X1486488Y492857D02*
X1485548Y491917D01*
G01X1491961Y492857D02*
X1486488D01*
G01X1492901Y491917D02*
X1491961Y492857D01*
G01X1492902Y491917D02*
X1492901D01*
G01X1494418Y490401D02*
X1492902Y491917D01*
G01X1578318Y490401D02*
X1494418D01*
G01X1495094Y491175D02*
X1578606D01*
G01X1492661Y493608D02*
X1495094Y491175D01*
G01X1486176Y493608D02*
X1492661D01*
G01X1485236Y492668D02*
X1486176Y493608D01*
G01X1481224Y492668D02*
X1485236D01*
G01X1477238Y488682D02*
X1481224Y492668D01*
G01X1467030Y488682D02*
X1477238D01*
G01X1487331Y468891D02*
X1531427D01*
G01X1486322Y469900D02*
X1487331Y468891D01*
G01X1485100Y469900D02*
X1486322D01*
G01X1485665Y479148D02*
X1537181D01*
G01X1485014Y479799D02*
X1485665Y479148D01*
G01X1481466Y479799D02*
X1485014D01*
G01X1478283Y476616D02*
X1481466Y479799D01*
G01X1494106Y489649D02*
X1578006D01*
G01X1491649Y492106D02*
X1494106Y489649D01*
G01X1486800Y492106D02*
X1491649D01*
G01X1483163Y488469D02*
X1486800Y492106D01*
G01X1479928Y488469D02*
X1483163D01*
G01X1478235Y486776D02*
X1479928Y488469D01*
G01X1484747Y482456D02*
X1566111D01*
G01X1483638Y483565D02*
X1484747Y482456D01*
G01X1477167Y483565D02*
X1483638D01*
G01X1476058Y482456D02*
X1477167Y483565D01*
G01X1467154Y482456D02*
X1476058D01*
G01X1516035Y550661D02*
X1545006D01*
G01X1514543Y552153D02*
X1516035Y550661D01*
G01X1509424Y564541D02*
X1504949Y560066D01*
G01X1535704Y564541D02*
X1509424D01*
G01X1468649Y571969D02*
Y570012D01*
G01X1474762Y578082D02*
X1468649Y571969D01*
G01X1514779Y578082D02*
X1474762D01*
G01X1522096Y570765D02*
X1514779Y578082D01*
G01X1532556Y570765D02*
X1522096D01*
G01X1515363Y579490D02*
X1467854D01*
G01X1522680Y572173D02*
X1515363Y579490D01*
G01X1531972Y572173D02*
X1522680D01*
G01X1471831Y565793D02*
X1470817Y564779D01*
G01X1535185Y565793D02*
X1471831D01*
G01X1517471Y558132D02*
X1544186D01*
G01X1514596Y561007D02*
X1517471Y558132D01*
G01X1508676Y561007D02*
X1514596D01*
G01X1506483Y558814D02*
X1508676Y561007D01*
G01X1508876Y559436D02*
X1507002Y557562D01*
G01X1514396Y559436D02*
X1508876D01*
G01X1516952Y556880D02*
X1514396Y559436D01*
G01X1544705Y556880D02*
X1516952D01*
G01X1470898Y568261D02*
X1533594D01*
G01X1469821Y567184D02*
X1470898Y568261D01*
G01X1467477Y567184D02*
X1469821D01*
G01X1466989Y567672D02*
X1467477Y567184D01*
G01X1471353Y566945D02*
X1470340Y565932D01*
G01X1534707Y566945D02*
X1471353D01*
G01X1516513Y551813D02*
X1515021Y553305D01*
G01X1544528Y551813D02*
X1516513D01*
G01X1588651Y5049D02*
X1600501D01*
G01X1586724Y6976D02*
X1588651Y5049D01*
G01X1575876Y6976D02*
X1586724D01*
G01X1574903Y7949D02*
X1575876Y6976D01*
G01X1530251Y7949D02*
X1574903D01*
G01X1529400Y8800D02*
X1530251Y7949D01*
G01X1560680Y-4980D02*
X1552300Y3400D01*
G01X1575267Y-4980D02*
X1560680D01*
G01X1576167Y-4080D02*
X1575267Y-4980D01*
G01X1581841Y-4080D02*
X1576167D01*
G01X1582699Y-3222D02*
X1581841Y-4080D01*
G01X1590294Y-3222D02*
X1582699D01*
G01X1578946Y-10200D02*
X1622059D01*
G01X1576582Y-7836D02*
X1578946Y-10200D01*
G01X1555043Y-7836D02*
X1576582D01*
G01X1543807Y3400D02*
X1555043Y-7836D01*
G01X1543500Y3400D02*
X1543807D01*
G01X1583523Y-5126D02*
X1591084D01*
G01X1581947Y-6702D02*
X1583523Y-5126D01*
G01X1562228Y-4028D02*
X1554800Y3400D01*
G01X1574872Y-4028D02*
X1562228D01*
G01X1575772Y-3128D02*
X1574872Y-4028D01*
G01X1581446Y-3128D02*
X1575772D01*
G01X1582304Y-2270D02*
X1581446Y-3128D01*
G01X1589899Y-2270D02*
X1582304D01*
G01X1557084Y-6884D02*
X1546800Y3400D01*
G01X1576977Y-6884D02*
X1557084D01*
G01X1578371Y-8278D02*
X1576977Y-6884D01*
G01X1588855Y-8278D02*
X1578371D01*
G01X1564476Y-3076D02*
X1558000Y3400D01*
G01X1574324Y-3076D02*
X1564476D01*
G01X1575224Y-2176D02*
X1574324Y-3076D01*
G01X1581051Y-2176D02*
X1575224D01*
G01X1581909Y-1318D02*
X1581051Y-2176D01*
G01X1584983Y-1318D02*
X1581909D01*
G01X1587277Y976D02*
X1584983Y-1318D01*
G01X1590370Y976D02*
X1587277D01*
G01X1583094Y-4174D02*
X1590689D01*
G01X1582236Y-5032D02*
X1583094Y-4174D01*
G01X1576968Y-5032D02*
X1582236D01*
G01X1576068Y-5932D02*
X1576968Y-5032D01*
G01X1559132Y-5932D02*
X1576068D01*
G01X1549800Y3400D02*
X1559132Y-5932D01*
G01X1578100Y3000D02*
X1576024Y5076D01*
G01X1585260Y3000D02*
X1578100D01*
G01X1586160Y3900D02*
X1585260Y3000D01*
G01X1594102Y3900D02*
X1586160D01*
G01X1586882Y1928D02*
X1592498D01*
G01X1586050Y1096D02*
X1586882Y1928D01*
G01X1572349Y1096D02*
X1586050D01*
G01X1572125Y872D02*
X1572349Y1096D01*
G01X1563028Y872D02*
X1572125D01*
G01X1560500Y3400D02*
X1563028Y872D01*
G01X1578352Y-12300D02*
X1622953D01*
G01X1575792Y-9740D02*
X1578352Y-12300D01*
G01X1554253Y-9740D02*
X1575792D01*
G01X1543641Y872D02*
X1554253Y-9740D01*
G01X1536628Y872D02*
X1543641D01*
G01X1534000Y3500D02*
X1536628Y872D01*
G01X1541576Y1824D02*
X1540000Y3400D01*
G01X1544036Y1824D02*
X1541576D01*
G01X1554648Y-8788D02*
X1544036Y1824D01*
G01X1576187Y-8788D02*
X1554648D01*
G01X1578599Y-11200D02*
X1576187Y-8788D01*
G01X1622406Y-11200D02*
X1578599D01*
G01X1564776Y1824D02*
X1563200Y3400D01*
G01X1571730Y1824D02*
X1564776D01*
G01X1571954Y2048D02*
X1571730Y1824D01*
G01X1585655Y2048D02*
X1571954D01*
G01X1586487Y2880D02*
X1585655Y2048D01*
G01X1592893Y2880D02*
X1586487D01*
G01X1535100Y-800D02*
X1530800Y3500D01*
G01X1542565Y-800D02*
X1535100D01*
G01X1552565Y-10800D02*
X1542565Y-800D01*
G01X1557600Y-10800D02*
X1552565D01*
G01X1561100Y-14300D02*
X1557600Y-10800D01*
G01X1561100Y-18000D02*
Y-14300D01*
G01X1564700Y-21600D02*
X1561100Y-18000D01*
G01X1822600Y-21600D02*
X1564700D01*
G01X1586500Y-16100D02*
X1593200D01*
G01X1579615Y90992D02*
X1574780D01*
G01X1580623Y92000D02*
X1579615Y90992D01*
G01X1592579Y92000D02*
X1580623D01*
G01X1574780Y89848D02*
Y90992D01*
G01X1578023Y86605D02*
X1574780Y89848D01*
G01X1578023Y83277D02*
Y86605D01*
G01X1577171Y82425D02*
X1578023Y83277D01*
G01X1559264Y82425D02*
X1577171D01*
G01X1554909Y86780D02*
X1559264Y82425D01*
G01X1545566Y86780D02*
X1554909D01*
G01X1541187Y82401D02*
X1545566Y86780D01*
G01X1533558Y82401D02*
X1541187D01*
G01X1531424Y84535D02*
X1533558Y82401D01*
G01X1577994Y93763D02*
X1581247Y97016D01*
G01X1570767Y93763D02*
X1577994D01*
G01X1569240Y95290D02*
X1570767Y93763D01*
G01X1527527Y90218D02*
X1533033Y95724D01*
G01X1586101Y82750D02*
X1595250D01*
G01X1585197Y83654D02*
X1586101Y82750D01*
G01X1585197Y87075D02*
Y83654D01*
G01X1586622Y88500D02*
X1585197Y87075D01*
G01X1595521Y88500D02*
X1586622D01*
G01X1583327Y90927D02*
X1594026D01*
G01X1579400Y87000D02*
X1583327Y90927D01*
G01X1579400Y82610D02*
Y87000D01*
G01X1577273Y80483D02*
X1579400Y82610D01*
G01X1559047Y80483D02*
X1577273D01*
G01X1553730Y85800D02*
X1559047Y80483D01*
G01X1545700Y85800D02*
X1553730D01*
G01X1544600Y84700D02*
X1545700Y85800D01*
G01X1544600Y79459D02*
Y84700D01*
G01X1540647Y75506D02*
X1544600Y79459D01*
G01X1587597Y81116D02*
X1594563D01*
G01X1586212Y79731D02*
X1587597Y81116D01*
G01X1548609Y79731D02*
X1586212D01*
G01X1541980Y73102D02*
X1548609Y79731D01*
G01X1541786Y73102D02*
X1541980D01*
G01X1541586Y72902D02*
X1541786Y73102D01*
G01X1585300Y53389D02*
X1600852Y37837D01*
G01X1585300Y70288D02*
Y53389D01*
G01X1584748Y70840D02*
X1585300Y70288D01*
G01X1583005Y74350D02*
X1590621D01*
G01X1579916Y71261D02*
X1583005Y74350D01*
G01X1575066Y71261D02*
X1579916D01*
G01X1575018Y71213D02*
X1575066Y71261D01*
G01X1546370Y79599D02*
X1541025Y74254D01*
G01X1546370Y84180D02*
Y79599D01*
G01X1555646Y92584D02*
X1553680Y94550D01*
G01X1578445Y92584D02*
X1555646D01*
G01X1581725Y95864D02*
X1578445Y92584D01*
G01X1589174Y86163D02*
X1587359Y84348D01*
G01X1534851Y141422D02*
X1527771D01*
G01X1536672Y143243D02*
X1534851Y141422D01*
G01X1547370Y143243D02*
X1536672D01*
G01X1547376Y143249D02*
X1547370Y143243D01*
G01X1547377Y143249D02*
X1547376D01*
G01X1548193Y144065D02*
X1547377Y143249D01*
G01X1548193Y144066D02*
Y144065D01*
G01X1552920Y148793D02*
X1548193Y144066D01*
G01X1570852Y148793D02*
X1552920D01*
G01X1572473Y147172D02*
X1570852Y148793D01*
G01X1585277Y147172D02*
X1572473D01*
G01X1590569Y152464D02*
X1585277Y147172D01*
G01X1534071Y138984D02*
X1528604D01*
G01X1534771Y138284D02*
X1534071Y138984D01*
G01X1546183Y138284D02*
X1534771D01*
G01X1550370Y142471D02*
X1546183Y138284D01*
G01X1550370Y142491D02*
Y142471D01*
G01X1551910Y144031D02*
X1550370Y142491D01*
G01X1551930Y144031D02*
X1551910D01*
G01X1554270Y146371D02*
X1551930Y144031D01*
G01X1562529Y146371D02*
X1554270D01*
G01X1566869Y142031D02*
X1562529Y146371D01*
G01X1573032Y142031D02*
X1566869D01*
G01X1577433Y137630D02*
X1573032Y142031D01*
G01X1579773Y137630D02*
X1577433D01*
G01X1584013Y141870D02*
X1579773Y137630D01*
G01X1587452Y141870D02*
X1584013D01*
G01X1592498Y146916D02*
X1587452Y141870D01*
G01X1536080Y143995D02*
X1534275Y142190D01*
G01X1547058Y143995D02*
X1536080D01*
G01X1552743Y149680D02*
X1547058Y143995D01*
G01X1571308Y149680D02*
X1552743D01*
G01X1573064Y147924D02*
X1571308Y149680D01*
G01X1583462Y147924D02*
X1573064D01*
G01X1592038Y156500D02*
X1583462Y147924D01*
G01X1566724Y151474D02*
X1577250Y162000D01*
G01X1552130Y151474D02*
X1566724D01*
G01X1546353Y145697D02*
X1552130Y151474D01*
G01X1534102Y145697D02*
X1546353D01*
G01X1532923Y144518D02*
X1534102Y145697D01*
G01X1587885Y138386D02*
X1594764Y145265D01*
G01X1582657Y138386D02*
X1587885D01*
G01X1580397Y136126D02*
X1582657Y138386D01*
G01X1578863Y136126D02*
X1580397D01*
G01X1573758Y131021D02*
X1578863Y136126D01*
G01X1565263Y131021D02*
X1573758D01*
G01X1563739Y132545D02*
X1565263Y131021D01*
G01X1563739Y140395D02*
Y132545D01*
G01X1559563Y144571D02*
X1563739Y140395D01*
G01X1554841Y144571D02*
X1559563D01*
G01X1551874Y141604D02*
X1554841Y144571D01*
G01X1551874Y137334D02*
Y141604D01*
G01X1546285Y131745D02*
X1551874Y137334D01*
G01X1539256Y131745D02*
X1546285D01*
G01X1532851Y138150D02*
X1539256Y131745D01*
G01X1530159Y138150D02*
X1532851D01*
G01X1529449Y137440D02*
X1530159Y138150D01*
G01X1529449Y137408D02*
Y137440D01*
G01X1528289Y121505D02*
X1527249Y122545D01*
G01X1528289Y120483D02*
Y121505D01*
G01X1538472Y110300D02*
X1528289Y120483D01*
G01X1561529Y110300D02*
X1538472D01*
G01X1562651Y109178D02*
X1561529Y110300D01*
G01X1573048Y109178D02*
X1562651D01*
G01X1573790Y109920D02*
X1573048Y109178D01*
G01X1579277Y109920D02*
X1573790D01*
G01X1580657Y111300D02*
X1579277Y109920D01*
G01X1581671Y111300D02*
X1580657D01*
G01X1581847Y111476D02*
X1581671Y111300D01*
G01X1583153Y111476D02*
X1581847D01*
G01X1583329Y111300D02*
X1583153Y111476D01*
G01X1590542Y111300D02*
X1583329D01*
G01X1556389Y118111D02*
X1553500Y121000D01*
G01X1580693Y118111D02*
X1556389D01*
G01X1582807Y120225D02*
X1580693Y118111D01*
G01X1593050Y120225D02*
X1582807D01*
G01X1543435Y112330D02*
X1541765Y114000D01*
G01X1575377Y112330D02*
X1543435D01*
G01X1577035Y110672D02*
X1575377Y112330D01*
G01X1578965Y110672D02*
X1577035D01*
G01X1583744Y115451D02*
X1578965Y110672D01*
G01X1595239Y115451D02*
X1583744D01*
G01X1573567Y103721D02*
X1573153D01*
G01X1575958Y106112D02*
X1573567Y103721D01*
G01X1575959Y106111D02*
X1575958Y106112D01*
G01X1579736Y106111D02*
X1575959D01*
G01X1580947Y104900D02*
X1579736Y106111D01*
G01X1590536Y104900D02*
X1580947D01*
G01X1587886Y97016D02*
X1591518Y100648D01*
G01X1581247Y97016D02*
X1587886D01*
G01X1558400Y95290D02*
X1569240D01*
G01X1557110Y96580D02*
X1558400Y95290D01*
G01X1543409Y96580D02*
X1557110D01*
G01X1542553Y95724D02*
X1543409Y96580D01*
G01X1533033Y95724D02*
X1542553D01*
G01X1586653Y146222D02*
X1596131Y155700D01*
G01X1572359Y146222D02*
X1586653D01*
G01X1571652Y146929D02*
X1572359Y146222D01*
G01X1564099Y146929D02*
X1571652D01*
G01X1563153Y147875D02*
X1564099Y146929D01*
G01X1553346Y147875D02*
X1563153D01*
G01X1548103Y142632D02*
X1553346Y147875D01*
G01X1548102Y142632D02*
X1548103D01*
G01X1547763Y142293D02*
X1548102Y142632D01*
G01X1536786Y142293D02*
X1547763D01*
G01X1535095Y140602D02*
X1536786Y142293D01*
G01X1535094Y140602D02*
X1535095D01*
G01X1534980Y140488D02*
X1535094Y140602D01*
G01X1527901Y140488D02*
X1534980D01*
G01X1574000Y154946D02*
Y152100D01*
G01X1578951Y159897D02*
X1574000Y154946D01*
G01X1529048Y124077D02*
X1527381Y125744D01*
G01X1529048Y120788D02*
Y124077D01*
G01X1533894Y115942D02*
X1529048Y120788D01*
G01X1542392Y115942D02*
X1533894D01*
G01X1545226Y113108D02*
X1542392Y115942D01*
G01X1575663Y113108D02*
X1545226D01*
G01X1577347Y111424D02*
X1575663Y113108D01*
G01X1578653Y111424D02*
X1577347D01*
G01X1583431Y116202D02*
X1578653Y111424D01*
G01X1596315Y116202D02*
X1583431D01*
G01X1543829Y153500D02*
X1549257Y158928D01*
G01X1540700Y153500D02*
X1543829D01*
G01X1535776Y148576D02*
X1540700Y153500D01*
G01X1531332Y148576D02*
X1535776D01*
G01X1527539Y144783D02*
X1531332Y148576D01*
G01X1535695Y139736D02*
X1528236D01*
G01X1537413Y141454D02*
X1535695Y139736D01*
G01X1547989Y141454D02*
X1537413D01*
G01X1553658Y147123D02*
X1547989Y141454D01*
G01X1562841Y147123D02*
X1553658D01*
G01X1563787Y146177D02*
X1562841Y147123D01*
G01X1571340Y146177D02*
X1563787D01*
G01X1572047Y145470D02*
X1571340Y146177D01*
G01X1586994Y145470D02*
X1572047D01*
G01X1596472Y154948D02*
X1586994Y145470D01*
G01X1573933Y127915D02*
X1574197D01*
G01X1573848Y127830D02*
X1573933Y127915D01*
G01X1564704Y127830D02*
X1573848D01*
G01X1561080Y131454D02*
X1564704Y127830D01*
G01X1553861Y131454D02*
X1561080D01*
G01X1551733Y129326D02*
X1553861Y131454D01*
G01X1533709Y129326D02*
X1551733D01*
G01X1533189Y128806D02*
X1533709Y129326D01*
G01X1575850Y155732D02*
X1579065Y158947D01*
G01X1575850Y151350D02*
Y155732D01*
G01X1574000Y149500D02*
X1575850Y151350D01*
G01X1534021Y128574D02*
X1533501Y128054D01*
G01X1552045Y128574D02*
X1534021D01*
G01X1554173Y130702D02*
X1552045Y128574D01*
G01X1558836Y130702D02*
X1554173D01*
G01X1559876Y129662D02*
X1558836Y130702D01*
G01X1559876Y129655D02*
Y129662D01*
G01X1563108Y126423D02*
X1559876Y129655D01*
G01X1583790Y117972D02*
X1595026D01*
G01X1580472Y114654D02*
X1583790Y117972D01*
G01X1553140Y114654D02*
X1580472D01*
G01X1550463Y117331D02*
X1553140Y114654D01*
G01X1545519Y117331D02*
X1550463D01*
G01X1544882Y116694D02*
X1545519Y117331D01*
G01X1536603Y116694D02*
X1544882D01*
G01X1529800Y123497D02*
X1536603Y116694D01*
G01X1529800Y124389D02*
Y123497D01*
G01X1527693Y126496D02*
X1529800Y124389D01*
G01X1579249Y102800D02*
X1596341D01*
G01X1577418Y100969D02*
X1579249Y102800D01*
G01X1566693Y100969D02*
X1577418D01*
G01X1564062Y103600D02*
X1566693Y100969D01*
G01X1554540Y103600D02*
X1564062D01*
G01X1551645Y106495D02*
X1554540Y103600D01*
G01X1546191Y106495D02*
X1551645D01*
G01X1543910Y104214D02*
X1546191Y106495D01*
G01X1533310Y104214D02*
X1543910D01*
G01X1530200Y101104D02*
X1533310Y104214D01*
G01X1565028Y154026D02*
X1576407Y165405D01*
G01X1549868Y154026D02*
X1565028D01*
G01X1544872Y149030D02*
X1549868Y154026D01*
G01X1541831Y149030D02*
X1544872D01*
G01X1588653Y98924D02*
X1591129Y101400D01*
G01X1573012Y98924D02*
X1588653D01*
G01X1572634Y98546D02*
X1573012Y98924D01*
G01X1532915Y105166D02*
X1529849Y102100D01*
G01X1543515Y105166D02*
X1532915D01*
G01X1545796Y107447D02*
X1543515Y105166D01*
G01X1552040Y107447D02*
X1545796D01*
G01X1554887Y104600D02*
X1552040Y107447D01*
G01X1570995Y104600D02*
X1554887D01*
G01X1572115Y105720D02*
X1570995Y104600D01*
G01X1573727Y105720D02*
X1572115D01*
G01X1575271Y107264D02*
X1573727Y105720D01*
G01X1577551Y107264D02*
X1575271D01*
G01X1577552Y107263D02*
X1577551Y107264D01*
G01X1580214Y107263D02*
X1577552D01*
G01X1581057Y106420D02*
X1580214Y107263D01*
G01X1584631Y106420D02*
X1581057D01*
G01X1586575Y108364D02*
X1584631Y106420D01*
G01X1589744Y108364D02*
X1586575D01*
G01X1585229Y110400D02*
X1590995D01*
G01X1583153Y108324D02*
X1585229Y110400D01*
G01X1581847Y108324D02*
X1583153D01*
G01X1581003Y109168D02*
X1581847Y108324D01*
G01X1579589Y109168D02*
X1581003D01*
G01X1579588Y109167D02*
X1579589Y109168D01*
G01X1578342Y109167D02*
X1579588D01*
G01X1578341Y109168D02*
X1578342Y109167D01*
G01X1574143Y109168D02*
X1578341D01*
G01X1572747Y107772D02*
X1574143Y109168D01*
G01X1562804Y107772D02*
X1572747D01*
G01X1561124Y109452D02*
X1562804Y107772D01*
G01X1529400Y109452D02*
X1561124D01*
G01X1528118Y110734D02*
X1529400Y109452D01*
G01X1587829Y140778D02*
X1590081Y143030D01*
G01X1583985Y140778D02*
X1587829D01*
G01X1580085Y136878D02*
X1583985Y140778D01*
G01X1577121Y136878D02*
X1580085D01*
G01X1572735Y141264D02*
X1577121Y136878D01*
G01X1566572Y141264D02*
X1572735D01*
G01X1562321Y145515D02*
X1566572Y141264D01*
G01X1554478Y145515D02*
X1562321D01*
G01X1552242Y143279D02*
X1554478Y145515D01*
G01X1552222Y143279D02*
X1552242D01*
G01X1551122Y142179D02*
X1552222Y143279D01*
G01X1551122Y142159D02*
Y142179D01*
G01X1545461Y136498D02*
X1551122Y142159D01*
G01X1541390Y136498D02*
X1545461D01*
G01X1566052Y153209D02*
X1576545Y163702D01*
G01X1551458Y153209D02*
X1566052D01*
G01X1545648Y147399D02*
X1551458Y153209D01*
G01X1532384Y147399D02*
X1545648D01*
G01X1531985Y147000D02*
X1532384Y147399D01*
G01X1535460Y157131D02*
X1532353Y154024D01*
G01X1537797Y156167D02*
X1537796Y156168D01*
G01X1537797Y155811D02*
Y156167D01*
G01X1533618Y151632D02*
X1537797Y155811D01*
G01X1578362Y132680D02*
X1595472D01*
G01X1575951Y130269D02*
X1578362Y132680D01*
G01X1564951Y130269D02*
X1575951D01*
G01X1562987Y132233D02*
X1564951Y130269D01*
G01X1562987Y135650D02*
Y132233D01*
G01X1561125Y137512D02*
X1562987Y135650D01*
G01X1561125Y141697D02*
Y137512D01*
G01X1559776Y143046D02*
X1561125Y141697D01*
G01X1554380Y143046D02*
X1559776D01*
G01X1552965Y141631D02*
X1554380Y143046D01*
G01X1552965Y137045D02*
Y141631D01*
G01X1546750Y130830D02*
X1552965Y137045D01*
G01X1533085Y130830D02*
X1546750D01*
G01X1532565Y130310D02*
X1533085Y130830D01*
G01X1533963Y142942D02*
X1528158D01*
G01X1535966Y144945D02*
X1533963Y142942D01*
G01X1546665Y144945D02*
X1535966D01*
G01X1552220Y150500D02*
X1546665Y144945D01*
G01X1566814Y150500D02*
X1552220D01*
G01X1577562Y161248D02*
X1566814Y150500D01*
G01X1586016Y143416D02*
X1592900Y150300D01*
G01X1576506Y143416D02*
X1586016D01*
G01X1533397Y130078D02*
X1532877Y129558D01*
G01X1549249Y130078D02*
X1533397D01*
G01X1552171Y133000D02*
X1549249Y130078D01*
G01X1579741Y152600D02*
X1577950D01*
G01X1588391Y161250D02*
X1579741Y152600D01*
G01X1543322Y108643D02*
X1541421Y106742D01*
G01X1560869Y108643D02*
X1543322D01*
G01X1562492Y107020D02*
X1560869Y108643D01*
G01X1573321Y107020D02*
X1562492D01*
G01X1574717Y108416D02*
X1573321Y107020D01*
G01X1578029Y108416D02*
X1574717D01*
G01X1578030Y108415D02*
X1578029Y108416D01*
G01X1579900Y108415D02*
X1578030D01*
G01X1579901Y108416D02*
X1579900Y108415D01*
G01X1580691Y108416D02*
X1579901D01*
G01X1581535Y107572D02*
X1580691Y108416D01*
G01X1583529Y107572D02*
X1581535D01*
G01X1585473Y109516D02*
X1583529Y107572D01*
G01X1590489Y109516D02*
X1585473D01*
G01X1553353Y123377D02*
Y124209D01*
G01X1556806Y119924D02*
X1553353Y123377D01*
G01X1560046Y119924D02*
X1556806D01*
G01X1563758Y123636D02*
X1560046Y119924D01*
G01X1570632Y123636D02*
X1563758D01*
G01X1573211Y126215D02*
X1570632Y123636D01*
G01X1581144Y126215D02*
X1573211D01*
G01X1585552Y130623D02*
X1581144Y126215D01*
G01X1595697Y130623D02*
X1585552D01*
G01X1583431Y118723D02*
X1594714D01*
G01X1580514Y115806D02*
X1583431Y118723D01*
G01X1553816Y115806D02*
X1580514D01*
G01X1546334Y123288D02*
X1553816Y115806D01*
G01X1532238Y123288D02*
X1546334D01*
G01X1531726Y123800D02*
X1532238Y123288D01*
G01X1545084Y151900D02*
X1541351D01*
G01X1548608Y155424D02*
X1545084Y151900D01*
G01X1564763Y155424D02*
X1548608D01*
G01X1575897Y166558D02*
X1564763Y155424D01*
G01X1577573Y105359D02*
X1576606Y104392D01*
G01X1579424Y105359D02*
X1577573D01*
G01X1580635Y104148D02*
X1579424Y105359D01*
G01X1590224Y104148D02*
X1580635D01*
G01X1553680Y94550D02*
X1534897D01*
G01X1595164Y95864D02*
X1581725D01*
G01X1534333Y127822D02*
X1533769Y127258D01*
G01X1543578Y127822D02*
X1534333D01*
G01X1554441Y116959D02*
X1543578Y127822D01*
G01X1580604Y116959D02*
X1554441D01*
G01X1583119Y119474D02*
X1580604Y116959D01*
G01X1594402Y119474D02*
X1583119D01*
G01X1537044Y156122D02*
Y156983D01*
G01X1533306Y152384D02*
X1537044Y156122D01*
G01X1578007Y149519D02*
X1577770D01*
G01X1588786Y160298D02*
X1578007Y149519D01*
G01X1536292Y156500D02*
X1532928Y153136D01*
G01X1530376Y150880D02*
X1527183Y147687D01*
G01X1533930Y150880D02*
X1530376D01*
G01X1538550Y155500D02*
X1533930Y150880D01*
G01X1538550Y155856D02*
Y155500D01*
G01X1538549Y155857D02*
X1538550Y155856D01*
G01X1538549Y156360D02*
Y155857D01*
G01X1530854Y149728D02*
X1527461Y146335D01*
G01X1534430Y149728D02*
X1530854D01*
G01X1539702Y155000D02*
X1534430Y149728D01*
G01X1539702Y155883D02*
Y155000D01*
G01X1541785Y157966D02*
X1539702Y155883D01*
G01X1585888Y166476D02*
X1592453D01*
G01X1581412Y162000D02*
X1585888Y166476D01*
G01X1577250Y162000D02*
X1581412D01*
G01X1582285Y159897D02*
X1578951D01*
G01X1585572Y163184D02*
X1582285Y159897D01*
G01X1599874Y163184D02*
X1585572D01*
G01X1585054Y173659D02*
X1594429D01*
G01X1579700Y168305D02*
X1585054Y173659D01*
G01X1576014Y168305D02*
X1579700D01*
G01X1565209Y157500D02*
X1576014Y168305D01*
G01X1560330Y157500D02*
X1565209D01*
G01X1558902Y158928D02*
X1560330Y157500D01*
G01X1549257Y158928D02*
X1558902D01*
G01X1586164Y162432D02*
X1600462D01*
G01X1582679Y158947D02*
X1586164Y162432D01*
G01X1579065Y158947D02*
X1582679D01*
G01X1551298Y171300D02*
X1528753D01*
G01X1552051Y172053D02*
X1551298Y171300D01*
G01X1584180Y168980D02*
X1598860D01*
G01X1580605Y165405D02*
X1584180Y168980D01*
G01X1576407Y165405D02*
X1580605D01*
G01X1585204Y168199D02*
X1599142D01*
G01X1580707Y163702D02*
X1585204Y168199D01*
G01X1576545Y163702D02*
X1580707D01*
G01X1583586Y182133D02*
X1592710D01*
G01X1575653Y174200D02*
X1583586Y182133D01*
G01X1569364Y174200D02*
X1575653D01*
G01X1567485Y172321D02*
X1569364Y174200D01*
G01X1561885Y172321D02*
X1567485D01*
G01X1559112Y169548D02*
X1561885Y172321D01*
G01X1541847Y169548D02*
X1559112D01*
G01X1541102Y168803D02*
X1541847Y169548D01*
G01X1533624Y168803D02*
X1541102D01*
G01X1531080Y166259D02*
X1533624Y168803D01*
G01X1531080Y166223D02*
Y166259D01*
G01X1529666Y164809D02*
X1531080Y166223D01*
G01X1535460Y158021D02*
Y157131D01*
G01X1544452Y167013D02*
X1535460Y158021D01*
G01X1559921Y167013D02*
X1544452D01*
G01X1562644Y169736D02*
X1559921Y167013D01*
G01X1567736Y169736D02*
X1562644D01*
G01X1569043Y171043D02*
X1567736Y169736D01*
G01X1569835Y171043D02*
X1569043D01*
G01X1571036Y172244D02*
X1569835Y171043D01*
G01X1578279Y172244D02*
X1571036D01*
G01X1584538Y178503D02*
X1578279Y172244D01*
G01X1597153Y178503D02*
X1584538D01*
G01X1570292Y167386D02*
X1570294Y167384D01*
G01X1563486Y167386D02*
X1570292D01*
G01X1558096Y161996D02*
X1563486Y167386D01*
G01X1551441Y161996D02*
X1558096D01*
G01X1551437Y162000D02*
X1551441Y161996D01*
G01X1548005Y162000D02*
X1551437D01*
G01X1545899Y159894D02*
X1548005Y162000D01*
G01X1542795Y159894D02*
X1545899D01*
G01X1542771Y159870D02*
X1542795Y159894D01*
G01X1542575Y159870D02*
X1542771D01*
G01X1542574Y159871D02*
X1542575Y159870D01*
G01X1540996Y159871D02*
X1542574D01*
G01X1537796Y156671D02*
X1540996Y159871D01*
G01X1537796Y156168D02*
Y156671D01*
G01X1581724Y161248D02*
X1577562D01*
G01X1585326Y164850D02*
X1581724Y161248D01*
G01X1591750Y164850D02*
X1585326D01*
G01X1533177Y170300D02*
X1528688Y165811D01*
G01X1558800Y170300D02*
X1533177D01*
G01X1561573Y173073D02*
X1558800Y170300D01*
G01X1562191Y173073D02*
X1561573D01*
G01X1562618Y173500D02*
X1562191Y173073D01*
G01X1567600Y173500D02*
X1562618D01*
G01X1569069Y174969D02*
X1567600Y173500D01*
G01X1575358Y174969D02*
X1569069D01*
G01X1583489Y183100D02*
X1575358Y174969D01*
G01X1592421Y183100D02*
X1583489D01*
G01X1600344Y161250D02*
X1588391D01*
G01X1580128Y166558D02*
X1575897D01*
G01X1583908Y170338D02*
X1580128Y166558D01*
G01X1593225Y170338D02*
X1583908D01*
G01X1572409Y169502D02*
X1572817Y169910D01*
G01X1569700Y169502D02*
X1572409D01*
G01X1568430Y168232D02*
X1569700Y169502D01*
G01X1563268Y168232D02*
X1568430D01*
G01X1557784Y162748D02*
X1563268Y168232D01*
G01X1551753Y162748D02*
X1557784D01*
G01X1550435Y164066D02*
X1551753Y162748D01*
G01X1544127Y164066D02*
X1550435D01*
G01X1537044Y156983D02*
X1544127Y164066D01*
G01X1536000Y168051D02*
X1532006Y164057D01*
G01X1541414Y168051D02*
X1536000D01*
G01X1541759Y168396D02*
X1541414Y168051D01*
G01X1559590Y168396D02*
X1541759D01*
G01X1561894Y170700D02*
X1559590Y168396D01*
G01X1567494Y170700D02*
X1561894D01*
G01X1569842Y173048D02*
X1567494Y170700D01*
G01X1576131Y173048D02*
X1569842D01*
G01X1583726Y180643D02*
X1576131Y173048D01*
G01X1592896Y180643D02*
X1583726D01*
G01X1536292Y157295D02*
Y156500D01*
G01X1544308Y165311D02*
X1536292Y157295D01*
G01X1550689Y165311D02*
X1544308D01*
G01X1552500Y163500D02*
X1550689Y165311D01*
G01X1557472Y163500D02*
X1552500D01*
G01X1562956Y168984D02*
X1557472Y163500D01*
G01X1568118Y168984D02*
X1562956D01*
G01X1569425Y170291D02*
X1568118Y168984D01*
G01X1570147Y170291D02*
X1569425D01*
G01X1571348Y171492D02*
X1570147Y170291D01*
G01X1578591Y171492D02*
X1571348D01*
G01X1584826Y177727D02*
X1578591Y171492D01*
G01X1602649Y177727D02*
X1584826D01*
G01X1541308Y159119D02*
X1538549Y156360D01*
G01X1542262Y159119D02*
X1541308D01*
G01X1542263Y159118D02*
X1542262Y159119D01*
G01X1546187Y159118D02*
X1542263D01*
G01X1548301Y161232D02*
X1546187Y159118D01*
G01X1561618Y161232D02*
X1548301D01*
G01X1562150Y160700D02*
X1561618Y161232D01*
G01X1546665Y157966D02*
X1541785D01*
G01X1548779Y160080D02*
X1546665Y157966D01*
G01X1559919Y160080D02*
X1548779D01*
G01X1560999Y159000D02*
X1559919Y160080D01*
G01X1564874Y159000D02*
X1560999D01*
G01X1565278Y159404D02*
X1564874Y159000D01*
G01X1565278Y163360D02*
Y159404D01*
G01X1567726Y165808D02*
X1565278Y163360D01*
G01X1571230Y165808D02*
X1567726D01*
G01X1572654Y167232D02*
X1571230Y165808D01*
G01X1572654Y167235D02*
Y167232D01*
G01X1575276Y169857D02*
X1572654Y167235D01*
G01X1579057Y169857D02*
X1575276D01*
G01X1585348Y176148D02*
X1579057Y169857D01*
G01X1602283Y176148D02*
X1585348D01*
G01X1539724Y260419D02*
X1531008Y269135D01*
G01X1540346Y260419D02*
X1539724D01*
G01X1540347Y260420D02*
X1540346Y260419D01*
G01X1554000Y260420D02*
X1540347D01*
G01X1564254Y270674D02*
X1554000Y260420D01*
G01X1599538Y270674D02*
X1564254D01*
G01X1539100Y258915D02*
X1530502Y267513D01*
G01X1540970Y258915D02*
X1539100D01*
G01X1540971Y258916D02*
X1540970Y258915D01*
G01X1555540Y258916D02*
X1540971D01*
G01X1557454Y260830D02*
X1555540Y258916D01*
G01X1565730Y260830D02*
X1557454D01*
G01X1567000Y259560D02*
X1565730Y260830D01*
G01X1538788Y258163D02*
X1530190Y266761D01*
G01X1541282Y258163D02*
X1538788D01*
G01X1541283Y258164D02*
X1541282Y258163D01*
G01X1563157Y258164D02*
X1541283D01*
G01X1563394Y272318D02*
X1598629D01*
G01X1553000Y261924D02*
X1563394Y272318D01*
G01X1540347Y261924D02*
X1553000D01*
G01X1531632Y270639D02*
X1540347Y261924D01*
G01X1579888Y267954D02*
X1601554D01*
G01X1578131Y266197D02*
X1579888Y267954D01*
G01X1577644Y266197D02*
X1578131D01*
G01X1568627Y257180D02*
X1577644Y266197D01*
G01X1566971Y257180D02*
X1568627D01*
G01X1566963Y257172D02*
X1566971Y257180D01*
G01X1565767Y257172D02*
X1566963D01*
G01X1564303Y255708D02*
X1565767Y257172D01*
G01X1561548Y255708D02*
X1564303D01*
G01X1560620Y256636D02*
X1561548Y255708D01*
G01X1553265Y256636D02*
X1560620D01*
G01X1553263Y256638D02*
X1553265Y256636D01*
G01X1548273Y256638D02*
X1553263D01*
G01X1548272Y256637D02*
X1548273Y256638D01*
G01X1547650Y256637D02*
X1548272D01*
G01X1547649Y256636D02*
X1547650Y256637D01*
G01X1538100Y256636D02*
X1547649D01*
G01X1529588Y265148D02*
X1538100Y256636D01*
G01X1537160Y254380D02*
X1535916Y255624D01*
G01X1548585Y254380D02*
X1537160D01*
G01X1548586Y254381D02*
X1548585Y254380D01*
G01X1549208Y254381D02*
X1548586D01*
G01X1549209Y254382D02*
X1549208Y254381D01*
G01X1552327Y254382D02*
X1549209D01*
G01X1552329Y254380D02*
X1552327Y254382D01*
G01X1559684Y254380D02*
X1552329D01*
G01X1560694Y253370D02*
X1559684Y254380D01*
G01X1565313Y253370D02*
X1560694D01*
G01X1566801Y254858D02*
X1565313Y253370D01*
G01X1568703Y254858D02*
X1566801D01*
G01X1568704Y254859D02*
X1568703Y254858D01*
G01X1570498Y254859D02*
X1568704D01*
G01X1571153Y254204D02*
X1570498Y254859D01*
G01X1572972Y254204D02*
X1571153D01*
G01X1576492Y257724D02*
X1572972Y254204D01*
G01X1576492Y258416D02*
Y257724D01*
G01X1581581Y263505D02*
X1576492Y258416D01*
G01X1582827Y263505D02*
X1581581D01*
G01X1582828Y263504D02*
X1582827Y263505D01*
G01X1594496Y263504D02*
X1582828D01*
G01X1568365Y247396D02*
Y247761D01*
G01X1566725Y245756D02*
X1568365Y247396D01*
G01X1556697Y245756D02*
X1566725D01*
G01X1551079Y251374D02*
X1556697Y245756D01*
G01X1550457Y251374D02*
X1551079D01*
G01X1550456Y251373D02*
X1550457Y251374D01*
G01X1549834Y251373D02*
X1550456D01*
G01X1549833Y251372D02*
X1549834Y251373D01*
G01X1533722Y251372D02*
X1549833D01*
G01X1532890Y252204D02*
X1533722Y251372D01*
G01X1532147Y277890D02*
X1607898D01*
G01X1531337Y278700D02*
X1532147Y277890D01*
G01X1527657Y278700D02*
X1531337D01*
G01X1582204Y262000D02*
X1593872D01*
G01X1577997Y257793D02*
X1582204Y262000D01*
G01X1577997Y257101D02*
Y257793D01*
G01X1573596Y252700D02*
X1577997Y257101D01*
G01X1570529Y252700D02*
X1573596D01*
G01X1569909Y253320D02*
X1570529Y252700D01*
G01X1567400Y253320D02*
X1569909D01*
G01X1565740Y251660D02*
X1567400Y253320D01*
G01X1565740Y250849D02*
Y251660D01*
G01X1564151Y249260D02*
X1565740Y250849D01*
G01X1561320Y249260D02*
X1564151D01*
G01X1558700Y251880D02*
X1561320Y249260D01*
G01X1558700Y252000D02*
Y251880D01*
G01X1574374Y244734D02*
X1599954D01*
G01X1570084Y240444D02*
X1574374Y244734D01*
G01X1553374Y240444D02*
X1570084D01*
G01X1550910Y237980D02*
X1553374Y240444D01*
G01X1545930Y237980D02*
X1550910D01*
G01X1545120Y238790D02*
X1545930Y237980D01*
G01X1540390Y238790D02*
X1545120D01*
G01X1539190Y239990D02*
X1540390Y238790D01*
G01X1586708Y248796D02*
X1589592Y251680D01*
G01X1572721Y248796D02*
X1586708D01*
G01X1568177Y244252D02*
X1572721Y248796D01*
G01X1556073Y244252D02*
X1568177D01*
G01X1550457Y249868D02*
X1556073Y244252D01*
G01X1532414Y249868D02*
X1550457D01*
G01X1531856Y250426D02*
X1532414Y249868D01*
G01X1565231Y269899D02*
X1600200D01*
G01X1555000Y259668D02*
X1565231Y269899D01*
G01X1540659Y259668D02*
X1555000D01*
G01X1540658Y259667D02*
X1540659Y259668D01*
G01X1539412Y259667D02*
X1540658D01*
G01X1530814Y268265D02*
X1539412Y259667D01*
G01X1530171Y244910D02*
X1529121Y245960D01*
G01X1535565Y244910D02*
X1530171D01*
G01X1538265Y247610D02*
X1535565Y244910D01*
G01X1542810Y247610D02*
X1538265D01*
G01X1544053Y246367D02*
X1542810Y247610D01*
G01X1544053Y246366D02*
Y246367D01*
G01X1546224Y244195D02*
X1544053Y246366D01*
G01X1546224Y242763D02*
Y244195D01*
G01X1547207Y241780D02*
X1546224Y242763D01*
G01X1549820Y241780D02*
X1547207D01*
G01X1551540Y243500D02*
X1549820Y241780D01*
G01X1568489Y243500D02*
X1551540D01*
G01X1573033Y248044D02*
X1568489Y243500D01*
G01X1588052Y248044D02*
X1573033D01*
G01X1592668Y252660D02*
X1588052Y248044D01*
G01X1539710Y236560D02*
X1538652Y237618D01*
G01X1539710Y236089D02*
Y236560D01*
G01X1541325Y234474D02*
X1539710Y236089D01*
G01X1543343Y234474D02*
X1541325D01*
G01X1544791Y235922D02*
X1543343Y234474D01*
G01X1551545Y235922D02*
X1544791D01*
G01X1554274Y238651D02*
X1551545Y235922D01*
G01X1569783Y238651D02*
X1554274D01*
G01X1570318Y238116D02*
X1569783Y238651D01*
G01X1539145Y241992D02*
X1527218D01*
G01X1539180Y242027D02*
X1539145Y241992D01*
G01X1539202Y242027D02*
X1539180D01*
G01X1540457Y243282D02*
X1539202Y242027D01*
G01X1543948Y243282D02*
X1540457D01*
G01X1546640Y240590D02*
X1543948Y243282D01*
G01X1550144Y240590D02*
X1546640D01*
G01X1550182Y240628D02*
X1550144Y240590D01*
G01X1550298Y240628D02*
X1550182D01*
G01X1552018Y242348D02*
X1550298Y240628D01*
G01X1568967Y242348D02*
X1552018D01*
G01X1573511Y246892D02*
X1568967Y242348D01*
G01X1592872Y246892D02*
X1573511D01*
G01X1530640Y246150D02*
X1529666Y247124D01*
G01X1533545Y246150D02*
X1530640D01*
G01X1536295Y248900D02*
X1533545Y246150D01*
G01X1546800Y248900D02*
X1536295D01*
G01X1549124Y246576D02*
X1546800Y248900D01*
G01X1549124Y244611D02*
Y246576D01*
G01X1547869Y243356D02*
X1549124Y244611D01*
G01X1580200Y268706D02*
X1602406D01*
G01X1580199Y268707D02*
X1580200Y268706D01*
G01X1579577Y268707D02*
X1580199D01*
G01X1579576Y268706D02*
X1579577Y268707D01*
G01X1579235Y268706D02*
X1579576D01*
G01X1577478Y266949D02*
X1579235Y268706D01*
G01X1577332Y266949D02*
X1577478D01*
G01X1568315Y257932D02*
X1577332Y266949D01*
G01X1567283Y257932D02*
X1568315D01*
G01X1567282Y257933D02*
X1567283Y257932D01*
G01X1566660Y257933D02*
X1567282D01*
G01X1566651Y257924D02*
X1566660Y257933D01*
G01X1565455Y257924D02*
X1566651D01*
G01X1563991Y256460D02*
X1565455Y257924D01*
G01X1562040Y256460D02*
X1563991D01*
G01X1561112Y257388D02*
X1562040Y256460D01*
G01X1553577Y257388D02*
X1561112D01*
G01X1553575Y257390D02*
X1553577Y257388D01*
G01X1547961Y257390D02*
X1553575D01*
G01X1547960Y257389D02*
X1547961Y257390D01*
G01X1547338Y257389D02*
X1547960D01*
G01X1547337Y257388D02*
X1547338Y257389D01*
G01X1538412Y257388D02*
X1547337D01*
G01X1529900Y265900D02*
X1538412Y257388D01*
G01X1563308Y278869D02*
X1559205Y282972D01*
G01X1563930Y278869D02*
X1563308D01*
G01X1563931Y278870D02*
X1563930Y278869D01*
G01X1609179Y278870D02*
X1563931D01*
G01X1572700Y238200D02*
Y239400D01*
G01X1570968Y236468D02*
X1572700Y238200D01*
G01X1568223Y236468D02*
X1570968D01*
G01X1566792Y237899D02*
X1568223Y236468D01*
G01X1554586Y237899D02*
X1566792D01*
G01X1551857Y235170D02*
X1554586Y237899D01*
G01X1545103Y235170D02*
X1551857D01*
G01X1543655Y233722D02*
X1545103Y235170D01*
G01X1541013Y233722D02*
X1543655D01*
G01X1540405Y234330D02*
X1541013Y233722D01*
G01X1532680Y234330D02*
X1540405D01*
G01X1530953Y236057D02*
X1532680Y234330D01*
G01X1577956Y265445D02*
X1579867D01*
G01X1568931Y256420D02*
X1577956Y265445D01*
G01X1566079Y256420D02*
X1568931D01*
G01X1564615Y254956D02*
X1566079Y256420D01*
G01X1561236Y254956D02*
X1564615D01*
G01X1560308Y255884D02*
X1561236Y254956D01*
G01X1552953Y255884D02*
X1560308D01*
G01X1552951Y255886D02*
X1552953Y255884D01*
G01X1548585Y255886D02*
X1552951D01*
G01X1548584Y255885D02*
X1548585Y255886D01*
G01X1547962Y255885D02*
X1548584D01*
G01X1547961Y255884D02*
X1547962Y255885D01*
G01X1537788Y255884D02*
X1547961D01*
G01X1529276Y264396D02*
X1537788Y255884D01*
G01X1539398Y245090D02*
X1541325D01*
G01X1537060Y242752D02*
X1539398Y245090D01*
G01X1528756Y242752D02*
X1537060D01*
G01X1528748Y242744D02*
X1528756Y242752D01*
G01X1527585Y242744D02*
X1528748D01*
G01X1540935Y242130D02*
X1539645Y240840D01*
G01X1543470Y242130D02*
X1540935D01*
G01X1546210Y239390D02*
X1543470Y242130D01*
G01X1550574Y239390D02*
X1546210D01*
G01X1550660Y239476D02*
X1550574Y239390D01*
G01X1550776Y239476D02*
X1550660D01*
G01X1552496Y241196D02*
X1550776Y239476D01*
G01X1569445Y241196D02*
X1552496D01*
G01X1573989Y245740D02*
X1569445Y241196D01*
G01X1595990Y245740D02*
X1573989D01*
G01X1534492Y252876D02*
X1533500Y253868D01*
G01X1549209Y252876D02*
X1534492D01*
G01X1549210Y252877D02*
X1549209Y252876D01*
G01X1549832Y252877D02*
X1549210D01*
G01X1549833Y252878D02*
X1549832Y252877D01*
G01X1551703Y252878D02*
X1549833D01*
G01X1551705Y252876D02*
X1551703Y252878D01*
G01X1552596Y252876D02*
X1551705D01*
G01X1558212Y247260D02*
X1552596Y252876D01*
G01X1563270Y247260D02*
X1558212D01*
G01X1566130Y250120D02*
X1563270Y247260D01*
G01X1569530Y250120D02*
X1566130D01*
G01X1571052Y251642D02*
X1569530Y250120D01*
G01X1576307Y251642D02*
X1571052D01*
G01X1579565Y254900D02*
X1576307Y251642D01*
G01X1579694Y254900D02*
X1579565D01*
G01X1579991Y255197D02*
X1579694Y254900D01*
G01X1596585Y255197D02*
X1579991D01*
G01X1574823Y243824D02*
X1600573D01*
G01X1570691Y239692D02*
X1574823Y243824D01*
G01X1554251Y239692D02*
X1570691D01*
G01X1551233Y236674D02*
X1554251Y239692D01*
G01X1545683Y236674D02*
X1551233D01*
G01X1544687Y237670D02*
X1545683Y236674D01*
G01X1540050Y237670D02*
X1544687D01*
G01X1539350Y238370D02*
X1540050Y237670D01*
G01X1582516Y262752D02*
X1594184D01*
G01X1582515Y262753D02*
X1582516Y262752D01*
G01X1581893Y262753D02*
X1582515D01*
G01X1577244Y258104D02*
X1581893Y262753D01*
G01X1577244Y257412D02*
Y258104D01*
G01X1573284Y253452D02*
X1577244Y257412D01*
G01X1570841Y253452D02*
X1573284D01*
G01X1570187Y254106D02*
X1570841Y253452D01*
G01X1567113Y254106D02*
X1570187D01*
G01X1565577Y252570D02*
X1567113Y254106D01*
G01X1560430Y252570D02*
X1565577D01*
G01X1559372Y253628D02*
X1560430Y252570D01*
G01X1552017Y253628D02*
X1559372D01*
G01X1552015Y253630D02*
X1552017Y253628D01*
G01X1549521Y253630D02*
X1552015D01*
G01X1549520Y253629D02*
X1549521Y253630D01*
G01X1548898Y253629D02*
X1549520D01*
G01X1548897Y253628D02*
X1548898Y253629D01*
G01X1534974Y253628D02*
X1548897D01*
G01X1533948Y254654D02*
X1534974Y253628D01*
G01X1537476Y255132D02*
X1528964Y263644D01*
G01X1548273Y255132D02*
X1537476D01*
G01X1548274Y255133D02*
X1548273Y255132D01*
G01X1548896Y255133D02*
X1548274D01*
G01X1548897Y255134D02*
X1548896Y255133D01*
G01X1552639Y255134D02*
X1548897D01*
G01X1552641Y255132D02*
X1552639Y255134D01*
G01X1559996Y255132D02*
X1552641D01*
G01X1560924Y254204D02*
X1559996Y255132D01*
G01X1565055Y254204D02*
X1560924D01*
G01X1566481Y255630D02*
X1565055Y254204D01*
G01X1569300Y255630D02*
X1566481D01*
G01X1572398Y258728D02*
X1569300Y255630D01*
G01X1575740Y258728D02*
X1572398D01*
G01X1581312Y264300D02*
X1575740Y258728D01*
G01X1594888Y264300D02*
X1581312D01*
G01X1534180Y252124D02*
X1533223Y253081D01*
G01X1549521Y252124D02*
X1534180D01*
G01X1549522Y252125D02*
X1549521Y252124D01*
G01X1550144Y252125D02*
X1549522D01*
G01X1550145Y252126D02*
X1550144Y252125D01*
G01X1551391Y252126D02*
X1550145D01*
G01X1551393Y252124D02*
X1551391Y252126D01*
G01X1552284Y252124D02*
X1551393D01*
G01X1557900Y246508D02*
X1552284Y252124D01*
G01X1563588Y246508D02*
X1557900D01*
G01X1566430Y249350D02*
X1563588Y246508D01*
G01X1569840Y249350D02*
X1566430D01*
G01X1571380Y250890D02*
X1569840Y249350D01*
G01X1576748Y250890D02*
X1571380D01*
G01X1580303Y254445D02*
X1576748Y250890D01*
G01X1596273Y254445D02*
X1580303D01*
G01X1532962Y250620D02*
X1532285Y251297D01*
G01X1550769Y250620D02*
X1532962D01*
G01X1556385Y245004D02*
X1550769Y250620D01*
G01X1567865Y245004D02*
X1556385D01*
G01X1572409Y249548D02*
X1567865Y245004D01*
G01X1585231Y249548D02*
X1572409D01*
G01X1586950Y251267D02*
X1585231Y249548D01*
G01X1563894Y271566D02*
X1598941D01*
G01X1553500Y261172D02*
X1563894Y271566D01*
G01X1540035Y261172D02*
X1553500D01*
G01X1531320Y269887D02*
X1540035Y261172D01*
G01X1530796Y308128D02*
X1529683Y307015D01*
G01X1538301Y308128D02*
X1530796D01*
G01X1542008Y304421D02*
X1538301Y308128D01*
G01X1544143Y304421D02*
X1542008D01*
G01X1545477Y303087D02*
X1544143Y304421D01*
G01X1550619Y303087D02*
X1545477D01*
G01X1585570Y338226D02*
X1593096D01*
G01X1583881Y336537D02*
X1585570Y338226D01*
G01X1576736Y336537D02*
X1583881D01*
G01X1576615Y336416D02*
X1576736Y336537D01*
G01X1572895Y336416D02*
X1576615D01*
G01X1571131Y338180D02*
X1572895Y336416D01*
G01X1566119Y338180D02*
X1571131D01*
G01X1564976Y339323D02*
X1566119Y338180D01*
G01X1564976Y339976D02*
Y339323D01*
G01X1566000Y341000D02*
X1564976Y339976D01*
G01X1544934Y298808D02*
X1542729Y301013D01*
G01X1557522Y298808D02*
X1544934D01*
G01X1559769Y296561D02*
X1557522Y298808D01*
G01X1566399Y296561D02*
X1559769D01*
G01X1569296Y293664D02*
X1566399Y296561D01*
G01X1573646Y293664D02*
X1569296D01*
G01X1578029Y289281D02*
X1573646Y293664D01*
G01X1583659Y289281D02*
X1578029D01*
G01X1585477Y287463D02*
X1583659Y289281D01*
G01X1598043Y287463D02*
X1585477D01*
G01X1546864Y293120D02*
X1541627Y298357D01*
G01X1552077Y293120D02*
X1546864D01*
G01X1552637Y293680D02*
X1552077Y293120D01*
G01X1556077Y293680D02*
X1552637D01*
G01X1556377Y293380D02*
X1556077Y293680D01*
G01X1565770Y293380D02*
X1556377D01*
G01X1568369Y290781D02*
X1565770Y293380D01*
G01X1572153Y290781D02*
X1568369D01*
G01X1576398Y286536D02*
X1572153Y290781D01*
G01X1582314Y286536D02*
X1576398D01*
G01X1584043Y284807D02*
X1582314Y286536D01*
G01X1599145Y284807D02*
X1584043D01*
G01X1529734Y319714D02*
Y319692D01*
G01X1559809Y310505D02*
X1559997Y310317D01*
G01X1559809Y310648D02*
Y310505D01*
G01X1558609Y311848D02*
X1559809Y310648D01*
G01X1550583Y311848D02*
X1558609D01*
G01X1549433Y310698D02*
X1550583Y311848D01*
G01X1547107Y310698D02*
X1549433D01*
G01X1545744Y312061D02*
X1547107Y310698D01*
G01X1545744Y312892D02*
Y312061D01*
G01X1540036Y318600D02*
X1545744Y312892D01*
G01X1535736Y318600D02*
X1540036D01*
G01X1534644Y319692D02*
X1535736Y318600D01*
G01X1529734Y319692D02*
X1534644D01*
G01X1531461Y294453D02*
X1527546Y290538D01*
G01X1532154Y294453D02*
X1531461D01*
G01X1532155Y294454D02*
X1532154Y294453D01*
G01X1532777Y294454D02*
X1532155D01*
G01X1532778Y294453D02*
X1532777Y294454D01*
G01X1535653Y294453D02*
X1532778D01*
G01X1537000Y295800D02*
X1535653Y294453D01*
G01X1542056Y295800D02*
X1537000D01*
G01X1546240Y291616D02*
X1542056Y295800D01*
G01X1552717Y291616D02*
X1546240D01*
G01X1553277Y292176D02*
X1552717Y291616D01*
G01X1555453Y292176D02*
X1553277D01*
G01X1555753Y291876D02*
X1555453Y292176D01*
G01X1563884Y291876D02*
X1555753D01*
G01X1565000Y290760D02*
X1563884Y291876D01*
G01X1565000Y290500D02*
Y290760D01*
G01X1587085Y339634D02*
X1592512D01*
G01X1583650Y343069D02*
X1587085Y339634D01*
G01X1578589Y340557D02*
Y342029D01*
G01X1580351Y338795D02*
X1578589Y340557D01*
G01X1581090Y338795D02*
X1580351D01*
G01X1587330Y317054D02*
X1598024D01*
G01X1585860Y318524D02*
X1587330Y317054D01*
G01X1584995Y318524D02*
X1585860D01*
G01X1582786Y316315D02*
X1584995Y318524D01*
G01X1575212Y316315D02*
X1582786D01*
G01X1570853Y320674D02*
X1575212Y316315D01*
G01X1553108Y320674D02*
X1570853D01*
G01X1551903Y321879D02*
X1553108Y320674D01*
G01X1550597Y321879D02*
X1551903D01*
G01X1549287Y320569D02*
X1550597Y321879D01*
G01X1547149Y320569D02*
X1549287D01*
G01X1545720Y321998D02*
X1547149Y320569D01*
G01X1545720Y323492D02*
Y321998D01*
G01X1542897Y326315D02*
X1545720Y323492D01*
G01X1536953Y326315D02*
X1542897D01*
G01X1533932Y329336D02*
X1536953Y326315D01*
G01X1530482Y329336D02*
X1533932D01*
G01X1528007Y331811D02*
X1530482Y329336D01*
G01X1583675Y297918D02*
X1591544D01*
G01X1579325Y302268D02*
X1583675Y297918D01*
G01X1570431Y302268D02*
X1579325D01*
G01X1566050Y306649D02*
X1570431Y302268D01*
G01X1564787Y306649D02*
X1566050D01*
G01X1561989Y303851D02*
X1564787Y306649D01*
G01X1556798Y303851D02*
X1561989D01*
G01X1555226Y305423D02*
X1556798Y303851D01*
G01X1545269Y305423D02*
X1555226D01*
G01X1544767Y305925D02*
X1545269Y305423D01*
G01X1542632Y305925D02*
X1544767D01*
G01X1538925Y309632D02*
X1542632Y305925D01*
G01X1538307Y309632D02*
X1538925D01*
G01X1535125Y312814D02*
X1538307Y309632D01*
G01X1532193Y312814D02*
X1535125D01*
G01X1529550Y310171D02*
X1532193Y312814D01*
G01X1577204Y307621D02*
X1577486D01*
G01X1574530Y310295D02*
X1577204Y307621D01*
G01X1568119Y310295D02*
X1574530D01*
G01X1566891Y311523D02*
X1568119Y310295D01*
G01X1566891Y312657D02*
Y311523D01*
G01X1566097Y313451D02*
X1566891Y312657D01*
G01X1562975Y313451D02*
X1566097D01*
G01X1561976Y312452D02*
X1562975Y313451D01*
G01X1561976Y307030D02*
Y312452D01*
G01X1561053Y306107D02*
X1561976Y307030D01*
G01X1557734Y306107D02*
X1561053D01*
G01X1556162Y307679D02*
X1557734Y306107D01*
G01X1549821Y307679D02*
X1556162D01*
G01X1549319Y308181D02*
X1549821Y307679D01*
G01X1543680Y308181D02*
X1549319D01*
G01X1541500Y310361D02*
X1543680Y308181D01*
G01X1541500Y315008D02*
Y310361D01*
G01X1539608Y316900D02*
X1541500Y315008D01*
G01X1528400Y316900D02*
X1539608D01*
G01X1586428Y289372D02*
X1601598D01*
G01X1581556Y294244D02*
X1586428Y289372D01*
G01X1581287Y294244D02*
X1581556D01*
G01X1580364Y295167D02*
X1581287Y294244D01*
G01X1580364Y295436D02*
Y295167D01*
G01X1577335Y298465D02*
X1580364Y295436D01*
G01X1560559Y298465D02*
X1577335D01*
G01X1558312Y300712D02*
X1560559Y298465D01*
G01X1545724Y300712D02*
X1558312D01*
G01X1543519Y302917D02*
X1545724Y300712D01*
G01X1541384Y302917D02*
X1543519D01*
G01X1537677Y306624D02*
X1541384Y302917D01*
G01X1531591Y306624D02*
X1537677D01*
G01X1529613Y304646D02*
X1531591Y306624D01*
G01X1547488Y294624D02*
X1542251Y299861D01*
G01X1551453Y294624D02*
X1547488D01*
G01X1552400Y295571D02*
X1551453Y294624D01*
G01X1552400Y296246D02*
Y295571D01*
G01X1553810Y297656D02*
X1552400Y296246D01*
G01X1557044Y297656D02*
X1553810D01*
G01X1559291Y295409D02*
X1557044Y297656D01*
G01X1565921Y295409D02*
X1559291D01*
G01X1568870Y292460D02*
X1565921Y295409D01*
G01X1572691Y292460D02*
X1568870D01*
G01X1577111Y288040D02*
X1572691Y292460D01*
G01X1583270Y288040D02*
X1577111D01*
G01X1584999Y286311D02*
X1583270Y288040D01*
G01X1598521Y286311D02*
X1584999D01*
G01X1554764Y316600D02*
X1549000D01*
G01X1557209Y319045D02*
X1554764Y316600D01*
G01X1570354Y319045D02*
X1557209D01*
G01X1574710Y314689D02*
X1570354Y319045D01*
G01X1583911Y314689D02*
X1574710D01*
G01X1585299Y313301D02*
X1583911Y314689D01*
G01X1598261Y313301D02*
X1585299D01*
G01X1584923Y314877D02*
X1589664D01*
G01X1584237Y315563D02*
X1584923Y314877D01*
G01X1574900Y315563D02*
X1584237D01*
G01X1570541Y319922D02*
X1574900Y315563D01*
G01X1551631Y319922D02*
X1570541D01*
G01X1551250Y320303D02*
X1551631Y319922D01*
G01X1579013Y301516D02*
X1590127Y290402D01*
G01X1570119Y301516D02*
X1579013D01*
G01X1565738Y305897D02*
X1570119Y301516D01*
G01X1565099Y305897D02*
X1565738D01*
G01X1562126Y302924D02*
X1565099Y305897D01*
G01X1556661Y302924D02*
X1562126D01*
G01X1554914Y304671D02*
X1556661Y302924D01*
G01X1544957Y304671D02*
X1554914D01*
G01X1544455Y305173D02*
X1544957Y304671D01*
G01X1542320Y305173D02*
X1544455D01*
G01X1538613Y308880D02*
X1542320Y305173D01*
G01X1537995Y308880D02*
X1538613D01*
G01X1534813Y312062D02*
X1537995Y308880D01*
G01X1532505Y312062D02*
X1534813D01*
G01X1529790Y309347D02*
X1532505Y312062D01*
G01X1546552Y292368D02*
X1541315Y297605D01*
G01X1552389Y292368D02*
X1546552D01*
G01X1552949Y292928D02*
X1552389Y292368D01*
G01X1555765Y292928D02*
X1552949D01*
G01X1556065Y292628D02*
X1555765Y292928D01*
G01X1565458Y292628D02*
X1556065D01*
G01X1568057Y290029D02*
X1565458Y292628D01*
G01X1571601Y290029D02*
X1568057D01*
G01X1576996Y284634D02*
X1571601Y290029D01*
G01X1576996Y284166D02*
Y284634D01*
G01X1577234Y283928D02*
X1576996Y284166D01*
G01X1577234Y283887D02*
Y283928D01*
G01X1578209Y282912D02*
X1577234Y283887D01*
G01X1579163Y282912D02*
X1578209D01*
G01X1581076Y284825D02*
X1579163Y282912D01*
G01X1581077Y284825D02*
X1581076D01*
G01X1564400Y307326D02*
Y308383D01*
G01X1561677Y304603D02*
X1564400Y307326D01*
G01X1557110Y304603D02*
X1561677D01*
G01X1555538Y306175D02*
X1557110Y304603D01*
G01X1545581Y306175D02*
X1555538D01*
G01X1545079Y306677D02*
X1545581Y306175D01*
G01X1542944Y306677D02*
X1545079D01*
G01X1539237Y310384D02*
X1542944Y306677D01*
G01X1538619Y310384D02*
X1539237D01*
G01X1535437Y313566D02*
X1538619Y310384D01*
G01X1545412Y299960D02*
X1543207Y302165D01*
G01X1558000Y299960D02*
X1545412D01*
G01X1560247Y297713D02*
X1558000Y299960D01*
G01X1577023Y297713D02*
X1560247D01*
G01X1579612Y295124D02*
X1577023Y297713D01*
G01X1579612Y294855D02*
Y295124D01*
G01X1580975Y293492D02*
X1579612Y294855D01*
G01X1581244Y293492D02*
X1580975D01*
G01X1586117Y288619D02*
X1581244Y293492D01*
G01X1586739Y288619D02*
X1586117D01*
G01X1586740Y288620D02*
X1586739Y288619D01*
G01X1600720Y288620D02*
X1586740D01*
G01X1531536Y292400D02*
X1527787Y288651D01*
G01X1537100Y292400D02*
X1531536D01*
G01X1537500Y292800D02*
X1537100Y292400D01*
G01X1530459Y321976D02*
X1528043Y324392D01*
G01X1533424Y321976D02*
X1530459D01*
G01X1533452Y321948D02*
X1533424Y321976D01*
G01X1539881Y321948D02*
X1533452D01*
G01X1543600Y318229D02*
X1539881Y321948D01*
G01X1543600Y316100D02*
Y318229D01*
G01X1546496Y313204D02*
X1543600Y316100D01*
G01X1546496Y312373D02*
Y313204D01*
G01X1547419Y311450D02*
X1546496Y312373D01*
G01X1549121Y311450D02*
X1547419D01*
G01X1550271Y312600D02*
X1549121Y311450D01*
G01X1558091Y312600D02*
X1550271D01*
G01X1562280Y316789D02*
X1558091Y312600D01*
G01X1569418Y316789D02*
X1562280D01*
G01X1575683Y310524D02*
X1569418Y316789D01*
G01X1597612Y310524D02*
X1575683D01*
G01X1556987Y311096D02*
X1560400Y307683D01*
G01X1550936Y311096D02*
X1556987D01*
G01X1550792Y310952D02*
X1550936Y311096D01*
G01X1550751Y310952D02*
X1550792D01*
G01X1549828Y310029D02*
X1550751Y310952D01*
G01X1549828Y309988D02*
Y310029D01*
G01X1549144Y309304D02*
X1549828Y309988D01*
G01X1543621Y309304D02*
X1549144D01*
G01X1542300Y310625D02*
X1543621Y309304D01*
G01X1542300Y310734D02*
Y310625D01*
G01X1542288Y310746D02*
X1542300Y310734D01*
G01X1542288Y315284D02*
Y310746D01*
G01X1539920Y317652D02*
X1542288Y315284D01*
G01X1527772Y317652D02*
X1539920D01*
G01X1581940Y296360D02*
Y295820D01*
G01X1579083Y299217D02*
X1581940Y296360D01*
G01X1560871Y299217D02*
X1579083D01*
G01X1558624Y301464D02*
X1560871Y299217D01*
G01X1546036Y301464D02*
X1558624D01*
G01X1543831Y303669D02*
X1546036Y301464D01*
G01X1541696Y303669D02*
X1543831D01*
G01X1537989Y307376D02*
X1541696Y303669D01*
G01X1531279Y307376D02*
X1537989D01*
G01X1529301Y305398D02*
X1531279Y307376D01*
G01X1552363Y286993D02*
X1549489Y284119D01*
G01X1557692Y286993D02*
X1552363D01*
G01X1558671Y287972D02*
X1557692Y286993D01*
G01X1560984Y287972D02*
X1558671D01*
G01X1567548Y281408D02*
X1560984Y287972D01*
G01X1582040Y281408D02*
X1567548D01*
G01X1583547Y282915D02*
X1582040Y281408D01*
G01X1598557Y282915D02*
X1583547D01*
G01X1586598Y334846D02*
X1596375D01*
G01X1586033Y334281D02*
X1586598Y334846D01*
G01X1577672Y334281D02*
X1586033D01*
G01X1576825Y333434D02*
X1577672Y334281D01*
G01X1569919Y333434D02*
X1576825D01*
G01X1569211Y334142D02*
X1569919Y333434D01*
G01X1530482Y290282D02*
X1528099Y287899D01*
G01X1545446Y290282D02*
X1530482D01*
G01X1545616Y290112D02*
X1545446Y290282D01*
G01X1547433Y290112D02*
X1545616D01*
G01X1549573Y287972D02*
X1547433Y290112D01*
G01X1557607Y287972D02*
X1549573D01*
G01X1558359Y288724D02*
X1557607Y287972D01*
G01X1560153Y288724D02*
X1558359D01*
G01X1560281Y288852D02*
X1560153Y288724D01*
G01X1561168Y288852D02*
X1560281D01*
G01X1561972Y288048D02*
X1561168Y288852D01*
G01X1564145Y288048D02*
X1561972D01*
G01X1567736Y284457D02*
X1564145Y288048D01*
G01X1570944Y284457D02*
X1567736D01*
G01X1571242Y284755D02*
X1570944Y284457D01*
G01X1571293Y284755D02*
X1571242D01*
G01X1563619Y279622D02*
X1609503D01*
G01X1559517Y283724D02*
X1563619Y279622D01*
G01X1559147Y283724D02*
X1559517D01*
G01X1558224Y284647D02*
X1559147Y283724D01*
G01X1558224Y285017D02*
Y284647D01*
G01X1557752Y285489D02*
X1558224Y285017D01*
G01X1552987Y285489D02*
X1557752D01*
G01X1549862Y282364D02*
X1552987Y285489D01*
G01X1552900Y281700D02*
X1552060Y280860D01*
G01X1553446Y284737D02*
X1550321Y281612D01*
G01X1557070Y284737D02*
X1553446D01*
G01X1558835Y282972D02*
X1557070Y284737D01*
G01X1559205Y282972D02*
X1558835D01*
G01X1586983Y333809D02*
X1596682D01*
G01X1586703Y333529D02*
X1586983Y333809D01*
G01X1577984Y333529D02*
X1586703D01*
G01X1576939Y332484D02*
X1577984Y333529D01*
G01X1570153Y332484D02*
X1576939D01*
G01X1569211Y331542D02*
X1570153Y332484D01*
G01X1530771Y322728D02*
X1528355Y325144D01*
G01X1540165Y322728D02*
X1530771D01*
G01X1544600Y318293D02*
X1540165Y322728D01*
G01X1544600Y316382D02*
Y318293D01*
G01X1547765Y313217D02*
X1544600Y316382D01*
G01X1548263Y313217D02*
X1547765D01*
G01X1548273Y313227D02*
X1548263Y313217D01*
G01X1575171Y312100D02*
X1582800D01*
G01X1569730Y317541D02*
X1575171Y312100D01*
G01X1561968Y317541D02*
X1569730D01*
G01X1557971Y313544D02*
X1561968Y317541D01*
G01X1548590Y313544D02*
X1557971D01*
G01X1548273Y313227D02*
X1548590Y313544D01*
G01X1530500Y287700D02*
X1527945Y285145D01*
G01X1581390Y308200D02*
X1587800D01*
G01X1578393Y305203D02*
X1581390Y308200D01*
G01X1569937Y305203D02*
X1578393D01*
G01X1566051Y309089D02*
X1569937Y305203D01*
G01X1566051Y311943D02*
Y309089D01*
G01X1565328Y312666D02*
X1566051Y311943D01*
G01X1563448Y312666D02*
X1565328D01*
G01X1562786Y312004D02*
X1563448Y312666D01*
G01X1562786Y306776D02*
Y312004D01*
G01X1561365Y305355D02*
X1562786Y306776D01*
G01X1557422Y305355D02*
X1561365D01*
G01X1555850Y306927D02*
X1557422Y305355D01*
G01X1545893Y306927D02*
X1555850D01*
G01X1545391Y307429D02*
X1545893Y306927D01*
G01X1543256Y307429D02*
X1545391D01*
G01X1539549Y311136D02*
X1543256Y307429D01*
G01X1538931Y311136D02*
X1539549D01*
G01X1535749Y314318D02*
X1538931Y311136D01*
G01X1574131Y322178D02*
X1575645Y320664D01*
G01X1554254Y322178D02*
X1574131D01*
G01X1549147Y327285D02*
X1554254Y322178D01*
G01X1544055Y327285D02*
X1549147D01*
G01X1539075Y332265D02*
X1544055Y327285D01*
G01X1530121Y332265D02*
X1539075D01*
G01X1528654Y333732D02*
X1530121Y332265D01*
G01X1586275Y336122D02*
X1593969D01*
G01X1585186Y335033D02*
X1586275Y336122D01*
G01X1577360Y335033D02*
X1585186D01*
G01X1576697Y334370D02*
X1577360Y335033D01*
G01X1571964Y334370D02*
X1576697D01*
G01X1570258Y336076D02*
X1571964Y334370D01*
G01X1561691Y336076D02*
X1570258D01*
G01X1559633Y338134D02*
X1561691Y336076D01*
G01X1554819Y338134D02*
X1559633D01*
G01X1550753Y342200D02*
X1554819Y338134D01*
G01X1573803Y284882D02*
X1573790Y284895D01*
G01X1574398Y284882D02*
X1573803D01*
G01X1577120Y282160D02*
X1574398Y284882D01*
G01X1581309Y282160D02*
X1577120D01*
G01X1582368Y283219D02*
X1581309Y282160D01*
G01X1582397Y283219D02*
X1582368D01*
G01X1582970Y283792D02*
X1582397Y283219D01*
G01X1598744Y283792D02*
X1582970D01*
G01X1585965Y337274D02*
X1593491D01*
G01X1584476Y335785D02*
X1585965Y337274D01*
G01X1577048Y335785D02*
X1584476D01*
G01X1576785Y335522D02*
X1577048Y335785D01*
G01X1572442Y335522D02*
X1576785D01*
G01X1570736Y337228D02*
X1572442Y335522D01*
G01X1565724Y337228D02*
X1570736D01*
G01X1564024Y338928D02*
X1565724Y337228D01*
G01X1564024Y339976D02*
Y338928D01*
G01X1563000Y341000D02*
X1564024Y339976D01*
G01X1552675Y286241D02*
X1549801Y283367D01*
G01X1558859Y286241D02*
X1552675D01*
G01X1559800Y285300D02*
X1558859Y286241D01*
G01X1554800Y341100D02*
X1558721Y345021D01*
G01X1547176Y293872D02*
X1541939Y299109D01*
G01X1551765Y293872D02*
X1547176D01*
G01X1553153Y295260D02*
X1551765Y293872D01*
G01X1553153Y295935D02*
Y295260D01*
G01X1554122Y296904D02*
X1553153Y295935D01*
G01X1556732Y296904D02*
X1554122D01*
G01X1558979Y294657D02*
X1556732Y296904D01*
G01X1565609Y294657D02*
X1558979D01*
G01X1568606Y291660D02*
X1565609Y294657D01*
G01X1572338Y291660D02*
X1568606D01*
G01X1576710Y287288D02*
X1572338Y291660D01*
G01X1582626Y287288D02*
X1576710D01*
G01X1584355Y285559D02*
X1582626Y287288D01*
G01X1598833Y285559D02*
X1584355D01*
G01X1581561Y318318D02*
X1581834Y318591D01*
G01X1575607Y318318D02*
X1581561D01*
G01X1573727Y320198D02*
X1575607Y318318D01*
G01X1572393Y320198D02*
X1573727D01*
G01X1571165Y321426D02*
X1572393Y320198D01*
G01X1553942Y321426D02*
X1571165D01*
G01X1551623Y323745D02*
X1553942Y321426D01*
G01X1546531Y323745D02*
X1551623D01*
G01X1543209Y327067D02*
X1546531Y323745D01*
G01X1537653Y327067D02*
X1543209D01*
G01X1534584Y330136D02*
X1537653Y327067D01*
G01X1530939Y330136D02*
X1534584D01*
G01X1528095Y332980D02*
X1530939Y330136D01*
G01X1531903Y305872D02*
X1529925Y303894D01*
G01X1535203Y305872D02*
X1531903D01*
G01X1536027Y305048D02*
X1535203Y305872D01*
G01X1584899Y312549D02*
X1598573D01*
G01X1583544Y313904D02*
X1584899Y312549D01*
G01X1574431Y313904D02*
X1583544D01*
G01X1570042Y318293D02*
X1574431Y313904D01*
G01X1557521Y318293D02*
X1570042D01*
G01X1554228Y315000D02*
X1557521Y318293D01*
G01X1548300Y315000D02*
X1554228D01*
G01X1547300Y316000D02*
X1548300Y315000D01*
G01X1547300Y316657D02*
Y316000D01*
G01X1538981Y324976D02*
X1547300Y316657D01*
G01X1536653Y324976D02*
X1538981D01*
G01X1533529Y328100D02*
X1536653Y324976D01*
G01X1557550Y342503D02*
Y341100D01*
G01X1531773Y293701D02*
X1527858Y289786D01*
G01X1536001Y293701D02*
X1531773D01*
G01X1536800Y294500D02*
X1536001Y293701D01*
G01X1542292Y294500D02*
X1536800D01*
G01X1545928Y290864D02*
X1542292Y294500D01*
G01X1547745Y290864D02*
X1545928D01*
G01X1549885Y288724D02*
X1547745Y290864D01*
G01X1557295Y288724D02*
X1549885D01*
G01X1558047Y289476D02*
X1557295Y288724D01*
G01X1559029Y289476D02*
X1558047D01*
G01X1559500Y289947D02*
X1559029Y289476D01*
G01X1559500Y290300D02*
Y289947D01*
G01X1582784Y401683D02*
X1587501Y406400D01*
G01X1579507Y401683D02*
X1582784D01*
G01X1573808Y395984D02*
X1579507Y401683D01*
G01X1559024Y395984D02*
X1573808D01*
G01X1557345Y394305D02*
X1559024Y395984D01*
G01X1557345Y393763D02*
Y394305D01*
G01X1556424Y392842D02*
X1557345Y393763D01*
G01X1549512Y392842D02*
X1556424D01*
G01X1547595Y390925D02*
X1549512Y392842D01*
G01X1547595Y390383D02*
Y390925D01*
G01X1546676Y389464D02*
X1547595Y390383D01*
G01X1541474Y389464D02*
X1546676D01*
G01X1539795Y391143D02*
X1541474Y389464D01*
G01X1539795Y391685D02*
Y391143D01*
G01X1538798Y392682D02*
X1539795Y391685D01*
G01X1588623Y352572D02*
X1588847Y352796D01*
G01X1585535Y352572D02*
X1588623D01*
G01X1585054Y353053D02*
X1585535Y352572D01*
G01X1570997Y353053D02*
X1585054D01*
G01X1568629Y350685D02*
X1570997Y353053D01*
G01X1565944Y350685D02*
X1568629D01*
G01X1560609Y356020D02*
X1565944Y350685D01*
G01X1554951Y356020D02*
X1560609D01*
G01X1552731Y353800D02*
X1554951Y356020D01*
G01X1549672Y353800D02*
X1552731D01*
G01X1543632Y347760D02*
X1549672Y353800D01*
G01X1540540Y347760D02*
X1543632D01*
G01X1540300Y348000D02*
X1540540Y347760D01*
G01X1540300Y351472D02*
Y348000D01*
G01X1538478Y353294D02*
X1540300Y351472D01*
G01X1530805Y380785D02*
X1529126Y382464D01*
G01X1530805Y380243D02*
Y380785D01*
G01X1531724Y379324D02*
X1530805Y380243D01*
G01X1556426Y379324D02*
X1531724D01*
G01X1557873Y380771D02*
X1556426Y379324D01*
G01X1557873Y381313D02*
Y380771D01*
G01X1559024Y382464D02*
X1557873Y381313D01*
G01X1560326Y382464D02*
X1559024D01*
G01X1562005Y380785D02*
X1560326Y382464D01*
G01X1562005Y380243D02*
Y380785D01*
G01X1564734Y377514D02*
X1562005Y380243D01*
G01X1565525Y377514D02*
X1564734D01*
G01X1533673Y344000D02*
X1531500Y346173D01*
G01X1542072Y344000D02*
X1533673D01*
G01X1542073Y343999D02*
X1542072Y344000D01*
G01X1545191Y343999D02*
X1542073D01*
G01X1545192Y344000D02*
X1545191Y343999D01*
G01X1554800Y344000D02*
X1545192D01*
G01X1556973Y346173D02*
X1554800Y344000D01*
G01X1571501Y346173D02*
X1556973D01*
G01X1573166Y347838D02*
X1571501Y346173D01*
G01X1583555Y347838D02*
X1573166D01*
G01X1585052Y346341D02*
X1583555Y347838D01*
G01X1591953Y346341D02*
X1585052D01*
G01X1576804Y372900D02*
X1567121Y363217D01*
G01X1588680Y372900D02*
X1576804D01*
G01X1596590Y364990D02*
X1588680Y372900D01*
G01X1535804Y364868D02*
X1533719Y362783D01*
G01X1535804Y367371D02*
Y364868D01*
G01X1537533Y369100D02*
X1535804Y367371D01*
G01X1560170Y369100D02*
X1537533D01*
G01X1562321Y366949D02*
X1560170Y369100D01*
G01X1562321Y360431D02*
Y366949D01*
G01X1565812Y356940D02*
X1562321Y360431D01*
G01X1581419Y356940D02*
X1565812D01*
G01X1587132Y362653D02*
X1581419Y356940D01*
G01X1587684Y362653D02*
X1587132D01*
G01X1577244Y380660D02*
X1599605Y403021D01*
G01X1570590Y380660D02*
X1577244D01*
G01X1568550Y382700D02*
X1570590Y380660D01*
G01X1564878Y382700D02*
X1568550D01*
G01X1563195Y384383D02*
X1564878Y382700D01*
G01X1563195Y384925D02*
Y384383D01*
G01X1562276Y385844D02*
X1563195Y384925D01*
G01X1553174Y385844D02*
X1562276D01*
G01X1551495Y384165D02*
X1553174Y385844D01*
G01X1551495Y383623D02*
Y384165D01*
G01X1550576Y382704D02*
X1551495Y383623D01*
G01X1537574Y382704D02*
X1550576D01*
G01X1536655Y383623D02*
X1537574Y382704D01*
G01X1536655Y384165D02*
Y383623D01*
G01X1534976Y385844D02*
X1536655Y384165D01*
G01X1531995Y385844D02*
X1534976D01*
G01X1530425Y384274D02*
X1531995Y385844D01*
G01X1579629Y343069D02*
X1583650D01*
G01X1578589Y342029D02*
X1579629Y343069D01*
G01X1578461Y359600D02*
X1576074D01*
G01X1585121Y366260D02*
X1578461Y359600D01*
G01X1590400Y366260D02*
X1585121D01*
G01X1573084Y399584D02*
X1580700Y407200D01*
G01X1551244Y399584D02*
X1573084D01*
G01X1549950Y400878D02*
X1551244Y399584D01*
G01X1549950Y404490D02*
Y400878D01*
G01X1585691Y347846D02*
X1591501D01*
G01X1584136Y349401D02*
X1585691Y347846D01*
G01X1572432Y349401D02*
X1584136D01*
G01X1570708Y347677D02*
X1572432Y349401D01*
G01X1556349Y347677D02*
X1570708D01*
G01X1554176Y345504D02*
X1556349Y347677D01*
G01X1544568Y345504D02*
X1554176D01*
G01X1544567Y345503D02*
X1544568Y345504D01*
G01X1542697Y345503D02*
X1544567D01*
G01X1542696Y345504D02*
X1542697Y345503D01*
G01X1536526Y345504D02*
X1542696D01*
G01X1528107Y353923D02*
X1536526Y345504D01*
G01X1528107Y380526D02*
Y353923D01*
G01X1528475Y380894D02*
X1528107Y380526D01*
G01X1546025Y400705D02*
Y401985D01*
G01X1544145Y398825D02*
X1546025Y400705D01*
G01X1544145Y397115D02*
Y398825D01*
G01X1542505Y395475D02*
X1544145Y397115D01*
G01X1542505Y393763D02*
Y395475D01*
G01X1545234Y391034D02*
X1542505Y393763D01*
G01X1546025Y391034D02*
X1545234D01*
G01X1539548Y349624D02*
X1538478Y350694D01*
G01X1539548Y347688D02*
Y349624D01*
G01X1540228Y347008D02*
X1539548Y347688D01*
G01X1543320Y347008D02*
X1540228D01*
G01X1543321Y347007D02*
X1543320Y347008D01*
G01X1543943Y347007D02*
X1543321D01*
G01X1549984Y353048D02*
X1543943Y347007D01*
G01X1553043Y353048D02*
X1549984D01*
G01X1555263Y355268D02*
X1553043Y353048D01*
G01X1560297Y355268D02*
X1555263D01*
G01X1565632Y349933D02*
X1560297Y355268D01*
G01X1569349Y349933D02*
X1565632D01*
G01X1571314Y351898D02*
X1569349Y349933D01*
G01X1585145Y351898D02*
X1571314D01*
G01X1586047Y350996D02*
X1585145Y351898D01*
G01X1587032Y350996D02*
X1586047D01*
G01X1552700Y358300D02*
X1552500Y358500D01*
G01X1562324Y358300D02*
X1552700D01*
G01X1565188Y355436D02*
X1562324Y358300D01*
G01X1582164Y355436D02*
X1565188D01*
G01X1583503Y356775D02*
X1582164Y355436D01*
G01X1587475Y356775D02*
X1583503D01*
G01X1589100Y358400D02*
X1587475Y356775D01*
G01X1582470Y384660D02*
X1610580D01*
G01X1573754Y375944D02*
X1582470Y384660D01*
G01X1560974Y375944D02*
X1573754D01*
G01X1559675Y377243D02*
X1560974Y375944D01*
G01X1559675Y380894D02*
Y377243D01*
G01X1542384Y344752D02*
X1536214D01*
G01X1542385Y344751D02*
X1542384Y344752D01*
G01X1544879Y344751D02*
X1542385D01*
G01X1544880Y344752D02*
X1544879Y344751D01*
G01X1554488Y344752D02*
X1544880D01*
G01X1556661Y346925D02*
X1554488Y344752D01*
G01X1571020Y346925D02*
X1556661D01*
G01X1572685Y348590D02*
X1571020Y346925D01*
G01X1583867Y348590D02*
X1572685D01*
G01X1585364Y347093D02*
X1583867Y348590D01*
G01X1591445Y347093D02*
X1585364D01*
G01X1550726Y350113D02*
X1550639Y350200D01*
G01X1558384Y350113D02*
X1550726D01*
G01X1559847Y351576D02*
X1558384Y350113D01*
G01X1561214Y351576D02*
X1559847D01*
G01X1564361Y348429D02*
X1561214Y351576D01*
G01X1569973Y348429D02*
X1564361D01*
G01X1571938Y350394D02*
X1569973Y348429D01*
G01X1584251Y350394D02*
X1571938D01*
G01X1585977Y348668D02*
X1584251Y350394D01*
G01X1591068Y348668D02*
X1585977D01*
G01X1533783Y360283D02*
X1533790D01*
G01X1533783Y360518D02*
Y360283D01*
G01X1536604Y363339D02*
X1533783Y360518D01*
G01X1536604Y366716D02*
Y363339D01*
G01X1538088Y368200D02*
X1536604Y366716D01*
G01X1559830Y368200D02*
X1538088D01*
G01X1561300Y366730D02*
X1559830Y368200D01*
G01X1561300Y360388D02*
Y366730D01*
G01X1565500Y356188D02*
X1561300Y360388D01*
G01X1581852Y356188D02*
X1565500D01*
G01X1584064Y358400D02*
X1581852Y356188D01*
G01X1586500Y358400D02*
X1584064D01*
G01X1587644Y353324D02*
X1589082Y354762D01*
G01X1585847Y353324D02*
X1587644D01*
G01X1585271Y353900D02*
X1585847Y353324D01*
G01X1564596Y353900D02*
X1585271D01*
G01X1561723Y356773D02*
X1564596Y353900D01*
G01X1554640Y356773D02*
X1561723D01*
G01X1553110Y355243D02*
X1554640Y356773D01*
G01X1548756Y355243D02*
X1553110D01*
G01X1547200Y353687D02*
X1548756Y355243D01*
G01X1544516Y353687D02*
X1547200D01*
G01X1544181Y354022D02*
X1544516Y353687D01*
G01X1541293Y354022D02*
X1544181D01*
G01X1540799Y354516D02*
X1541293Y354022D01*
G01X1540799Y356000D02*
Y354516D01*
G01X1538500Y358299D02*
X1540799Y356000D01*
G01X1538500Y359363D02*
Y358299D01*
G01X1540149Y371690D02*
X1534325Y377514D01*
G01X1559830Y371690D02*
X1540149D01*
G01X1563170Y368350D02*
X1559830Y371690D01*
G01X1563170Y360770D02*
Y368350D01*
G01X1566230Y357710D02*
X1563170Y360770D01*
G01X1578930Y357710D02*
X1566230D01*
G01X1585740Y364520D02*
X1578930Y357710D01*
G01X1589750Y364520D02*
X1585740D01*
G01X1566922Y360613D02*
Y359681D01*
G01X1570031Y363722D02*
X1566922Y360613D01*
G01X1570031Y364548D02*
Y363722D01*
G01X1577383Y371900D02*
X1570031Y364548D01*
G01X1588330Y371900D02*
X1577383D01*
G01X1596220Y364010D02*
X1588330Y371900D01*
G01X1561321Y389300D02*
X1582600D01*
G01X1559675Y387654D02*
X1561321Y389300D01*
G01X1560339Y374900D02*
X1557725Y377514D01*
G01X1575590Y374900D02*
X1560339D01*
G01X1576870Y376180D02*
X1575590Y374900D01*
G01X1584750Y376180D02*
X1576870D01*
G01X1591710Y383140D02*
X1584750Y376180D01*
G01X1538605Y387545D02*
X1536800Y389350D01*
G01X1538605Y387003D02*
Y387545D01*
G01X1539524Y386084D02*
X1538605Y387003D01*
G01X1548626Y386084D02*
X1539524D01*
G01X1549545Y387003D02*
X1548626Y386084D01*
G01X1549545Y387545D02*
Y387003D01*
G01X1551350Y389350D02*
X1549545Y387545D01*
G01X1558262Y389350D02*
X1551350D01*
G01X1559800Y390888D02*
X1558262Y389350D01*
G01X1559800Y391430D02*
Y390888D01*
G01X1562784Y394414D02*
X1559800Y391430D01*
G01X1563575Y394414D02*
X1562784D01*
G01X1548100Y342200D02*
X1550753D01*
G01X1589225Y342084D02*
X1588551Y341410D01*
G01X1536902Y354318D02*
X1538478Y355894D01*
G01X1536902Y347697D02*
Y354318D01*
G01X1538343Y346256D02*
X1536902Y347697D01*
G01X1543008Y346256D02*
X1538343D01*
G01X1543009Y346255D02*
X1543008Y346256D01*
G01X1544255Y346255D02*
X1543009D01*
G01X1549750Y351750D02*
X1544255Y346255D01*
G01X1549960Y351750D02*
X1549750D01*
G01X1549986Y351776D02*
X1549960Y351750D01*
G01X1558213Y351776D02*
X1549986D01*
G01X1559049Y352612D02*
X1558213Y351776D01*
G01X1561425Y352612D02*
X1559049D01*
G01X1564856Y349181D02*
X1561425Y352612D01*
G01X1569661Y349181D02*
X1564856D01*
G01X1571626Y351146D02*
X1569661Y349181D01*
G01X1584563Y351146D02*
X1571626D01*
G01X1586289Y349420D02*
X1584563Y351146D01*
G01X1588723Y349420D02*
X1586289D01*
G01X1590218Y350915D02*
X1588723Y349420D01*
G01X1572890Y361090D02*
X1571450Y359650D01*
G01X1572890Y362150D02*
Y361090D01*
G01X1578540Y367800D02*
X1572890Y362150D01*
G01X1591040Y367800D02*
X1578540D01*
G01X1585150Y398606D02*
Y397400D01*
G01X1586571Y400027D02*
X1585150Y398606D01*
G01X1593859Y400027D02*
X1586571D01*
G01X1540038Y361861D02*
X1538397D01*
G01X1544299Y357600D02*
X1540038Y361861D01*
G01X1551171Y357600D02*
X1544299D01*
G01X1551847Y356924D02*
X1551171Y357600D01*
G01X1553727Y356924D02*
X1551847D01*
G01X1554328Y357525D02*
X1553727Y356924D01*
G01X1562035Y357525D02*
X1554328D01*
G01X1564876Y354684D02*
X1562035Y357525D01*
G01X1586284Y354684D02*
X1564876D01*
G01X1586500Y354900D02*
X1586284Y354684D01*
G01X1582235Y400820D02*
X1593588D01*
G01X1575829Y394414D02*
X1582235Y400820D01*
G01X1571375Y394414D02*
X1575829D01*
G01X1584586Y345189D02*
X1593098D01*
G01X1583099Y346676D02*
X1584586Y345189D01*
G01X1573634Y346676D02*
X1583099D01*
G01X1571979Y345021D02*
X1573634Y346676D01*
G01X1558721Y345021D02*
X1571979D01*
G01X1573250Y402950D02*
X1578400Y408100D01*
G01X1559675Y401174D02*
X1561451Y402950D01*
G01X1567335Y386084D02*
X1565525Y384274D01*
G01X1581605Y386084D02*
X1567335D01*
G01X1584170Y388649D02*
X1581605Y386084D01*
G01X1584170Y394070D02*
Y388649D01*
G01X1585300Y395200D02*
X1584170Y394070D01*
G01X1590215Y395200D02*
X1585300D01*
G01X1559116Y344069D02*
X1557550Y342503D01*
G01X1572374Y344069D02*
X1559116D01*
G01X1574029Y345724D02*
X1572374Y344069D01*
G01X1582987Y345724D02*
X1574029D01*
G01X1584474Y344237D02*
X1582987Y345724D01*
G01X1593493Y344237D02*
X1584474D01*
G01X1587501Y406400D02*
X1592300D01*
G01X1580700Y407200D02*
X1591800D01*
G01X1584335Y442765D02*
X1593400Y433700D01*
G01X1584335Y447038D02*
Y442765D01*
G01X1582847Y448526D02*
X1584335Y447038D01*
G01X1558974Y448526D02*
X1582847D01*
G01X1556800Y450700D02*
X1558974Y448526D01*
G01X1554800Y450700D02*
X1556800D01*
G01X1552836Y448736D02*
X1554800Y450700D01*
G01X1548735Y448736D02*
X1552836D01*
G01X1544453Y453018D02*
X1548735Y448736D01*
G01X1528840Y453018D02*
X1544453D01*
G01X1528798Y452976D02*
X1528840Y453018D01*
G01X1527584Y452976D02*
X1528798D01*
G01X1527542Y453018D02*
X1527584Y452976D01*
G01X1576860Y417274D02*
X1588986Y429400D01*
G01X1576860Y410302D02*
Y417274D01*
G01X1574464Y407906D02*
X1576860Y410302D01*
G01X1587926Y442718D02*
X1589200D01*
G01X1585997Y444647D02*
X1587926Y442718D01*
G01X1585997Y446715D02*
Y444647D01*
G01X1583358Y449354D02*
X1585997Y446715D01*
G01X1560680Y452320D02*
X1561039Y451961D01*
G01X1558949Y452320D02*
X1560680D01*
G01X1558729Y452100D02*
X1558949Y452320D01*
G01X1547200Y452100D02*
X1558729D01*
G01X1545645Y453655D02*
X1547200Y452100D01*
G01X1545645Y457717D02*
Y453655D01*
G01X1544562Y458800D02*
X1545645Y457717D01*
G01X1541357Y458800D02*
X1544562D01*
G01X1540295Y459862D02*
X1541357Y458800D01*
G01X1540295Y460970D02*
Y459862D01*
G01X1539051Y462214D02*
X1540295Y460970D01*
G01X1535141Y462214D02*
X1539051D01*
G01X1534296Y463059D02*
X1535141Y462214D01*
G01X1534296Y464495D02*
Y463059D01*
G01X1532582Y466209D02*
X1534296Y464495D01*
G01X1558512Y459082D02*
G02X1560679Y459166I1163J-2016D01*
G01X1556938Y459082D02*
G03X1558512I787J1364D01*
G01X1554612D02*
G02X1556938I1163J-2016D01*
G01X1553038D02*
G03X1554612I787J1364D01*
G01X1550712D02*
G02X1553038I1163J-2016D01*
G01X1549138D02*
G03X1550712I787J1364D01*
G01X1548351Y460398D02*
G03X1549138Y459082I1574J48D01*
G01X1548351Y460527D02*
Y460398D01*
G01X1547188Y462462D02*
G02X1548351Y460527I-1163J-2016D01*
G01X1545092Y462579D02*
G02X1547188Y462462I932J-2133D01*
G01X1544740Y462673D02*
X1545092Y462579D01*
G01X1544075Y463826D02*
X1544740Y462673D01*
G01X1546405Y460066D02*
X1546025Y460446D01*
G01X1546405Y456415D02*
Y460066D01*
G01X1547420Y455400D02*
X1546405Y456415D01*
G01X1559100Y455400D02*
X1547420D01*
G01X1575748Y464550D02*
X1572440Y461242D01*
G01X1591949Y464550D02*
X1575748D01*
G01X1578400Y417750D02*
X1588850Y428200D01*
G01X1578400Y408100D02*
Y417750D01*
G01X1561451Y402950D02*
X1573250D01*
G01X1539640Y468900D02*
X1596780D01*
G01X1538100Y470440D02*
X1539640Y468900D01*
G01X1538100Y470982D02*
Y470440D01*
G01X1536384Y472698D02*
X1538100Y470982D01*
G01X1536384Y474585D02*
Y472698D01*
G01X1535345Y475624D02*
X1536384Y474585D01*
G01X1587609Y484701D02*
X1608755Y463555D01*
G01X1570179Y484701D02*
X1587609D01*
G01X1568964Y485916D02*
X1570179Y484701D01*
G01X1581519Y487200D02*
X1578318Y490401D01*
G01X1588400Y487200D02*
X1581519D01*
G01X1603600Y472000D02*
X1588400Y487200D01*
G01X1581183Y488600D02*
X1590629D01*
G01X1578630Y491153D02*
X1581183Y488600D01*
G01X1578628Y491153D02*
X1578630D01*
G01X1578606Y491175D02*
X1578628Y491153D01*
G01X1532582Y467736D02*
Y466209D01*
G01X1531427Y468891D02*
X1532582Y467736D01*
G01X1540175Y474237D02*
Y470586D01*
G01X1538267Y476145D02*
X1540175Y474237D01*
G01X1538267Y478062D02*
Y476145D01*
G01X1537181Y479148D02*
X1538267Y478062D01*
G01X1588300Y486200D02*
X1610336Y464164D01*
G01X1581455Y486200D02*
X1588300D01*
G01X1578006Y489649D02*
X1581455Y486200D01*
G01X1578184Y479156D02*
X1584970Y472370D01*
G01X1568774Y479156D02*
X1578184D01*
G01X1567307Y480623D02*
X1568774Y479156D01*
G01X1567307Y481260D02*
Y480623D01*
G01X1566111Y482456D02*
X1567307Y481260D01*
G01X1596871Y466809D02*
X1579009D01*
G01X1579781Y569610D02*
X1592369D01*
G01X1576467Y566296D02*
X1579781Y569610D01*
G01X1576467Y561846D02*
Y566296D01*
G01X1573005Y558384D02*
X1576467Y561846D01*
G01X1568804Y558384D02*
X1573005D01*
G01X1564665Y554245D02*
X1568804Y558384D01*
G01X1548590Y554245D02*
X1564665D01*
G01X1545006Y550661D02*
X1548590Y554245D01*
G01X1558698Y587258D02*
X1562474Y591034D01*
G01X1554358Y587258D02*
X1558698D01*
G01X1546813Y575650D02*
X1535704Y564541D01*
G01X1561886Y575650D02*
X1546813D01*
G01X1564163Y577927D02*
X1561886Y575650D01*
G01X1585233Y577927D02*
X1564163D01*
G01X1586438Y576722D02*
X1585233Y577927D01*
G01X1588782Y576722D02*
X1586438D01*
G01X1599694Y587634D02*
X1588782Y576722D01*
G01X1544330Y582539D02*
X1532556Y570765D01*
G01X1546519Y582539D02*
X1544330D01*
G01X1546520Y582540D02*
X1546519Y582539D01*
G01X1559064Y582540D02*
X1546520D01*
G01X1563990Y587466D02*
X1559064Y582540D01*
G01X1576574Y587466D02*
X1563990D01*
G01X1581504Y592396D02*
X1576574Y587466D01*
G01X1543747Y583948D02*
X1531972Y572173D01*
G01X1558480Y583948D02*
X1543747D01*
G01X1563406Y588874D02*
X1558480Y583948D01*
G01X1546294Y576902D02*
X1535185Y565793D01*
G01X1561367Y576902D02*
X1546294D01*
G01X1563644Y579179D02*
X1561367Y576902D01*
G01X1585752Y579179D02*
X1563644D01*
G01X1586957Y577974D02*
X1585752Y579179D01*
G01X1588263Y577974D02*
X1586957D01*
G01X1598442Y588153D02*
X1588263Y577974D01*
G01X1547156Y557701D02*
X1545183Y555728D01*
G01X1563231Y557701D02*
X1547156D01*
G01X1572257Y566727D02*
X1563231Y557701D01*
G01X1572257Y566976D02*
Y566727D01*
G01X1578347Y573066D02*
X1572257Y566976D01*
G01X1590363Y573066D02*
X1578347D01*
G01X1585919Y575470D02*
X1589301D01*
G01X1584832Y576557D02*
X1585919Y575470D01*
G01X1574883Y576557D02*
X1584832D01*
G01X1569767Y571441D02*
X1574883Y576557D01*
G01X1569767Y567638D02*
Y571441D01*
G01X1562329Y560200D02*
X1569767Y567638D01*
G01X1546254Y560200D02*
X1562329D01*
G01X1544186Y558132D02*
X1546254Y560200D01*
G01X1546678Y558853D02*
X1544705Y556880D01*
G01X1562753Y558853D02*
X1546678D01*
G01X1571067Y567167D02*
X1562753Y558853D01*
G01X1571067Y570970D02*
Y567167D01*
G01X1575384Y575287D02*
X1571067Y570970D01*
G01X1584331Y575287D02*
X1575384D01*
G01X1585400Y574218D02*
X1584331Y575287D01*
G01X1589820Y574218D02*
X1585400D01*
G01X1547634Y556549D02*
X1545661Y554576D01*
G01X1563709Y556549D02*
X1547634D01*
G01X1573410Y566250D02*
X1563709Y556549D01*
G01X1573410Y566499D02*
Y566250D01*
G01X1578825Y571914D02*
X1573410Y566499D01*
G01X1591231Y571914D02*
X1578825D01*
G01X1558596Y586056D02*
X1562822Y590282D01*
G01X1555385Y586056D02*
X1558596D01*
G01X1555011Y585682D02*
X1555385Y586056D01*
G01X1553705Y585682D02*
X1555011D01*
G01X1552799Y586588D02*
X1553705Y585682D01*
G01X1550990Y586588D02*
X1552799D01*
G01X1563459Y583335D02*
X1589272D01*
G01X1560154Y580030D02*
X1563459Y583335D01*
G01X1545363Y580030D02*
X1560154D01*
G01X1533594Y568261D02*
X1545363Y580030D01*
G01X1546540Y578778D02*
X1534707Y566945D01*
G01X1560673Y578778D02*
X1546540D01*
G01X1560760Y578865D02*
X1560673Y578778D01*
G01X1560859Y578865D02*
X1560760D01*
G01X1563839Y581845D02*
X1560859Y578865D01*
G01X1590041Y581845D02*
X1563839D01*
G01X1548112Y555397D02*
X1544528Y551813D01*
G01X1564187Y555397D02*
X1548112D01*
G01X1568326Y559536D02*
X1564187Y555397D01*
G01X1572527Y559536D02*
X1568326D01*
G01X1574967Y561976D02*
X1572527Y559536D01*
G01X1574967Y566426D02*
Y561976D01*
G01X1579303Y570762D02*
X1574967Y566426D01*
G01X1591823Y570762D02*
X1579303D01*
G01X1586802Y624402D02*
X1823926D01*
G01X1583000Y620600D02*
X1586802Y624402D01*
G01X1583000Y600047D02*
Y620600D01*
G01X1573987Y591034D02*
X1583000Y600047D01*
G01X1562474Y591034D02*
X1573987D01*
G01X1592934Y592396D02*
X1581504D01*
G01X1575990Y588874D02*
X1563406D01*
G01X1580921Y593805D02*
X1575990Y588874D01*
G01X1582087Y593805D02*
X1580921D01*
G01X1582088Y593804D02*
X1582087Y593805D01*
G01X1590604Y593804D02*
X1582088D01*
G01X1587450Y623650D02*
X1804678D01*
G01X1583752Y619952D02*
X1587450Y623650D01*
G01X1583752Y599735D02*
Y619952D01*
G01X1574299Y590282D02*
X1583752Y599735D01*
G01X1562822Y590282D02*
X1574299D01*
G01X1643218Y-5253D02*
X1654916D01*
G01X1637109Y856D02*
X1643218Y-5253D01*
G01X1604694Y856D02*
X1637109D01*
G01X1600501Y5049D02*
X1604694Y856D01*
G01X1590295Y-3221D02*
X1590294Y-3222D01*
G01X1591873Y-3221D02*
X1590295D01*
G01X1595796Y-7144D02*
X1591873Y-3221D01*
G01X1621074Y-7144D02*
X1595796D01*
G01X1623333Y-4885D02*
X1621074Y-7144D01*
G01X1624911Y-4885D02*
X1623333D01*
G01X1624912Y-4886D02*
X1624911Y-4885D01*
G01X1631776Y-4886D02*
X1624912D01*
G01X1636903Y-10013D02*
X1631776Y-4886D01*
G01X1657058Y-10013D02*
X1636903D01*
G01X1646660Y-13236D02*
X1657876D01*
G01X1646659Y-13237D02*
X1646660Y-13236D01*
G01X1641131Y-13237D02*
X1646659D01*
G01X1641130Y-13236D02*
X1641131Y-13237D01*
G01X1636085Y-13236D02*
X1641130D01*
G01X1630593Y-7744D02*
X1636085Y-13236D01*
G01X1626885Y-7744D02*
X1630593D01*
G01X1626883Y-7742D02*
X1626885Y-7744D01*
G01X1625305Y-7742D02*
X1626883D01*
G01X1625304Y-7743D02*
X1625305Y-7742D01*
G01X1624516Y-7743D02*
X1625304D01*
G01X1622059Y-10200D02*
X1624516Y-7743D01*
G01X1636113Y-11917D02*
X1657848D01*
G01X1630986Y-6790D02*
X1636113Y-11917D01*
G01X1624122Y-6790D02*
X1630986D01*
G01X1621864Y-9048D02*
X1624122Y-6790D01*
G01X1595006Y-9048D02*
X1621864D01*
G01X1591084Y-5126D02*
X1595006Y-9048D01*
G01X1589900Y-2269D02*
X1589899Y-2270D01*
G01X1592268Y-2269D02*
X1589900D01*
G01X1596191Y-6192D02*
X1592268Y-2269D01*
G01X1620679Y-6192D02*
X1596191D01*
G01X1622938Y-3933D02*
X1620679Y-6192D01*
G01X1625306Y-3933D02*
X1622938D01*
G01X1625307Y-3934D02*
X1625306Y-3933D01*
G01X1632171Y-3934D02*
X1625307D01*
G01X1637298Y-9061D02*
X1632171Y-3934D01*
G01X1656663Y-9061D02*
X1637298D01*
G01X1590431Y-6702D02*
X1588855Y-8278D01*
G01X1606650Y-15700D02*
X1605004Y-17346D01*
G01X1611900Y-15700D02*
X1606650D01*
G01X1614600Y-18400D02*
X1611900Y-15700D01*
G01X1658100Y-18400D02*
X1614600D01*
G01X1596586Y-5240D02*
X1590370Y976D01*
G01X1619084Y-5240D02*
X1596586D01*
G01X1622300Y-2024D02*
X1619084Y-5240D01*
G01X1635948Y-2024D02*
X1622300D01*
G01X1642033Y-8109D02*
X1635948Y-2024D01*
G01X1656268Y-8109D02*
X1642033D01*
G01X1636508Y-10965D02*
X1657453D01*
G01X1631381Y-5838D02*
X1636508Y-10965D01*
G01X1624517Y-5838D02*
X1631381D01*
G01X1624516Y-5837D02*
X1624517Y-5838D01*
G01X1623728Y-5837D02*
X1624516D01*
G01X1621469Y-8096D02*
X1623728Y-5837D01*
G01X1595401Y-8096D02*
X1621469D01*
G01X1591478Y-4173D02*
X1595401Y-8096D01*
G01X1590690Y-4173D02*
X1591478D01*
G01X1590689Y-4174D02*
X1590690Y-4173D01*
G01X1609358Y-19200D02*
X1607504Y-17346D01*
G01X1821600Y-19200D02*
X1609358D01*
G01X1637977Y9123D02*
X1653622D01*
G01X1635638Y11462D02*
X1637977Y9123D01*
G01X1635638Y22680D02*
Y11462D01*
G01X1632879Y25439D02*
X1635638Y22680D01*
G01X1603042Y25439D02*
X1632879D01*
G01X1600852Y27629D02*
X1603042Y25439D01*
G01X1600852Y37837D02*
Y27629D01*
G01X1598602Y-600D02*
X1594102Y3900D01*
G01X1603058Y-20400D02*
X1600004Y-17346D01*
G01X1822100Y-20400D02*
X1603058D01*
G01X1642428Y-7157D02*
X1655873D01*
G01X1636343Y-1072D02*
X1642428Y-7157D01*
G01X1605725Y-1072D02*
X1636343D01*
G01X1603669Y-3128D02*
X1605725Y-1072D01*
G01X1597554Y-3128D02*
X1603669D01*
G01X1592498Y1928D02*
X1597554Y-3128D01*
G01X1647450Y-15140D02*
X1658666D01*
G01X1647449Y-15141D02*
X1647450Y-15140D01*
G01X1640341Y-15141D02*
X1647449D01*
G01X1640340Y-15140D02*
X1640341Y-15141D01*
G01X1635295Y-15140D02*
X1640340D01*
G01X1629803Y-9648D02*
X1635295Y-15140D01*
G01X1625605Y-9648D02*
X1629803D01*
G01X1622953Y-12300D02*
X1625605Y-9648D01*
G01X1624911Y-8695D02*
X1622406Y-11200D01*
G01X1625699Y-8695D02*
X1624911D01*
G01X1625700Y-8694D02*
X1625699Y-8695D01*
G01X1626488Y-8694D02*
X1625700D01*
G01X1626490Y-8696D02*
X1626488Y-8694D01*
G01X1630198Y-8696D02*
X1626490D01*
G01X1635690Y-14188D02*
X1630198Y-8696D01*
G01X1640735Y-14188D02*
X1635690D01*
G01X1640736Y-14189D02*
X1640735Y-14188D01*
G01X1647054Y-14189D02*
X1640736D01*
G01X1647055Y-14188D02*
X1647054Y-14189D01*
G01X1658271Y-14188D02*
X1647055D01*
G01X1643053Y21623D02*
X1637482D01*
G01X1648983Y27553D02*
X1643053Y21623D01*
G01X1760685Y27553D02*
X1648983D01*
G01X1597949Y-2176D02*
X1592893Y2880D01*
G01X1602969Y-2176D02*
X1597949D01*
G01X1605025Y-120D02*
X1602969Y-2176D01*
G01X1636738Y-120D02*
X1605025D01*
G01X1642823Y-6205D02*
X1636738Y-120D01*
G01X1655478Y-6205D02*
X1642823D01*
G01X1647845Y-16092D02*
X1659061D01*
G01X1647844Y-16093D02*
X1647845Y-16092D01*
G01X1639946Y-16093D02*
X1647844D01*
G01X1639945Y-16092D02*
X1639946Y-16093D01*
G01X1634900Y-16092D02*
X1639945D01*
G01X1629408Y-10600D02*
X1634900Y-16092D01*
G01X1626000Y-10600D02*
X1629408D01*
G01X1619572Y-17028D02*
X1626000Y-10600D01*
G01X1614581Y-17028D02*
X1619572D01*
G01X1612253Y-14700D02*
X1614581Y-17028D01*
G01X1594600Y-14700D02*
X1612253D01*
G01X1593200Y-16100D02*
X1594600Y-14700D01*
G01X1598476Y82924D02*
X1596900Y84500D01*
G01X1603677Y82924D02*
X1598476D01*
G01X1606655Y79946D02*
X1603677Y82924D01*
G01X1610468Y79946D02*
X1606655D01*
G01X1618825Y71589D02*
X1610468Y79946D01*
G01X1624933Y71589D02*
X1618825D01*
G01X1626762Y69760D02*
X1624933Y71589D01*
G01X1627384Y69760D02*
X1626762D01*
G01X1627385Y69761D02*
X1627384Y69760D01*
G01X1651815Y69761D02*
X1627385D01*
G01X1613918Y92982D02*
X1608995Y97905D01*
G01X1629324Y92982D02*
X1613918D01*
G01X1630600Y91706D02*
X1629324Y92982D01*
G01X1659565Y91706D02*
X1630600D01*
G01X1596054Y95475D02*
X1592579Y92000D01*
G01X1599443Y93276D02*
Y94553D01*
G01X1602456Y90263D02*
X1599443Y93276D01*
G01X1608529Y90263D02*
X1602456D01*
G01X1612475Y86317D02*
X1608529Y90263D01*
G01X1620943Y86317D02*
X1612475D01*
G01X1624693Y82567D02*
X1620943Y86317D01*
G01X1626084Y82567D02*
X1624693D01*
G01X1629827Y78824D02*
X1626084Y82567D01*
G01X1646243Y78824D02*
X1629827D01*
G01X1649439Y82020D02*
X1646243Y78824D01*
G01X1660619Y82020D02*
X1649439D01*
G01X1602990Y93925D02*
X1604000D01*
G01X1596267Y100648D02*
X1602990Y93925D01*
G01X1593997Y77143D02*
X1593000Y78140D01*
G01X1593997Y75224D02*
Y77143D01*
G01X1595981Y73240D02*
X1593997Y75224D01*
G01X1597600Y73240D02*
X1595981D01*
G01X1598200Y72640D02*
X1597600Y73240D01*
G01X1598200Y64800D02*
Y72640D01*
G01X1603846Y59154D02*
X1598200Y64800D01*
G01X1620348Y59154D02*
X1603846D01*
G01X1620700Y58802D02*
X1620348Y59154D01*
G01X1620700Y57153D02*
Y58802D01*
G01X1620348Y56801D02*
X1620700Y57153D01*
G01X1608552Y56801D02*
X1620348D01*
G01X1608200Y56449D02*
X1608552Y56801D01*
G01X1608200Y54800D02*
Y56449D01*
G01X1608552Y54448D02*
X1608200Y54800D01*
G01X1652548Y54448D02*
X1608552D01*
G01X1613252Y52095D02*
X1652548D01*
G01X1612900Y51743D02*
X1613252Y52095D01*
G01X1612900Y50094D02*
Y51743D01*
G01X1613252Y49742D02*
X1612900Y50094D01*
G01X1654342Y49742D02*
X1613252D01*
G01X1629100Y57250D02*
X1654550D01*
G01X1622174Y64176D02*
X1629100Y57250D01*
G01X1622174Y64674D02*
Y64176D01*
G01X1623340Y65840D02*
X1622174Y64674D01*
G01X1623838Y65840D02*
X1623340D01*
G01X1630290Y59388D02*
X1623838Y65840D01*
G01X1630788Y59388D02*
X1630290D01*
G01X1631954Y60554D02*
X1630788Y59388D01*
G01X1631954Y61052D02*
Y60554D01*
G01X1625406Y67600D02*
X1631954Y61052D01*
G01X1618750Y67600D02*
X1625406D01*
G01X1618250Y68100D02*
X1618750Y67600D01*
G01X1610499Y68100D02*
X1618250D01*
G01X1608599Y70000D02*
X1610499Y68100D01*
G01X1608599Y70299D02*
Y70000D01*
G01X1610523Y72223D02*
X1608599Y70299D01*
G01X1610523Y73077D02*
Y72223D01*
G01X1607859Y75741D02*
X1610523Y73077D01*
G01X1607361Y75741D02*
X1607859D01*
G01X1605309Y73689D02*
X1607361Y75741D01*
G01X1604811Y73689D02*
X1605309D01*
G01X1603645Y74855D02*
X1604811Y73689D01*
G01X1603645Y75353D02*
Y74855D01*
G01X1605300Y77008D02*
X1603645Y75353D01*
G01X1605300Y77800D02*
Y77008D01*
G01X1601992Y81108D02*
X1605300Y77800D01*
G01X1596892Y81108D02*
X1601992D01*
G01X1595250Y82750D02*
X1596892Y81108D01*
G01X1597867Y90846D02*
X1595521Y88500D01*
G01X1597867Y93900D02*
Y90846D01*
G01X1596999Y93900D02*
X1597867D01*
G01X1594026Y90927D02*
X1596999Y93900D01*
G01X1648325Y75200D02*
X1673800D01*
G01X1646951Y76574D02*
X1648325Y75200D01*
G01X1628423Y76574D02*
X1646951D01*
G01X1625075Y79922D02*
X1628423Y76574D01*
G01X1625075Y80182D02*
Y79922D01*
G01X1644340Y83724D02*
X1659736D01*
G01X1642063Y86001D02*
X1644340Y83724D01*
G01X1640377Y86001D02*
X1642063D01*
G01X1640376Y86000D02*
X1640377Y86001D01*
G01X1630000Y86000D02*
X1640376D01*
G01X1625127Y90873D02*
X1630000Y86000D01*
G01X1613064Y90873D02*
X1625127D01*
G01X1613016Y90921D02*
X1613064Y90873D01*
G01X1613002Y90921D02*
X1613016D01*
G01X1612176Y91747D02*
X1613002Y90921D01*
G01X1612176Y91761D02*
Y91747D01*
G01X1607736Y96201D02*
X1612176Y91761D01*
G01X1597987Y78932D02*
Y79500D01*
G01X1601457Y75462D02*
X1597987Y78932D01*
G01X1601457Y74696D02*
Y75462D01*
G01X1599580Y72819D02*
X1601457Y74696D01*
G01X1599580Y72321D02*
Y72819D01*
G01X1600746Y71155D02*
X1599580Y72321D01*
G01X1601244Y71155D02*
X1600746D01*
G01X1603121Y73032D02*
X1601244Y71155D01*
G01X1603619Y73032D02*
X1603121D01*
G01X1604785Y71866D02*
X1603619Y73032D01*
G01X1604785Y71368D02*
Y71866D01*
G01X1602908Y69491D02*
X1604785Y71368D01*
G01X1602908Y68993D02*
Y69491D01*
G01X1604074Y67827D02*
X1602908Y68993D01*
G01X1604572Y67827D02*
X1604074D01*
G01X1606449Y69704D02*
X1604572Y67827D01*
G01X1606947Y69704D02*
X1606449D01*
G01X1609992Y66659D02*
X1606947Y69704D01*
G01X1617249Y66659D02*
X1609992D01*
G01X1618397Y65511D02*
X1617249Y66659D01*
G01X1618397Y65013D02*
Y65511D01*
G01X1615641Y62257D02*
X1618397Y65013D01*
G01X1615641Y61759D02*
Y62257D01*
G01X1616807Y60593D02*
X1615641Y61759D01*
G01X1617305Y60593D02*
X1616807D01*
G01X1620061Y63349D02*
X1617305Y60593D01*
G01X1620559Y63349D02*
X1620061D01*
G01X1623920Y59988D02*
X1620559Y63349D01*
G01X1623920Y59490D02*
Y59988D01*
G01X1622264Y57834D02*
X1623920Y59490D01*
G01X1622264Y57336D02*
Y57834D01*
G01X1623430Y56170D02*
X1622264Y57336D01*
G01X1623928Y56170D02*
X1623430D01*
G01X1625584Y57826D02*
X1623928Y56170D01*
G01X1626082Y57826D02*
X1625584D01*
G01X1628108Y55800D02*
X1626082Y57826D01*
G01X1657100Y55800D02*
X1628108D01*
G01X1596179Y79500D02*
X1597987D01*
G01X1594563Y81116D02*
X1596179Y79500D01*
G01X1643945Y82772D02*
X1660271D01*
G01X1641669Y85048D02*
X1643945Y82772D01*
G01X1629605Y85048D02*
X1641669D01*
G01X1625706Y88947D02*
X1629605Y85048D01*
G01X1613629Y88947D02*
X1625706D01*
G01X1611224Y91352D02*
X1613629Y88947D01*
G01X1611224Y91366D02*
Y91352D01*
G01X1607140Y95450D02*
X1611224Y91366D01*
G01X1603165Y84500D02*
X1602000D01*
G01X1606967Y80698D02*
X1603165Y84500D01*
G01X1610780Y80698D02*
X1606967D01*
G01X1619137Y72341D02*
X1610780Y80698D01*
G01X1625245Y72341D02*
X1619137D01*
G01X1627073Y70513D02*
X1625245Y72341D01*
G01X1652127Y70513D02*
X1627073D01*
G01X1613071Y45200D02*
X1652750D01*
G01X1594300Y63971D02*
X1613071Y45200D01*
G01X1594300Y73099D02*
Y63971D01*
G01X1593475Y73924D02*
X1594300Y73099D01*
G01X1591047Y73924D02*
X1593475D01*
G01X1590621Y74350D02*
X1591047Y73924D01*
G01X1631259Y92785D02*
X1660056D01*
G01X1629670Y94374D02*
X1631259Y92785D01*
G01X1619817Y94374D02*
X1629670D01*
G01X1617559Y96632D02*
X1619817Y94374D01*
G01X1635288Y93536D02*
X1632610Y96214D01*
G01X1659743Y93536D02*
X1635288D01*
G01X1612176Y93377D02*
X1608600Y96953D01*
G01X1612190Y93377D02*
X1612176D01*
G01X1613328Y92239D02*
X1612190Y93377D01*
G01X1613328Y92225D02*
Y92239D01*
G01X1613480Y92073D02*
X1613328Y92225D01*
G01X1613494Y92073D02*
X1613480D01*
G01X1613542Y92025D02*
X1613494Y92073D01*
G01X1628934Y92025D02*
X1613542D01*
G01X1630205Y90754D02*
X1628934Y92025D01*
G01X1659170Y90754D02*
X1630205D01*
G01X1612098Y48402D02*
X1599000Y61500D01*
G01X1657403Y48402D02*
X1612098D01*
G01X1650800Y79500D02*
X1649900Y78600D01*
G01X1600873Y93539D02*
Y94940D01*
G01X1602950Y91462D02*
X1600873Y93539D01*
G01X1608960Y91462D02*
X1602950D01*
G01X1612904Y87518D02*
X1608960Y91462D01*
G01X1625253Y87518D02*
X1612904D01*
G01X1631469Y81302D02*
X1625253Y87518D01*
G01X1642598Y81302D02*
X1631469D01*
G01X1643500Y80400D02*
X1642598Y81302D01*
G01X1602566Y86163D02*
X1589174D01*
G01X1607278Y81451D02*
X1602566Y86163D01*
G01X1611027Y81451D02*
X1607278D01*
G01X1611028Y81450D02*
X1611027Y81451D01*
G01X1611092Y81450D02*
X1611028D01*
G01X1619449Y73093D02*
X1611092Y81450D01*
G01X1625557Y73093D02*
X1619449D01*
G01X1627385Y71265D02*
X1625557Y73093D01*
G01X1651815Y71265D02*
X1627385D01*
G01X1596116Y146916D02*
X1592498D01*
G01X1599436Y150236D02*
X1596116Y146916D01*
G01X1600760Y150236D02*
X1599436D01*
G01X1602847Y152323D02*
X1600760Y150236D01*
G01X1604779Y152323D02*
X1602847D01*
G01X1607715Y149387D02*
X1604779Y152323D01*
G01X1608057Y149387D02*
X1607715D01*
G01X1608058Y149386D02*
X1608057Y149387D01*
G01X1608828Y149386D02*
X1608058D01*
G01X1609552Y148662D02*
X1608828Y149386D01*
G01X1617503Y148662D02*
X1609552D01*
G01X1618625Y149784D02*
X1617503Y148662D01*
G01X1618625Y153912D02*
Y149784D01*
G01X1621515Y156802D02*
X1618625Y153912D01*
G01X1623200Y149884D02*
Y153100D01*
G01X1621715Y148399D02*
X1623200Y149884D01*
G01X1621715Y146404D02*
Y148399D01*
G01X1620783Y145472D02*
X1621715Y146404D01*
G01X1619355Y145472D02*
X1620783D01*
G01X1618375Y144492D02*
X1619355Y145472D01*
G01X1618375Y143268D02*
Y144492D01*
G01X1617512Y142405D02*
X1618375Y143268D01*
G01X1617500Y142405D02*
X1617512D01*
G01X1617403Y142308D02*
X1617500Y142405D01*
G01X1610033Y142308D02*
X1617403D01*
G01X1609170Y143171D02*
X1610033Y142308D01*
G01X1609170Y144334D02*
Y143171D01*
G01X1608239Y145265D02*
X1609170Y144334D01*
G01X1608100Y145265D02*
X1608239D01*
G01X1608053Y145312D02*
X1608100Y145265D01*
G01X1606829Y145312D02*
X1608053D01*
G01X1606782Y145265D02*
X1606829Y145312D01*
G01X1594764Y145265D02*
X1606782D01*
G01X1645914Y99022D02*
X1653489D01*
G01X1642724Y102212D02*
X1645914Y99022D01*
G01X1613358Y102212D02*
X1642724D01*
G01X1610108Y105462D02*
X1613358Y102212D01*
G01X1608021Y105462D02*
X1610108D01*
G01X1607441Y106042D02*
X1608021Y105462D01*
G01X1593000Y113758D02*
X1590542Y111300D01*
G01X1595584Y113758D02*
X1593000D01*
G01X1596122Y113220D02*
X1595584Y113758D01*
G01X1601191Y113220D02*
X1596122D01*
G01X1605898Y108513D02*
X1601191Y113220D01*
G01X1607257Y108513D02*
X1605898D01*
G01X1609557Y106213D02*
X1607257Y108513D01*
G01X1610421Y106213D02*
X1609557D01*
G01X1612818Y103816D02*
X1610421Y106213D01*
G01X1647851Y103816D02*
X1612818D01*
G01X1650902Y100765D02*
X1647851Y103816D01*
G01X1595343Y122518D02*
X1593050Y120225D01*
G01X1596383Y122518D02*
X1595343D01*
G01X1596988Y123123D02*
X1596383Y122518D01*
G01X1599927Y123123D02*
X1596988D01*
G01X1602835Y120215D02*
X1599927Y123123D01*
G01X1647265Y120215D02*
X1602835D01*
G01X1650104Y117376D02*
X1647265Y120215D01*
G01X1652319Y117376D02*
X1650104D01*
G01X1596603Y114087D02*
X1595239Y115451D01*
G01X1601482Y114087D02*
X1596603D01*
G01X1606305Y109264D02*
X1601482Y114087D01*
G01X1607569Y109264D02*
X1606305D01*
G01X1609869Y106964D02*
X1607569Y109264D01*
G01X1610733Y106964D02*
X1609869D01*
G01X1613130Y104567D02*
X1610733Y106964D01*
G01X1643937Y104567D02*
X1613130D01*
G01X1646810Y107440D02*
X1643937Y104567D01*
G01X1646810Y109900D02*
Y107440D01*
G01X1647576Y110666D02*
X1646810Y109900D01*
G01X1652302Y110666D02*
X1647576D01*
G01X1590537Y104899D02*
X1590536Y104900D01*
G01X1596832Y104899D02*
X1590537D01*
G01X1600966Y100765D02*
X1596832Y104899D01*
G01X1602104Y100765D02*
X1600966D01*
G01X1602105Y100764D02*
X1602104Y100765D01*
G01X1603226Y100764D02*
X1602105D01*
G01X1606085Y97905D02*
X1603226Y100764D01*
G01X1608995Y97905D02*
X1606085D01*
G01X1598521Y95475D02*
X1596054D01*
G01X1599443Y94553D02*
X1598521Y95475D01*
G01X1591518Y100648D02*
X1596267D01*
G01X1637519Y94925D02*
X1656197D01*
G01X1632869Y99575D02*
X1637519Y94925D01*
G01X1612315Y99575D02*
X1632869D01*
G01X1609395Y102495D02*
X1612315Y99575D01*
G01X1606775Y102495D02*
X1609395D01*
G01X1601632Y107638D02*
X1606775Y102495D01*
G01X1595966Y107638D02*
X1601632D01*
G01X1594452Y109152D02*
X1595966Y107638D01*
G01X1594452Y111377D02*
Y109152D01*
G01X1600310Y155700D02*
X1605233Y160623D01*
G01X1596131Y155700D02*
X1600310D01*
G01X1650007Y113871D02*
X1655241D01*
G01X1648387Y115491D02*
X1650007Y113871D01*
G01X1597616Y114901D02*
X1596315Y116202D01*
G01X1601731Y114901D02*
X1597616D01*
G01X1606617Y110015D02*
X1601731Y114901D01*
G01X1607881Y110015D02*
X1606617D01*
G01X1610181Y107715D02*
X1607881Y110015D01*
G01X1616633Y107715D02*
X1610181D01*
G01X1616678Y107670D02*
X1616633Y107715D01*
G01X1641529Y107670D02*
X1616678D01*
G01X1645237Y111378D02*
X1641529Y107670D01*
G01X1645237Y112341D02*
Y111378D01*
G01X1600622Y154948D02*
X1596472D01*
G01X1603590Y157916D02*
X1600622Y154948D01*
G01X1648588Y122544D02*
X1650817Y120315D01*
G01X1637327Y122544D02*
X1648588D01*
G01X1631428Y128443D02*
X1637327Y122544D01*
G01X1626503Y128443D02*
X1631428D01*
G01X1625382Y129564D02*
X1626503Y128443D01*
G01X1613129Y129564D02*
X1625382D01*
G01X1612208Y128643D02*
X1613129Y129564D01*
G01X1612208Y126556D02*
Y128643D01*
G01X1610591Y124939D02*
X1612208Y126556D01*
G01X1615115Y126415D02*
X1613690Y124990D01*
G01X1628460Y126415D02*
X1615115D01*
G01X1633082Y121793D02*
X1628460Y126415D01*
G01X1648276Y121793D02*
X1633082D01*
G01X1650505Y119564D02*
X1648276Y121793D01*
G01X1650336Y107991D02*
X1651536Y109191D01*
G01X1650336Y107496D02*
Y107991D01*
G01X1651332Y106500D02*
X1650336Y107496D01*
G01X1650284Y145736D02*
X1650621Y145399D01*
G01X1633835Y145736D02*
X1650284D01*
G01X1627492Y139393D02*
X1633835Y145736D01*
G01X1627492Y135174D02*
Y139393D01*
G01X1624295Y131977D02*
X1627492Y135174D01*
G01X1609682Y131977D02*
X1624295D01*
G01X1607441Y134218D02*
X1609682Y131977D01*
G01X1607441Y134389D02*
Y134218D01*
G01X1645237Y114587D02*
Y115491D01*
G01X1643730Y113080D02*
X1645237Y114587D01*
G01X1643730Y111380D02*
Y113080D01*
G01X1643140Y110790D02*
X1643730Y111380D01*
G01X1617569Y110790D02*
X1643140D01*
G01X1617545Y110766D02*
X1617569Y110790D01*
G01X1606930Y110766D02*
X1617545D01*
G01X1599644Y118052D02*
X1606930Y110766D01*
G01X1595106Y118052D02*
X1599644D01*
G01X1595026Y117972D02*
X1595106Y118052D01*
G01X1607097Y96201D02*
X1607736D01*
G01X1607096Y96202D02*
X1607097Y96201D01*
G01X1605014Y96202D02*
X1607096D01*
G01X1604540Y96676D02*
X1605014Y96202D01*
G01X1602465Y96676D02*
X1604540D01*
G01X1596341Y102800D02*
X1602465Y96676D01*
G01X1604702Y95450D02*
X1607140D01*
G01X1604228Y95924D02*
X1604702Y95450D01*
G01X1602055Y95924D02*
X1604228D01*
G01X1596579Y101400D02*
X1602055Y95924D01*
G01X1591129Y101400D02*
X1596579D01*
G01X1591974Y106134D02*
X1589744Y108364D01*
G01X1601010Y106134D02*
X1591974D01*
G01X1606190Y100954D02*
X1601010Y106134D01*
G01X1608808Y100954D02*
X1606190D01*
G01X1611897Y97865D02*
X1608808Y100954D01*
G01X1611898Y97865D02*
X1611897D01*
G01X1612077Y97686D02*
X1611898Y97865D01*
G01X1617717Y97686D02*
X1612077D01*
G01X1620154Y95249D02*
X1617717Y97686D01*
G01X1631257Y95249D02*
X1620154D01*
G01X1632006Y94500D02*
X1631257Y95249D01*
G01X1644957Y97454D02*
X1652361D01*
G01X1641317Y101094D02*
X1644957Y97454D01*
G01X1613016Y101094D02*
X1641317D01*
G01X1609543Y104567D02*
X1613016Y101094D01*
G01X1606829Y104567D02*
X1609543D01*
G01X1605251Y106145D02*
X1606829Y104567D01*
G01X1605251Y108096D02*
Y106145D01*
G01X1601015Y112332D02*
X1605251Y108096D01*
G01X1595828Y112332D02*
X1601015D01*
G01X1595153Y113007D02*
X1595828Y112332D01*
G01X1593929Y113007D02*
X1595153D01*
G01X1593928Y113006D02*
X1593929Y113007D01*
G01X1593601Y113006D02*
X1593928D01*
G01X1590995Y110400D02*
X1593601Y113006D01*
G01X1642670Y154910D02*
X1652365D01*
G01X1642050Y155530D02*
X1642670Y154910D01*
G01X1623019Y155530D02*
X1642050D01*
G01X1621725Y154236D02*
X1623019Y155530D01*
G01X1621725Y149738D02*
Y154236D01*
G01X1620449Y148462D02*
X1621725Y149738D01*
G01X1619229Y148462D02*
X1620449D01*
G01X1618366Y147599D02*
X1619229Y148462D01*
G01X1618366Y146375D02*
Y147599D01*
G01X1617503Y145512D02*
X1618366Y146375D01*
G01X1609979Y145512D02*
X1617503D01*
G01X1608949Y146542D02*
X1609979Y145512D01*
G01X1608949Y147486D02*
Y146542D01*
G01X1607973Y148462D02*
X1608949Y147486D01*
G01X1602169Y148462D02*
X1607973D01*
G01X1599872Y146165D02*
X1602169Y148462D01*
G01X1593216Y146165D02*
X1599872D01*
G01X1591143Y144092D02*
X1593216Y146165D01*
G01X1625313Y151770D02*
X1651081D01*
G01X1624703Y151160D02*
X1625313Y151770D01*
G01X1624703Y145958D02*
Y151160D01*
G01X1624100Y145355D02*
X1624703Y145958D01*
G01X1622622Y145355D02*
X1624100D01*
G01X1618368Y141101D02*
X1622622Y145355D01*
G01X1618368Y140171D02*
Y141101D01*
G01X1617410Y139213D02*
X1618368Y140171D01*
G01X1609980Y139213D02*
X1617410D01*
G01X1607441Y141752D02*
X1609980Y139213D01*
G01X1607441Y143837D02*
Y141752D01*
G01X1649386Y108192D02*
X1648387Y109191D01*
G01X1649386Y107102D02*
Y108192D01*
G01X1650938Y105550D02*
X1649386Y107102D01*
G01X1600511Y108390D02*
X1598190Y110711D01*
G01X1601943Y108390D02*
X1600511D01*
G01X1607086Y103247D02*
X1601943Y108390D01*
G01X1609707Y103247D02*
X1607086D01*
G01X1612627Y100327D02*
X1609707Y103247D01*
G01X1614179Y100327D02*
X1612627D01*
G01X1614180Y100326D02*
X1614179Y100327D01*
G01X1631033Y100326D02*
X1614180D01*
G01X1631035Y100328D02*
X1631033Y100326D01*
G01X1632965Y100328D02*
X1631035D01*
G01X1632967Y100326D02*
X1632965Y100328D01*
G01X1641022Y100326D02*
X1632967D01*
G01X1644900Y96448D02*
X1641022Y100326D01*
G01X1653043Y96448D02*
X1644900D01*
G01X1649620Y148520D02*
X1652900Y151800D01*
G01X1642370Y148520D02*
X1649620D01*
G01X1639900Y150990D02*
X1642370Y148520D01*
G01X1632843Y150990D02*
X1639900D01*
G01X1625334Y143481D02*
X1632843Y150990D01*
G01X1625334Y139065D02*
Y143481D01*
G01X1622332Y136063D02*
X1625334Y139065D01*
G01X1609980Y136063D02*
X1622332D01*
G01X1609116Y136927D02*
X1609980Y136063D01*
G01X1609116Y137949D02*
Y136927D01*
G01X1607872Y139193D02*
X1609116Y137949D01*
G01X1603504Y139193D02*
X1607872D01*
G01X1601456Y137145D02*
X1603504Y139193D01*
G01X1594155Y137145D02*
X1601456D01*
G01X1593500Y137800D02*
X1594155Y137145D01*
G01X1641280Y123326D02*
X1652010D01*
G01X1640240Y124366D02*
X1641280Y123326D01*
G01X1640240Y127560D02*
Y124366D01*
G01X1638080Y129720D02*
X1640240Y127560D01*
G01X1626289Y129720D02*
X1638080D01*
G01X1625694Y130315D02*
X1626289Y129720D01*
G01X1612817Y130315D02*
X1625694D01*
G01X1612066Y129564D02*
X1612817Y130315D01*
G01X1606222Y129564D02*
X1612066D01*
G01X1602411Y133375D02*
X1606222Y129564D01*
G01X1596167Y133375D02*
X1602411D01*
G01X1595472Y132680D02*
X1596167Y133375D01*
G01X1608370Y150137D02*
X1610591D01*
G01X1604896Y153611D02*
X1608370Y150137D01*
G01X1599682Y153611D02*
X1604896D01*
G01X1596371Y150300D02*
X1599682Y153611D01*
G01X1592900Y150300D02*
X1596371D01*
G01X1611968Y96632D02*
X1617559D01*
G01X1609200Y99400D02*
X1611968Y96632D01*
G01X1608000Y99400D02*
X1609200D01*
G01X1593119Y106886D02*
X1590489Y109516D01*
G01X1601321Y106886D02*
X1593119D01*
G01X1606472Y101735D02*
X1601321Y106886D01*
G01X1609091Y101735D02*
X1606472D01*
G01X1612208Y98618D02*
X1609091Y101735D01*
G01X1619132Y98618D02*
X1612208D01*
G01X1621536Y96214D02*
X1619132Y98618D01*
G01X1632610Y96214D02*
X1621536D01*
G01X1599708Y126612D02*
X1595697Y130623D01*
G01X1607854Y126612D02*
X1599708D01*
G01X1608916Y125550D02*
X1607854Y126612D01*
G01X1608916Y124528D02*
Y125550D01*
G01X1610179Y123265D02*
X1608916Y124528D01*
G01X1629732Y123265D02*
X1610179D01*
G01X1632031Y120966D02*
X1629732Y123265D01*
G01X1648040Y120966D02*
X1632031D01*
G01X1650879Y118127D02*
X1648040Y120966D01*
G01X1641050Y112340D02*
X1641770D01*
G01X1636424Y116966D02*
X1641050Y112340D01*
G01X1622588Y116966D02*
X1636424D01*
G01X1619596Y113974D02*
X1622588Y116966D01*
G01X1605736Y113974D02*
X1619596D01*
G01X1600907Y118803D02*
X1605736Y113974D01*
G01X1594794Y118803D02*
X1600907D01*
G01X1594714Y118723D02*
X1594794Y118803D01*
G01X1592541Y136059D02*
X1590800Y137800D01*
G01X1594715Y136059D02*
X1592541D01*
G01X1594719Y136063D02*
X1594715Y136059D01*
G01X1607853Y136063D02*
X1594719D01*
G01X1609116Y134800D02*
X1607853Y136063D01*
G01X1609116Y133778D02*
Y134800D01*
G01X1609981Y132913D02*
X1609116Y133778D01*
G01X1623801Y132913D02*
X1609981D01*
G01X1626741Y135853D02*
X1623801Y132913D01*
G01X1626741Y143825D02*
Y135853D01*
G01X1630116Y147200D02*
X1626741Y143825D01*
G01X1649650Y147200D02*
X1630116D01*
G01X1651027Y148577D02*
X1649650Y147200D01*
G01X1590225Y104147D02*
X1590224Y104148D01*
G01X1596520Y104147D02*
X1590225D01*
G01X1600654Y100013D02*
X1596520Y104147D01*
G01X1600655Y100013D02*
X1600654D01*
G01X1600855Y99813D02*
X1600655Y100013D01*
G01X1602830Y99813D02*
X1600855D01*
G01X1605689Y96954D02*
X1602830Y99813D01*
G01X1607408Y96954D02*
X1605689D01*
G01X1607409Y96953D02*
X1607408Y96954D01*
G01X1608600Y96953D02*
X1607409D01*
G01X1595700Y96400D02*
X1595164Y95864D01*
G01X1599413Y96400D02*
X1595700D01*
G01X1600873Y94940D02*
X1599413Y96400D01*
G01X1597300Y122372D02*
X1594402Y119474D01*
G01X1599223Y122372D02*
X1597300D01*
G01X1604430Y117165D02*
X1599223Y122372D01*
G01X1612266Y117165D02*
X1604430D01*
G01X1613741Y118640D02*
X1612266Y117165D01*
G01X1646512Y156802D02*
X1621515D01*
G01X1647820Y158110D02*
X1646512Y156802D01*
G01X1650061Y158110D02*
X1647820D01*
G01X1651536Y159585D02*
X1650061Y158110D01*
G01X1643676Y161174D02*
X1642087Y159585D01*
G01X1645762Y161174D02*
X1643676D01*
G01X1646627Y162039D02*
X1645762Y161174D01*
G01X1646627Y163061D02*
Y162039D01*
G01X1647776Y164210D02*
X1646627Y163061D01*
G01X1649136Y164210D02*
X1647776D01*
G01X1649997Y165071D02*
X1649136Y164210D01*
G01X1649997Y166691D02*
Y165071D01*
G01X1650895Y167589D02*
X1649997Y166691D01*
G01X1592804Y156500D02*
X1592038D01*
G01X1595850Y159546D02*
X1592804Y156500D01*
G01X1601051Y159546D02*
X1595850D01*
G01X1608865Y167360D02*
X1601051Y159546D01*
G01X1618566Y167360D02*
X1608865D01*
G01X1620041Y165885D02*
X1618566Y167360D01*
G01X1609015Y173389D02*
X1609222D01*
G01X1600016Y164390D02*
X1609015Y173389D01*
G01X1594539Y164390D02*
X1600016D01*
G01X1592453Y166476D02*
X1594539Y164390D01*
G01X1621517Y167445D02*
X1620006Y168956D01*
G01X1621517Y165273D02*
Y167445D01*
G01X1620653Y164409D02*
X1621517Y165273D01*
G01X1620651Y164409D02*
X1620653D01*
G01X1620561Y164319D02*
X1620651Y164409D01*
G01X1606939Y164319D02*
X1620561D01*
G01X1605233Y162613D02*
X1606939Y164319D01*
G01X1605233Y160623D02*
Y162613D01*
G01X1607609Y170919D02*
X1599874Y163184D01*
G01X1616218Y170919D02*
X1607609D01*
G01X1620762Y175463D02*
X1616218Y170919D01*
G01X1647730Y175463D02*
X1620762D01*
G01X1647731Y175464D02*
X1647730Y175463D01*
G01X1648353Y175464D02*
X1647731D01*
G01X1648354Y175463D02*
X1648353Y175464D01*
G01X1648697Y175463D02*
X1648354D01*
G01X1649446Y174714D02*
X1648697Y175463D01*
G01X1653097Y174714D02*
X1649446D01*
G01X1600479Y175021D02*
X1597642Y172184D01*
G01X1602219Y175021D02*
X1600479D01*
G01X1606262Y179064D02*
X1602219Y175021D01*
G01X1606262Y181499D02*
Y179064D01*
G01X1607808Y183045D02*
X1606262Y181499D01*
G01X1613854Y183045D02*
X1607808D01*
G01X1616795Y180104D02*
X1613854Y183045D01*
G01X1624884Y180104D02*
X1616795D01*
G01X1627423Y177565D02*
X1624884Y180104D01*
G01X1648721Y177565D02*
X1627423D01*
G01X1650070Y176216D02*
X1648721Y177565D01*
G01X1653721Y176216D02*
X1650070D01*
G01X1597236Y172184D02*
X1597642D01*
G01X1595761Y173659D02*
X1597236Y172184D01*
G01X1595655Y173659D02*
X1595761D01*
G01X1595654Y173660D02*
X1595655Y173659D01*
G01X1594430Y173660D02*
X1595654D01*
G01X1594429Y173659D02*
X1594430Y173660D01*
G01X1646182Y157916D02*
X1603590D01*
G01X1646911Y158645D02*
X1646182Y157916D01*
G01X1646911Y160197D02*
Y158645D01*
G01X1647775Y161061D02*
X1646911Y160197D01*
G01X1647777Y161061D02*
X1647775D01*
G01X1647878Y161162D02*
X1647777Y161061D01*
G01X1649117Y161162D02*
X1647878D01*
G01X1650690Y162735D02*
X1649117Y161162D01*
G01X1649134Y173963D02*
X1652785D01*
G01X1648385Y174712D02*
X1649134Y173963D01*
G01X1621075Y174712D02*
X1648385D01*
G01X1616334Y169971D02*
X1621075Y174712D01*
G01X1608001Y169971D02*
X1616334D01*
G01X1600462Y162432D02*
X1608001Y169971D01*
G01X1610401Y177800D02*
X1614000D01*
G01X1602300Y169699D02*
X1610401Y177800D01*
G01X1599580Y169699D02*
X1602300D01*
G01X1599567Y169686D02*
X1599580Y169699D01*
G01X1599566Y169686D02*
X1599567D01*
G01X1598860Y168980D02*
X1599566Y169686D01*
G01X1650382Y176967D02*
X1654033D01*
G01X1649032Y178317D02*
X1650382Y176967D01*
G01X1627735Y178317D02*
X1649032D01*
G01X1622719Y183333D02*
X1627735Y178317D01*
G01X1616207Y183333D02*
X1622719D01*
G01X1616206Y183332D02*
X1616207Y183333D01*
G01X1614900Y183332D02*
X1616206D01*
G01X1614899Y183333D02*
X1614900Y183332D01*
G01X1614669Y183333D02*
X1614899D01*
G01X1613053Y184949D02*
X1614669Y183333D01*
G01X1612300Y175100D02*
X1613650Y173750D01*
G01X1608801Y175100D02*
X1612300D01*
G01X1602654Y168953D02*
X1608801Y175100D01*
G01X1602617Y168953D02*
X1602654D01*
G01X1602612Y168948D02*
X1602617Y168953D01*
G01X1599892Y168948D02*
X1602612D01*
G01X1599879Y168935D02*
X1599892Y168948D01*
G01X1599878Y168935D02*
X1599879D01*
G01X1599142Y168199D02*
X1599878Y168935D01*
G01X1649130Y159585D02*
X1650744Y161199D01*
G01X1648387Y159585D02*
X1649130D01*
G01X1600073Y182821D02*
X1602185Y180709D01*
G01X1593398Y182821D02*
X1600073D01*
G01X1592710Y182133D02*
X1593398Y182821D01*
G01X1598950Y180300D02*
X1597153Y178503D01*
G01X1591800Y164900D02*
X1591750Y164850D01*
G01X1593318Y183997D02*
X1592421Y183100D01*
G01X1602197Y183997D02*
X1593318D01*
G01X1603300Y185100D02*
X1602197Y183997D01*
G01X1608313Y169219D02*
X1600344Y161250D01*
G01X1616818Y169219D02*
X1608313D01*
G01X1618832Y171233D02*
X1616818Y169219D01*
G01X1628944Y171233D02*
X1618832D01*
G01X1629043Y171134D02*
X1628944Y171233D01*
G01X1648920Y171134D02*
X1629043D01*
G01X1649580Y171794D02*
X1648920Y171134D01*
G01X1661415Y171794D02*
X1649580D01*
G01X1629490Y159585D02*
X1629489D01*
G01X1631165Y161260D02*
X1629490Y159585D01*
G01X1642698Y161260D02*
X1631165D01*
G01X1643676Y162238D02*
X1642698Y161260D01*
G01X1643676Y163260D02*
Y162238D01*
G01X1644825Y164409D02*
X1643676Y163260D01*
G01X1645848Y164409D02*
X1644825D01*
G01X1646712Y165273D02*
X1645848Y164409D01*
G01X1646712Y166297D02*
Y165273D01*
G01X1647974Y167559D02*
X1646712Y166297D01*
G01X1649708Y167559D02*
X1647974D01*
G01X1650869Y168720D02*
X1649708Y167559D01*
G01X1593627Y169936D02*
X1593225Y170338D01*
G01X1598753Y169936D02*
X1593627D01*
G01X1599254Y170437D02*
X1598753Y169936D01*
G01X1599255Y170437D02*
X1599254D01*
G01X1599268Y170450D02*
X1599255Y170437D01*
G01X1601988Y170450D02*
X1599268D01*
G01X1608731Y177193D02*
X1601988Y170450D01*
G01X1608731Y180819D02*
Y177193D01*
G01X1649934Y168881D02*
X1650559Y169506D01*
G01X1638681Y168881D02*
X1649934D01*
G01X1637300Y167500D02*
X1638681Y168881D01*
G01X1637300Y164247D02*
Y167500D01*
G01X1635788Y162735D02*
X1637300Y164247D01*
G01X1649758Y175465D02*
X1653409D01*
G01X1648410Y176813D02*
X1649758Y175465D01*
G01X1627111Y176813D02*
X1648410D01*
G01X1624622Y179302D02*
X1627111Y176813D01*
G01X1615234Y179302D02*
X1624622D01*
G01X1612242Y182294D02*
X1615234Y179302D01*
G01X1608120Y182294D02*
X1612242D01*
G01X1607237Y181411D02*
X1608120Y182294D01*
G01X1607237Y178976D02*
Y181411D01*
G01X1602275Y174014D02*
X1607237Y178976D01*
G01X1600884Y174014D02*
X1602275D01*
G01X1599667Y172797D02*
X1600884Y174014D01*
G01X1599667Y172123D02*
Y172797D01*
G01X1598253Y170709D02*
X1599667Y172123D01*
G01X1596517Y170709D02*
X1598253D01*
G01X1595042Y172184D02*
X1596517Y170709D01*
G01X1650233Y170257D02*
X1660826D01*
G01X1649608Y169632D02*
X1650233Y170257D01*
G01X1635530Y169632D02*
X1649608D01*
G01X1631200Y165302D02*
X1635530Y169632D01*
G01X1631200Y162360D02*
Y165302D01*
G01X1630965Y162125D02*
X1631200Y162360D01*
G01X1630965Y162123D02*
Y162125D01*
G01X1630101Y161259D02*
X1630965Y162123D01*
G01X1630099Y161259D02*
X1630101D01*
G01X1629975Y161135D02*
X1630099Y161259D01*
G01X1612141Y161135D02*
X1629975D01*
G01X1610591Y159585D02*
X1612141Y161135D01*
G01X1594128Y181875D02*
X1592896Y180643D01*
G01X1599603Y181875D02*
X1594128D01*
G01X1600525Y180953D02*
X1599603Y181875D01*
G01X1600525Y180143D02*
Y180953D01*
G01X1600610Y180058D02*
X1600525Y180143D01*
G01X1600610Y180056D02*
Y180058D01*
G01X1601532Y179134D02*
X1600610Y180056D01*
G01X1602838Y179134D02*
X1601532D01*
G01X1603760Y180056D02*
X1602838Y179134D01*
G01X1603760Y180061D02*
Y180056D01*
G01X1603921Y180222D02*
X1603760Y180061D01*
G01X1603921Y182642D02*
Y180222D01*
G01X1604950Y183671D02*
X1603921Y182642D01*
G01X1604950Y186587D02*
Y183671D01*
G01X1607212Y188849D02*
X1604950Y186587D01*
G01X1624851Y188849D02*
X1607212D01*
G01X1626521Y187179D02*
X1624851Y188849D01*
G01X1626521Y187178D02*
Y187179D01*
G01X1632592Y181107D02*
X1626521Y187178D01*
G01X1640925Y181107D02*
X1632592D01*
G01X1643234Y183416D02*
X1640925Y181107D01*
G01X1646279Y183416D02*
X1643234D01*
G01X1646863Y184000D02*
X1646279Y183416D01*
G01X1654526Y184000D02*
X1646863D01*
G01X1600739Y160298D02*
X1588786D01*
G01X1608708Y168267D02*
X1600739Y160298D01*
G01X1617067Y168267D02*
X1608708D01*
G01X1619266Y170466D02*
X1617067Y168267D01*
G01X1628648Y170466D02*
X1619266D01*
G01X1628731Y170383D02*
X1628648Y170466D01*
G01X1649282Y170383D02*
X1628731D01*
G01X1649942Y171043D02*
X1649282Y170383D01*
G01X1661103Y171043D02*
X1649942D01*
G01X1604672Y179750D02*
X1602649Y177727D01*
G01X1604672Y182330D02*
Y179750D01*
G01X1605701Y183359D02*
X1604672Y182330D01*
G01X1605701Y183362D02*
Y183359D01*
G01X1605730Y183391D02*
X1605701Y183362D01*
G01X1605730Y186303D02*
Y183391D01*
G01X1607524Y188097D02*
X1605730Y186303D01*
G01X1624539Y188097D02*
X1607524D01*
G01X1625769Y186867D02*
X1624539Y188097D01*
G01X1625769Y186866D02*
Y186867D01*
G01X1626520Y186115D02*
X1625769Y186866D01*
G01X1626521Y186115D02*
X1626520D01*
G01X1632797Y179839D02*
X1626521Y186115D01*
G01X1648420Y179839D02*
X1632797D01*
G01X1649929Y181348D02*
X1648420Y179839D01*
G01X1649931Y181348D02*
X1649929D01*
G01X1650391Y181808D02*
X1649931Y181348D01*
G01X1652392Y181808D02*
X1650391D01*
G01X1605422Y179287D02*
X1602283Y176148D01*
G01X1605422Y179597D02*
Y179287D01*
G01X1605423Y179598D02*
X1605422Y179597D01*
G01X1605423Y182018D02*
Y179598D01*
G01X1606481Y183076D02*
X1605423Y182018D01*
G01X1606481Y185424D02*
Y183076D01*
G01X1608002Y186945D02*
X1606481Y185424D01*
G01X1622592Y186945D02*
X1608002D01*
G01X1623824Y185713D02*
X1622592Y186945D01*
G01X1623824Y184407D02*
Y185713D01*
G01X1623823Y184406D02*
X1623824Y184407D01*
G01X1623823Y183677D02*
Y184406D01*
G01X1628412Y179088D02*
X1623823Y183677D01*
G01X1648732Y179088D02*
X1628412D01*
G01X1650241Y180597D02*
X1648732Y179088D01*
G01X1651500Y180597D02*
X1650241D01*
G01X1601009Y272145D02*
X1599538Y270674D01*
G01X1604609Y272145D02*
X1601009D01*
G01X1608200Y268554D02*
X1604609Y272145D01*
G01X1630262Y268554D02*
X1608200D01*
G01X1630265Y268551D02*
X1630262Y268554D01*
G01X1630613Y268551D02*
X1630265D01*
G01X1632572Y266592D02*
X1630613Y268551D01*
G01X1632572Y261592D02*
Y266592D01*
G01X1635864Y258300D02*
X1632572Y261592D01*
G01X1641779Y258300D02*
X1635864D01*
G01X1658219Y241860D02*
X1641779Y258300D01*
G01X1630284Y277557D02*
X1622309Y285532D01*
G01X1631046Y277557D02*
X1630284D01*
G01X1631047Y277558D02*
X1631046Y277557D01*
G01X1632625Y277558D02*
X1631047D01*
G01X1632628Y277555D02*
X1632625Y277558D01*
G01X1632815Y277555D02*
X1632628D01*
G01X1635555Y274815D02*
X1632815Y277555D01*
G01X1636684Y274815D02*
X1635555D01*
G01X1629183Y274900D02*
X1622583Y281500D01*
G01X1630740Y274900D02*
X1629183D01*
G01X1630741Y274901D02*
X1630740Y274900D01*
G01X1631363Y274901D02*
X1630741D01*
G01X1631364Y274900D02*
X1631363Y274901D01*
G01X1631525Y274900D02*
X1631364D01*
G01X1631526Y274899D02*
X1631525Y274900D01*
G01X1631713Y274899D02*
X1631526D01*
G01X1635712Y270900D02*
X1631713Y274899D01*
G01X1636914Y270900D02*
X1635712D01*
G01X1635370Y260922D02*
X1637281D01*
G01X1634076Y262216D02*
X1635370Y260922D01*
G01X1634076Y267216D02*
Y262216D01*
G01X1631236Y270056D02*
X1634076Y267216D01*
G01X1630888Y270056D02*
X1631236D01*
G01X1630886Y270058D02*
X1630888Y270056D01*
G01X1608824Y270058D02*
X1630886D01*
G01X1605218Y273664D02*
X1608824Y270058D01*
G01X1599975Y273664D02*
X1605218D01*
G01X1598629Y272318D02*
X1599975Y273664D01*
G01X1646363Y252652D02*
X1657907Y241108D01*
G01X1636412Y252652D02*
X1646363D01*
G01X1631068Y257996D02*
X1636412Y252652D01*
G01X1631068Y265968D02*
Y257996D01*
G01X1629989Y267047D02*
X1631068Y265968D01*
G01X1629641Y267047D02*
X1629989D01*
G01X1629640Y267048D02*
X1629641Y267047D01*
G01X1620512Y267048D02*
X1629640D01*
G01X1620511Y267047D02*
X1620512Y267048D01*
G01X1619889Y267047D02*
X1620511D01*
G01X1619886Y267050D02*
X1619889Y267047D01*
G01X1607576Y267050D02*
X1619886D01*
G01X1606478Y265952D02*
X1607576Y267050D01*
G01X1603556Y265952D02*
X1606478D01*
G01X1601554Y267954D02*
X1603556Y265952D01*
G01X1644974Y264093D02*
X1656080Y252987D01*
G01X1644974Y269393D02*
Y264093D01*
G01X1639839Y274528D02*
X1644974Y269393D01*
G01X1639839Y284712D02*
Y274528D01*
G01X1598280Y259720D02*
X1594496Y263504D01*
G01X1599586Y259720D02*
X1598280D01*
G01X1599801Y259505D02*
X1599586Y259720D01*
G01X1602317Y259505D02*
X1599801D01*
G01X1608164Y265352D02*
X1602317Y259505D01*
G01X1610290Y265352D02*
X1608164D01*
G01X1639661Y263610D02*
X1656343Y246928D01*
G01X1639661Y264460D02*
Y263610D01*
G01X1636562Y267559D02*
X1639661Y264460D01*
G01X1635861Y267559D02*
X1636562D01*
G01X1631858Y271562D02*
X1635861Y267559D01*
G01X1621583Y271562D02*
X1631858D01*
G01X1619330Y273815D02*
X1621583Y271562D01*
G01X1619330Y273830D02*
Y273815D01*
G01X1618025Y275135D02*
X1619330Y273830D01*
G01X1606939Y275135D02*
X1618025D01*
G01X1605336Y276738D02*
X1606939Y275135D01*
G01X1629807Y276404D02*
X1622711Y283500D01*
G01X1630116Y276404D02*
X1629807D01*
G01X1630117Y276405D02*
X1630116Y276404D01*
G01X1631524Y276405D02*
X1630117D01*
G01X1631525Y276406D02*
X1631524Y276405D01*
G01X1632147Y276406D02*
X1631525D01*
G01X1632150Y276403D02*
X1632147Y276406D01*
G01X1632337Y276403D02*
X1632150D01*
G01X1635512Y273228D02*
X1632337Y276403D01*
G01X1637879Y273228D02*
X1635512D01*
G01X1642669Y268438D02*
X1637879Y273228D01*
G01X1642669Y264858D02*
Y268438D01*
G01X1655391Y252136D02*
X1642669Y264858D01*
G01X1609136Y270810D02*
X1604720Y275226D01*
G01X1631546Y270810D02*
X1609136D01*
G01X1634828Y267528D02*
X1631546Y270810D01*
G01X1634828Y263806D02*
Y267528D01*
G01X1636136Y262498D02*
X1634828Y263806D01*
G01X1639709Y262498D02*
X1636136D01*
G01X1656855Y245352D02*
X1639709Y262498D01*
G01X1634969Y279030D02*
X1636684Y277315D01*
G01X1634969Y279630D02*
Y279030D01*
G01X1623197Y273523D02*
X1623447Y273273D01*
G01X1621267Y273523D02*
X1623197D01*
G01X1618503Y276287D02*
X1621267Y273523D01*
G01X1609501Y276287D02*
X1618503D01*
G01X1607898Y277890D02*
X1609501Y276287D01*
G01X1623669Y259632D02*
X1626401Y256900D01*
G01X1604572Y259632D02*
X1623669D01*
G01X1602941Y258001D02*
X1604572Y259632D01*
G01X1599177Y258001D02*
X1602941D01*
G01X1598962Y258216D02*
X1599177Y258001D01*
G01X1597656Y258216D02*
X1598962D01*
G01X1593872Y262000D02*
X1597656Y258216D01*
G01X1624640Y256900D02*
X1626401D01*
G01X1620924Y253184D02*
X1624640Y256900D01*
G01X1620922Y253184D02*
X1620924D01*
G01X1620903Y253165D02*
X1620922Y253184D01*
G01X1616005Y253165D02*
X1620903D01*
G01X1612580Y256590D02*
X1616005Y253165D01*
G01X1606420Y256590D02*
X1612580D01*
G01X1603360Y253530D02*
X1606420Y256590D01*
G01X1603360Y248140D02*
Y253530D01*
G01X1599954Y244734D02*
X1603360Y248140D01*
G01X1626401Y256900D02*
X1627043D01*
G01X1589592Y251680D02*
Y252472D01*
G01X1600771Y270470D02*
X1601870D01*
G01X1600200Y269899D02*
X1600771Y270470D01*
G01X1640591Y275620D02*
Y285024D01*
G01X1645726Y270485D02*
X1640591Y275620D01*
G01X1645726Y264405D02*
Y270485D01*
G01X1656392Y253739D02*
X1645726Y264405D01*
G01X1596451Y252660D02*
X1592668D01*
G01X1599270Y249841D02*
X1596451Y252660D01*
G01X1599270Y246310D02*
Y249841D01*
G01X1611494Y278743D02*
X1608865Y281372D01*
G01X1620056Y278743D02*
X1611494D01*
G01X1621952Y276849D02*
X1620056Y278743D01*
G01X1626170Y276849D02*
X1621952D01*
G01X1628871Y274148D02*
X1626170Y276849D01*
G01X1631052Y274148D02*
X1628871D01*
G01X1631053Y274147D02*
X1631052Y274148D01*
G01X1631401Y274147D02*
X1631053D01*
G01X1636485Y269063D02*
X1631401Y274147D01*
G01X1637186Y269063D02*
X1636485D01*
G01X1641165Y265084D02*
X1637186Y269063D01*
G01X1641165Y264234D02*
Y265084D01*
G01X1656967Y248432D02*
X1641165Y264234D01*
G01X1596300Y250320D02*
X1592872Y246892D01*
G01X1640413Y263922D02*
X1656655Y247680D01*
G01X1640413Y264772D02*
Y263922D01*
G01X1636874Y268311D02*
X1640413Y264772D01*
G01X1636173Y268311D02*
X1636874D01*
G01X1631089Y273395D02*
X1636173Y268311D01*
G01X1628560Y273395D02*
X1631089D01*
G01X1625858Y276097D02*
X1628560Y273395D01*
G01X1621374Y276097D02*
X1625858D01*
G01X1619478Y277991D02*
X1621374Y276097D01*
G01X1611134Y277991D02*
X1619478D01*
G01X1609503Y279622D02*
X1611134Y277991D01*
G01X1631820Y259783D02*
X1637281Y254322D01*
G01X1631820Y266280D02*
Y259783D01*
G01X1630301Y267799D02*
X1631820Y266280D01*
G01X1629953Y267799D02*
X1630301D01*
G01X1629952Y267800D02*
X1629953Y267799D01*
G01X1620200Y267800D02*
X1629952D01*
G01X1620198Y267802D02*
X1620200Y267800D01*
G01X1607888Y267802D02*
X1620198D01*
G01X1605822Y269868D02*
X1607888Y267802D01*
G01X1603568Y269868D02*
X1605822D01*
G01X1602406Y268706D02*
X1603568Y269868D01*
G01X1610810Y277239D02*
X1609179Y278870D01*
G01X1618898Y277239D02*
X1610810D01*
G01X1620912Y275225D02*
X1618898Y277239D01*
G01X1624375Y275225D02*
X1620912D01*
G01X1626291Y273309D02*
X1624375Y275225D01*
G01X1641719Y276620D02*
Y307929D01*
G01X1648177Y270162D02*
X1641719Y276620D01*
G01X1648177Y264498D02*
Y270162D01*
G01X1658087Y254588D02*
X1648177Y264498D01*
G01X1596600Y246350D02*
X1595990Y245740D01*
G01X1597942Y253840D02*
X1596585Y255197D01*
G01X1600783Y253840D02*
X1597942D01*
G01X1605275Y258332D02*
X1600783Y253840D01*
G01X1614397Y258332D02*
X1605275D01*
G01X1616932Y255797D02*
X1614397Y258332D01*
G01X1618260Y255797D02*
X1616932D01*
G01X1620123Y257660D02*
X1618260Y255797D01*
G01X1620240Y257660D02*
X1620123D01*
G01X1643775Y247433D02*
Y246137D01*
G01X1640157Y251051D02*
X1643775Y247433D01*
G01X1635165Y251051D02*
X1640157D01*
G01X1631020Y255196D02*
X1635165Y251051D01*
G01X1628204Y255196D02*
X1631020D01*
G01X1628200Y255200D02*
X1628204Y255196D01*
G01X1624004Y255200D02*
X1628200D01*
G01X1621236Y252432D02*
X1624004Y255200D01*
G01X1621234Y252432D02*
X1621236D01*
G01X1621215Y252413D02*
X1621234Y252432D01*
G01X1615693Y252413D02*
X1621215D01*
G01X1612268Y255838D02*
X1615693Y252413D01*
G01X1607245Y255838D02*
X1612268D01*
G01X1605240Y253833D02*
X1607245Y255838D01*
G01X1605240Y248491D02*
Y253833D01*
G01X1600573Y243824D02*
X1605240Y248491D01*
G01X1622000Y279495D02*
X1621495Y280000D01*
G01X1607577Y273433D02*
X1617498D01*
G01X1605024Y275986D02*
X1607577Y273433D01*
G01X1646051Y251900D02*
X1657595Y240356D01*
G01X1636100Y251900D02*
X1646051D01*
G01X1629500Y258500D02*
X1636100Y251900D01*
G01X1626101Y258500D02*
X1629500D01*
G01X1624217Y260384D02*
X1626101Y258500D01*
G01X1604260Y260384D02*
X1624217D01*
G01X1602629Y258753D02*
X1604260Y260384D01*
G01X1599489Y258753D02*
X1602629D01*
G01X1599274Y258968D02*
X1599489Y258753D01*
G01X1597968Y258968D02*
X1599274D01*
G01X1594184Y262752D02*
X1597968Y258968D01*
G01X1629495Y275652D02*
X1622647Y282500D01*
G01X1630428Y275652D02*
X1629495D01*
G01X1630429Y275653D02*
X1630428Y275652D01*
G01X1631836Y275653D02*
X1630429D01*
G01X1631838Y275651D02*
X1631836Y275653D01*
G01X1632025Y275651D02*
X1631838D01*
G01X1635200Y272476D02*
X1632025Y275651D01*
G01X1637567Y272476D02*
X1635200D01*
G01X1641917Y268126D02*
X1637567Y272476D01*
G01X1641917Y264546D02*
Y268126D01*
G01X1656455Y250008D02*
X1641917Y264546D01*
G01X1595796Y263392D02*
X1594888Y264300D01*
G01X1601492Y263392D02*
X1595796D01*
G01X1602085Y263985D02*
X1601492Y263392D01*
G01X1602085Y264731D02*
Y263985D01*
G01X1600810Y266006D02*
X1602085Y264731D01*
G01X1597846Y252872D02*
X1596273Y254445D01*
G01X1600879Y252872D02*
X1597846D01*
G01X1605587Y257580D02*
X1600879Y252872D01*
G01X1614085Y257580D02*
X1605587D01*
G01X1616620Y255045D02*
X1614085Y257580D01*
G01X1619478Y255045D02*
X1616620D01*
G01X1619782Y254741D02*
X1619478Y255045D01*
G01X1620250Y254741D02*
X1619782D01*
G01X1641943Y259200D02*
X1658531Y242612D01*
G01X1636028Y259200D02*
X1641943D01*
G01X1633324Y261904D02*
X1636028Y259200D01*
G01X1633324Y266904D02*
Y261904D01*
G01X1630925Y269303D02*
X1633324Y266904D01*
G01X1630577Y269303D02*
X1630925D01*
G01X1630574Y269306D02*
X1630577Y269303D01*
G01X1608512Y269306D02*
X1630574D01*
G01X1604920Y272898D02*
X1608512Y269306D01*
G01X1604298Y272898D02*
X1604920D01*
G01X1604297Y272897D02*
X1604298Y272898D01*
G01X1600286Y272897D02*
X1604297D01*
G01X1600279Y272904D02*
X1600286Y272897D01*
G01X1598941Y271566D02*
X1600279Y272904D01*
G01X1646884Y340092D02*
Y379883D01*
G01X1643423Y336631D02*
X1646884Y340092D01*
G01X1628514Y336631D02*
X1643423D01*
G01X1626319Y338826D02*
X1628514Y336631D01*
G01X1626319Y338834D02*
Y338826D01*
G01X1620781Y344372D02*
X1626319Y338834D01*
G01X1593096Y338226D02*
X1597106Y342236D01*
G01X1598044Y287464D02*
X1598043Y287463D01*
G01X1600246Y287464D02*
X1598044D01*
G01X1602178Y285532D02*
X1600246Y287464D01*
G01X1622309Y285532D02*
X1602178D01*
G01X1601076Y282876D02*
X1599145Y284807D01*
G01X1610234Y282876D02*
X1601076D01*
G01X1611610Y281500D02*
X1610234Y282876D01*
G01X1622583Y281500D02*
X1611610D01*
G01X1645476Y340676D02*
Y367556D01*
G01X1642839Y338039D02*
X1645476Y340676D01*
G01X1629098Y338039D02*
X1642839D01*
G01X1627727Y339410D02*
X1629098Y338039D01*
G01X1627727Y339418D02*
Y339410D01*
G01X1618804Y348341D02*
X1627727Y339418D01*
G01X1592512Y339634D02*
X1601219Y348341D01*
G01X1608149Y321825D02*
X1608764Y322440D01*
G01X1602795Y321825D02*
X1608149D01*
G01X1598024Y317054D02*
X1602795Y321825D01*
G01X1638908Y285643D02*
X1639839Y284712D01*
G01X1637780Y285643D02*
X1638908D01*
G01X1637765Y285628D02*
X1637780Y285643D01*
G01X1635835Y285628D02*
X1637765D01*
G01X1635821Y285642D02*
X1635835Y285628D01*
G01X1635391Y285642D02*
X1635821D01*
G01X1628886Y292147D02*
X1635391Y285642D01*
G01X1628886Y308414D02*
Y292147D01*
G01X1620132Y317168D02*
X1628886Y308414D01*
G01X1605320Y317168D02*
X1620132D01*
G01X1597380Y309228D02*
X1605320Y317168D01*
G01X1597380Y303754D02*
Y309228D01*
G01X1591544Y297918D02*
X1597380Y303754D01*
G01X1624564Y287436D02*
X1625846Y286154D01*
G01X1603534Y287436D02*
X1624564D01*
G01X1601598Y289372D02*
X1603534Y287436D01*
G01X1598522Y286312D02*
X1598521Y286311D01*
G01X1599768Y286312D02*
X1598522D01*
G01X1601700Y284380D02*
X1599768Y286312D01*
G01X1611050Y284380D02*
X1601700D01*
G01X1611930Y283500D02*
X1611050Y284380D01*
G01X1622711Y283500D02*
X1611930D01*
G01X1604624Y319664D02*
X1598261Y313301D01*
G01X1638086Y319664D02*
X1604624D01*
G01X1589664Y314877D02*
X1590212Y315425D01*
G01X1626383Y288216D02*
X1634969Y279630D01*
G01X1604088Y288216D02*
X1626383D01*
G01X1601902Y290402D02*
X1604088Y288216D01*
G01X1590127Y290402D02*
X1601902D01*
G01X1602656Y286684D02*
X1600720Y288620D01*
G01X1622916Y286684D02*
X1602656D01*
G01X1629200Y280400D02*
X1622916Y286684D01*
G01X1631300Y280400D02*
X1629200D01*
G01X1605008Y317920D02*
X1597612Y310524D01*
G01X1620444Y317920D02*
X1605008D01*
G01X1629638Y308726D02*
X1620444Y317920D01*
G01X1629638Y292459D02*
Y308726D01*
G01X1635702Y286395D02*
X1629638Y292459D01*
G01X1636132Y286395D02*
X1635702D01*
G01X1636147Y286380D02*
X1636132Y286395D01*
G01X1637453Y286380D02*
X1636147D01*
G01X1637468Y286395D02*
X1637453Y286380D01*
G01X1639220Y286395D02*
X1637468D01*
G01X1640591Y285024D02*
X1639220Y286395D01*
G01X1600100Y281372D02*
X1598557Y282915D01*
G01X1608865Y281372D02*
X1600100D01*
G01X1649379Y340209D02*
Y352969D01*
G01X1649380Y340208D02*
X1649379Y340209D01*
G01X1649380Y339090D02*
Y340208D01*
G01X1649379Y339089D02*
X1649380Y339090D01*
G01X1649379Y336364D02*
Y339089D01*
G01X1647113Y334098D02*
X1649379Y336364D01*
G01X1627231Y334098D02*
X1647113D01*
G01X1626790Y334539D02*
X1627231Y334098D01*
G01X1614475Y334539D02*
X1626790D01*
G01X1613138Y333202D02*
X1614475Y334539D01*
G01X1608942Y333202D02*
X1613138D01*
G01X1605549Y336595D02*
X1608942Y333202D01*
G01X1598124Y336595D02*
X1605549D01*
G01X1596375Y334846D02*
X1598124Y336595D01*
G01X1650329Y340603D02*
Y352575D01*
G01X1650330Y340602D02*
X1650329Y340603D01*
G01X1650330Y338696D02*
Y340602D01*
G01X1650329Y338695D02*
X1650330Y338696D01*
G01X1650329Y335970D02*
Y338695D01*
G01X1647507Y333148D02*
X1650329Y335970D01*
G01X1627117Y333148D02*
X1647507D01*
G01X1626685Y333580D02*
X1627117Y333148D01*
G01X1614580Y333580D02*
X1626685D01*
G01X1613252Y332252D02*
X1614580Y333580D01*
G01X1608548Y332252D02*
X1613252D01*
G01X1605155Y335645D02*
X1608548Y332252D01*
G01X1598518Y335645D02*
X1605155D01*
G01X1596682Y333809D02*
X1598518Y335645D01*
G01X1641719Y307929D02*
X1639413Y310235D01*
G01X1602942Y339630D02*
X1609172D01*
G01X1601258Y337946D02*
X1602942Y339630D01*
G01X1595793Y337946D02*
X1601258D01*
G01X1593969Y336122D02*
X1595793Y337946D01*
G01X1600412Y282124D02*
X1598744Y283792D01*
G01X1609478Y282124D02*
X1600412D01*
G01X1611602Y280000D02*
X1609478Y282124D01*
G01X1621495Y280000D02*
X1611602D01*
G01X1647636Y339780D02*
Y379288D01*
G01X1643735Y335879D02*
X1647636Y339780D01*
G01X1628202Y335879D02*
X1643735D01*
G01X1625567Y338514D02*
X1628202Y335879D01*
G01X1625567Y338522D02*
Y338514D01*
G01X1620469Y343620D02*
X1625567Y338522D01*
G01X1593491Y337274D02*
X1597701Y341484D01*
G01X1598834Y285560D02*
X1598833Y285559D01*
G01X1599456Y285560D02*
X1598834D01*
G01X1601388Y283628D02*
X1599456Y285560D01*
G01X1610738Y283628D02*
X1601388D01*
G01X1611866Y282500D02*
X1610738Y283628D01*
G01X1622647Y282500D02*
X1611866D01*
G01X1637306Y318077D02*
X1639040Y316343D01*
G01X1621351Y318077D02*
X1637306D01*
G01X1620756Y318672D02*
X1621351Y318077D01*
G01X1604696Y318672D02*
X1620756D01*
G01X1598573Y312549D02*
X1604696Y318672D01*
G01X1629216Y364075D02*
X1630240Y365099D01*
G01X1627979Y364075D02*
X1629216D01*
G01X1624959Y361055D02*
X1627979Y364075D01*
G01X1617945Y361055D02*
X1624959D01*
G01X1616840Y359950D02*
X1617945Y361055D01*
G01X1609090Y359950D02*
X1616840D01*
G01X1604710Y355570D02*
X1609090Y359950D01*
G01X1596690Y355570D02*
X1604710D01*
G01X1593916Y352796D02*
X1596690Y355570D01*
G01X1588847Y352796D02*
X1593916D01*
G01X1646884Y379883D02*
X1659196Y392195D01*
G01X1616400Y344372D02*
X1620781D01*
G01X1614264Y342236D02*
X1616400Y344372D01*
G01X1597106Y342236D02*
X1614264D01*
G01X1591954Y346342D02*
X1591953Y346341D01*
G01X1592125Y346342D02*
X1591954D01*
G01X1597943Y352160D02*
X1592125Y346342D01*
G01X1614068Y352160D02*
X1597943D01*
G01X1618432Y356521D02*
X1614068Y352160D01*
G01X1621724Y356521D02*
X1618432D01*
G01X1625673Y352572D02*
X1621724Y356521D01*
G01X1631499Y352572D02*
X1625673D01*
G01X1637560Y358633D02*
X1631499Y352572D01*
G01X1637560Y371740D02*
Y358633D01*
G01X1660890Y395070D02*
X1637560Y371740D01*
G01X1598460Y364990D02*
X1596590D01*
G01X1604470Y371000D02*
X1598460Y364990D01*
G01X1612872Y371000D02*
X1604470D01*
G01X1617200Y375328D02*
X1612872Y371000D01*
G01X1617200Y381700D02*
Y375328D01*
G01X1621800Y386300D02*
X1617200Y381700D01*
G01X1615360Y395374D02*
X1621727D01*
G01X1607713Y403021D02*
X1615360Y395374D01*
G01X1640000Y370790D02*
X1640001D01*
G01X1640034Y370756D02*
X1640000Y370790D01*
G01X1642276Y370756D02*
X1640034D01*
G01X1645476Y367556D02*
X1642276Y370756D01*
G01X1614623Y348341D02*
X1618804D01*
G01X1611893Y345611D02*
X1614623Y348341D01*
G01X1608749Y345611D02*
X1611893D01*
G01X1606019Y348341D02*
X1608749Y345611D01*
G01X1601219Y348341D02*
X1606019D01*
G01X1595070Y361590D02*
X1590400Y366260D01*
G01X1603211Y361590D02*
X1595070D01*
G01X1607141Y365520D02*
X1603211Y361590D01*
G01X1622870Y365520D02*
X1607141D01*
G01X1626200Y368850D02*
X1622870Y365520D01*
G01X1626200Y373900D02*
Y368850D01*
G01X1630800Y378500D02*
X1626200Y373900D01*
G01X1625613Y354900D02*
X1630534D01*
G01X1622380Y358133D02*
X1625613Y354900D01*
G01X1617563Y358133D02*
X1622380D01*
G01X1613126Y353696D02*
X1617563Y358133D01*
G01X1597351Y353696D02*
X1613126D01*
G01X1591501Y347846D02*
X1597351Y353696D01*
G01X1640150Y375600D02*
X1630900D01*
G01X1659200Y394650D02*
X1640150Y375600D01*
G01X1624700Y395300D02*
X1630300D01*
G01X1622900Y393500D02*
X1624700Y395300D01*
G01X1612600Y393500D02*
X1622900D01*
G01X1611570Y392470D02*
X1612600Y393500D01*
G01X1611570Y385650D02*
Y392470D01*
G01X1610580Y384660D02*
X1611570Y385650D01*
G01X1591446Y347094D02*
X1591445Y347093D01*
G01X1591813Y347094D02*
X1591446D01*
G01X1597663Y352944D02*
X1591813Y347094D01*
G01X1613476Y352944D02*
X1597663D01*
G01X1617913Y357381D02*
X1613476Y352944D01*
G01X1621928Y357381D02*
X1617913D01*
G01X1625985Y353324D02*
X1621928Y357381D01*
G01X1631187Y353324D02*
X1625985D01*
G01X1632110Y354247D02*
X1631187Y353324D01*
G01X1632110Y355901D02*
Y354247D01*
G01X1630408Y357603D02*
X1632110Y355901D01*
G01X1596940Y354540D02*
X1591068Y348668D01*
G01X1612780Y354540D02*
X1596940D01*
G01X1618543Y360303D02*
X1612780Y354540D01*
G01X1625988Y360303D02*
X1618543D01*
G01X1628962Y363277D02*
X1625988Y360303D01*
G01X1629660Y363277D02*
X1628962D01*
G01X1630337Y362600D02*
X1629660Y363277D01*
G01X1650285Y353875D02*
X1651361D01*
G01X1649379Y352969D02*
X1650285Y353875D01*
G01X1589082Y354762D02*
X1590154D01*
G01X1594140Y360130D02*
X1589750Y364520D01*
G01X1603820Y360130D02*
X1594140D01*
G01X1607540Y363850D02*
X1603820Y360130D01*
G01X1624300Y363850D02*
X1607540D01*
G01X1628180Y367730D02*
X1624300Y363850D01*
G01X1630200Y367730D02*
X1628180D01*
G01X1598630Y364010D02*
X1596220D01*
G01X1604855Y370235D02*
X1598630Y364010D01*
G01X1613315Y370235D02*
X1604855D01*
G01X1621800Y378720D02*
X1613315Y370235D01*
G01X1621800Y381500D02*
Y378720D01*
G01X1650329Y352575D02*
X1650679Y352925D01*
G01X1616040Y383140D02*
X1591710D01*
G01X1624700Y391800D02*
X1616040Y383140D01*
G01X1630400Y391800D02*
X1624700D01*
G01X1592970Y342084D02*
X1589225D01*
G01X1600635Y349749D02*
X1592970Y342084D01*
G01X1619388Y349749D02*
X1600635D01*
G01X1620014Y349123D02*
X1619388Y349749D01*
G01X1637054Y349123D02*
X1620014D01*
G01X1638427Y347750D02*
X1637054Y349123D01*
G01X1639572Y347750D02*
X1638427D01*
G01X1642443Y344879D02*
X1639572Y347750D01*
G01X1590218Y350995D02*
Y350915D01*
G01X1595690Y363150D02*
X1591040Y367800D01*
G01X1598940Y363150D02*
X1595690D01*
G01X1605273Y369483D02*
X1598940Y363150D01*
G01X1613723Y369483D02*
X1605273D01*
G01X1623800Y379560D02*
X1613723Y369483D01*
G01X1623800Y384800D02*
Y379560D01*
G01X1628900Y389900D02*
X1623800Y384800D01*
G01X1631700Y389900D02*
X1628900D01*
G01X1632630Y390830D02*
X1631700Y389900D01*
G01X1632630Y392570D02*
Y390830D01*
G01X1631800Y393400D02*
X1632630Y392570D01*
G01X1624900Y393400D02*
X1631800D01*
G01X1618598Y387098D02*
X1624900Y393400D01*
G01X1613452Y387098D02*
X1618598D01*
G01X1598357Y404525D02*
X1593859Y400027D01*
G01X1614162Y398700D02*
X1608337Y404525D01*
G01X1630400Y398700D02*
X1614162D01*
G01X1627799Y402800D02*
X1628099Y403100D01*
G01X1611126Y402800D02*
X1627799D01*
G01X1608649Y405277D02*
X1611126Y402800D01*
G01X1593588Y400820D02*
X1598045Y405277D01*
G01X1647636Y379288D02*
X1659342Y390994D01*
G01X1616712Y343620D02*
X1620469D01*
G01X1614576Y341484D02*
X1616712Y343620D01*
G01X1597701Y341484D02*
X1614576D01*
G01X1641887Y349854D02*
X1643700Y351667D01*
G01X1638451Y349854D02*
X1641887D01*
G01X1636885Y351420D02*
X1638451Y349854D01*
G01X1625195Y351420D02*
X1636885D01*
G01X1621246Y355369D02*
X1625195Y351420D01*
G01X1618480Y355369D02*
X1621246D01*
G01X1614451Y351369D02*
X1618480Y355369D01*
G01X1599278Y351369D02*
X1614451D01*
G01X1593098Y345189D02*
X1599278Y351369D01*
G01X1598788Y403773D02*
X1590215Y395200D01*
G01X1614698Y397100D02*
X1608025Y403773D01*
G01X1654398Y397100D02*
X1614698D01*
G01X1599803Y350547D02*
X1593493Y344237D01*
G01X1614974Y350547D02*
X1599803D01*
G01X1618874Y354417D02*
X1614974Y350547D01*
G01X1620851Y354417D02*
X1618874D01*
G01X1624800Y350468D02*
X1620851Y354417D01*
G01X1636773Y350468D02*
X1624800D01*
G01X1638339Y348902D02*
X1636773Y350468D01*
G01X1642785Y348902D02*
X1638339D01*
G01X1642995Y348692D02*
X1642785Y348902D01*
G01X1643150Y348692D02*
X1642995D01*
G01X1628942Y413942D02*
X1630386D01*
G01X1618674Y403674D02*
X1628942Y413942D01*
G01X1611316Y403674D02*
X1618674D01*
G01X1606290Y408700D02*
X1611316Y403674D01*
G01X1594600Y408700D02*
X1606290D01*
G01X1592300Y406400D02*
X1594600Y408700D01*
G01X1622005Y458693D02*
X1628909Y465597D01*
G01X1606987Y458693D02*
X1622005D01*
G01X1596780Y468900D02*
X1606987Y458693D01*
G01X1650175Y429225D02*
X1666413Y412987D01*
G01X1650175Y479154D02*
Y429225D01*
G01X1599605Y403021D02*
X1607713D01*
G01X1611781Y405438D02*
X1612825D01*
G01X1607719Y409500D02*
X1611781Y405438D01*
G01X1594100Y409500D02*
X1607719D01*
G01X1591800Y407200D02*
X1594100Y409500D01*
G01X1593400Y433700D02*
Y432200D01*
G01X1595900Y437587D02*
X1602600Y444287D01*
G01X1595900Y432471D02*
Y437587D01*
G01X1592829Y429400D02*
X1595900Y432471D01*
G01X1588986Y429400D02*
X1592829D01*
G01X1620901Y460101D02*
X1622700Y461900D01*
G01X1610719Y460101D02*
X1620901D01*
G01X1608755Y462065D02*
X1610719Y460101D01*
G01X1608755Y463555D02*
Y462065D01*
G01X1632778Y462378D02*
X1636300Y465900D01*
G01X1632778Y411630D02*
Y462378D01*
G01X1634166Y410242D02*
X1632778Y411630D01*
G01X1657757Y410242D02*
X1634166D01*
G01X1634500Y412900D02*
X1634400D01*
G01X1636500Y414900D02*
X1634500Y412900D01*
G01X1636500Y422200D02*
Y414900D01*
G01X1633800Y424900D02*
X1636500Y422200D01*
G01X1633800Y461816D02*
Y424900D01*
G01X1637292Y465308D02*
X1633800Y461816D01*
G01X1589200Y442718D02*
X1591446Y440472D01*
G01X1604999Y451500D02*
X1591949Y464550D01*
G01X1600650Y435389D02*
X1603652Y438391D01*
G01X1600650Y420250D02*
Y435389D01*
G01X1602600Y418300D02*
X1600650Y420250D01*
G01X1612700Y418300D02*
X1602600D01*
G01X1617900Y413100D02*
X1612700Y418300D01*
G01X1617900Y409900D02*
Y413100D01*
G01X1589396Y415755D02*
Y425674D01*
G01X1594815Y410336D02*
X1589396Y415755D01*
G01X1608154Y410336D02*
X1594815D01*
G01X1611316Y407174D02*
X1608154Y410336D01*
G01X1618673Y407174D02*
X1611316D01*
G01X1627017Y415518D02*
X1618673Y407174D01*
G01X1631039Y415518D02*
X1627017D01*
G01X1631962Y414595D02*
X1631039Y415518D01*
G01X1631962Y411382D02*
Y414595D01*
G01X1634015Y409329D02*
X1631962Y411382D01*
G01X1656439Y409329D02*
X1634015D01*
G01X1611509Y461877D02*
X1611642D01*
G01X1610336Y463050D02*
X1611509Y461877D01*
G01X1610336Y464164D02*
Y463050D01*
G01X1610500Y413800D02*
X1612500Y411800D01*
G01X1596300Y413800D02*
X1610500D01*
G01X1595200Y412700D02*
X1596300Y413800D01*
G01X1608337Y404525D02*
X1598357D01*
G01X1628099Y403100D02*
X1653354D01*
G01X1598045Y405277D02*
X1608649D01*
G01X1594850Y448800D02*
X1591350Y445300D01*
G01X1601900Y448800D02*
X1594850D01*
G01X1604300Y446400D02*
X1601900Y448800D01*
G01X1604300Y443400D02*
Y446400D01*
G01X1596652Y435752D02*
X1604300Y443400D01*
G01X1596652Y431488D02*
Y435752D01*
G01X1596150Y430986D02*
X1596652Y431488D01*
G01X1596150Y430950D02*
Y430986D01*
G01X1593400Y428200D02*
X1596150Y430950D01*
G01X1588850Y428200D02*
X1593400D01*
G01X1606468Y457212D02*
X1596871Y466809D01*
G01X1619788Y457212D02*
X1606468D01*
G01X1624100Y452900D02*
X1619788Y457212D01*
G01X1624100Y437250D02*
Y452900D01*
G01X1630150Y431200D02*
X1624100Y437250D01*
G01X1630150Y427663D02*
Y431200D01*
G01X1608025Y403773D02*
X1598788D01*
G01X1632855Y472859D02*
X1633359D01*
G01X1628909Y468913D02*
X1632855Y472859D01*
G01X1628909Y465597D02*
Y468913D01*
G01X1647229Y482100D02*
X1650175Y479154D01*
G01X1644889Y482100D02*
X1647229D01*
G01X1641165Y485824D02*
X1644889Y482100D01*
G01X1640447Y485824D02*
X1641165D01*
G01X1638611Y487660D02*
X1640447Y485824D01*
G01X1638611Y490475D02*
Y487660D01*
G01X1639271Y491135D02*
X1638611Y490475D01*
G01X1621271Y472000D02*
X1603600D01*
G01X1624495Y475224D02*
X1621271Y472000D01*
G01X1633976Y475224D02*
X1624495D01*
G01X1636300Y472900D02*
X1633976Y475224D01*
G01X1636300Y465900D02*
Y472900D01*
G01X1637292Y473208D02*
Y465308D01*
G01X1634524Y475976D02*
X1637292Y473208D01*
G01X1624012Y475976D02*
X1634524D01*
G01X1621036Y473000D02*
X1624012Y475976D01*
G01X1606916Y473000D02*
X1621036D01*
G01X1605200Y474716D02*
X1606916Y473000D01*
G01X1605200Y478916D02*
Y474716D01*
G01X1603044Y481072D02*
X1605200Y478916D01*
G01X1598157Y481072D02*
X1603044D01*
G01X1590629Y488600D02*
X1598157Y481072D01*
G01X1650403Y479990D02*
X1656311D01*
G01X1647540Y482853D02*
X1650403Y479990D01*
G01X1645200Y482853D02*
X1647540D01*
G01X1641357Y486696D02*
X1645200Y482853D01*
G01X1641357Y487224D02*
Y486696D01*
G01X1640743Y487838D02*
X1641357Y487224D01*
G01X1640743Y487760D02*
Y487838D01*
G01X1640781Y487760D02*
X1640743D01*
G01X1621387Y553251D02*
X1654890D01*
G01X1618604Y556034D02*
X1621387Y553251D01*
G01X1618604Y568725D02*
Y556034D01*
G01X1613189Y574140D02*
X1618604Y568725D01*
G01X1601511Y574140D02*
X1613189D01*
G01X1601295Y574356D02*
X1601511Y574140D01*
G01X1597115Y574356D02*
X1601295D01*
G01X1592369Y569610D02*
X1597115Y574356D01*
G01X1599694Y597853D02*
Y587634D01*
G01X1617880Y584940D02*
Y590395D01*
G01X1625924Y576896D02*
X1617880Y584940D01*
G01X1647640Y576896D02*
X1625924D01*
G01X1650512Y574024D02*
X1647640Y576896D01*
G01X1601793Y584496D02*
X1590363Y573066D01*
G01X1606837Y584496D02*
X1601793D01*
G01X1612722Y578611D02*
X1606837Y584496D01*
G01X1615759Y578611D02*
X1612722D01*
G01X1621130Y573240D02*
X1615759Y578611D01*
G01X1644200Y573240D02*
X1621130D01*
G01X1649528Y567912D02*
X1644200Y573240D01*
G01X1649528Y563503D02*
Y567912D01*
G01X1653849Y559182D02*
X1649528Y563503D01*
G01X1649640Y572772D02*
X1654202D01*
G01X1646768Y575644D02*
X1649640Y572772D01*
G01X1622127Y575644D02*
X1646768D01*
G01X1616756Y581015D02*
X1622127Y575644D01*
G01X1613719Y581015D02*
X1616756D01*
G01X1607834Y586900D02*
X1613719Y581015D01*
G01X1600731Y586900D02*
X1607834D01*
G01X1589301Y575470D02*
X1600731Y586900D01*
G01X1601250Y585648D02*
X1589820Y574218D01*
G01X1607315Y585648D02*
X1601250D01*
G01X1613200Y579763D02*
X1607315Y585648D01*
G01X1616237Y579763D02*
X1613200D01*
G01X1621608Y574392D02*
X1616237Y579763D01*
G01X1644678Y574392D02*
X1621608D01*
G01X1650681Y568389D02*
X1644678Y574392D01*
G01X1595977Y576660D02*
X1591231Y571914D01*
G01X1602251Y576660D02*
X1595977D01*
G01X1602467Y576444D02*
X1602251Y576660D01*
G01X1614145Y576444D02*
X1602467D01*
G01X1620908Y569681D02*
X1614145Y576444D01*
G01X1620908Y566951D02*
Y569681D01*
G01X1622459Y565400D02*
X1620908Y566951D01*
G01X1624900Y565400D02*
X1622459D01*
G01X1629039Y561261D02*
X1624900Y565400D01*
G01X1640728Y561261D02*
X1629039D01*
G01X1643959Y558030D02*
X1640728Y561261D01*
G01X1725291Y558030D02*
X1643959D01*
G01X1589272Y583335D02*
X1595904Y589967D01*
G01X1597190Y588994D02*
X1590041Y581845D01*
G01X1596569Y575508D02*
X1591823Y570762D01*
G01X1601773Y575508D02*
X1596569D01*
G01X1601989Y575292D02*
X1601773Y575508D01*
G01X1613667Y575292D02*
X1601989D01*
G01X1619756Y569203D02*
X1613667Y575292D01*
G01X1619756Y566473D02*
Y569203D01*
G01X1622729Y563500D02*
X1619756Y566473D01*
G01X1625000Y563500D02*
X1622729D01*
G01X1628391Y560109D02*
X1625000Y563500D01*
G01X1640250Y560109D02*
X1628391D01*
G01X1643481Y556878D02*
X1640250Y560109D01*
G01X1710542Y556878D02*
X1643481D01*
G01X1600617Y598776D02*
X1599694Y597853D01*
G01X1609499Y598776D02*
X1600617D01*
G01X1617880Y590395D02*
X1609499Y598776D01*
G01X1592650Y595850D02*
X1590604Y593804D01*
G01X1592650Y608500D02*
Y595850D01*
G01X1590530Y610620D02*
X1592650Y608500D01*
G01X1598442Y598372D02*
Y588153D01*
G01X1599286Y599216D02*
X1598442Y598372D01*
G01X1599286Y610085D02*
Y599216D01*
G01X1601497Y612296D02*
X1599286Y610085D01*
G01X1602803Y612296D02*
X1601497D01*
G01X1603726Y611373D02*
X1602803Y612296D01*
G01X1603726Y611222D02*
Y611373D01*
G01X1609391Y605557D02*
X1603726Y611222D01*
G01X1613576Y605557D02*
X1609391D01*
G01X1620621Y612602D02*
X1613576Y605557D01*
G01X1620621Y614123D02*
Y612602D01*
G01X1625240Y618742D02*
X1620621Y614123D01*
G01X1654478Y618742D02*
X1625240D01*
G01X1621317Y621146D02*
X1691963D01*
G01X1618100Y617929D02*
X1621317Y621146D01*
G01X1618100Y613482D02*
Y617929D01*
G01X1612580Y607962D02*
X1618100Y613482D01*
G01X1610387Y607962D02*
X1612580D01*
G01X1606130Y612219D02*
X1610387Y607962D01*
G01X1606130Y612370D02*
Y612219D01*
G01X1603546Y614954D02*
X1606130Y612370D01*
G01X1599385Y614954D02*
X1603546D01*
G01X1596751Y612320D02*
X1599385Y614954D01*
G01X1596751Y610270D02*
Y612320D01*
G01X1596752Y610269D02*
X1596751Y610270D01*
G01X1596752Y600383D02*
Y610269D01*
G01X1595904Y599535D02*
X1596752Y600383D01*
G01X1595904Y589967D02*
Y599535D01*
G01X1597190Y598980D02*
Y588994D01*
G01X1598004Y599794D02*
X1597190Y598980D01*
G01X1598004Y611376D02*
Y599794D01*
G01X1600329Y613701D02*
X1598004Y611376D01*
G01X1603028Y613701D02*
X1600329D01*
G01X1604878Y611851D02*
X1603028Y613701D01*
G01X1604878Y611700D02*
Y611851D01*
G01X1609868Y606710D02*
X1604878Y611700D01*
G01X1613099Y606710D02*
X1609868D01*
G01X1619469Y613080D02*
X1613099Y606710D01*
G01X1619469Y614601D02*
Y613080D01*
G01X1624762Y619894D02*
X1619469Y614601D01*
G01X1691444Y619894D02*
X1624762D01*
G01X1686424Y4576D02*
X1688000Y3000D01*
G01X1679518Y4576D02*
X1686424D01*
G01X1677016Y2074D02*
X1679518Y4576D01*
G01X1662243Y2074D02*
X1677016D01*
G01X1654916Y-5253D02*
X1662243Y2074D01*
G01X1663071Y-4000D02*
X1657058Y-10013D01*
G01X1693271Y-4000D02*
X1663071D01*
G01X1699957Y2686D02*
X1693271Y-4000D01*
G01X1772099Y2686D02*
X1699957D01*
G01X1701931Y-171D02*
X1789918D01*
G01X1701930Y-170D02*
X1701931Y-171D01*
G01X1701142Y-170D02*
X1701930D01*
G01X1693996Y-7316D02*
X1701142Y-170D01*
G01X1682004Y-7316D02*
X1693996D01*
G01X1681979Y-7291D02*
X1682004Y-7316D01*
G01X1678321Y-7291D02*
X1681979D01*
G01X1678320Y-7292D02*
X1678321Y-7291D01*
G01X1666980Y-7292D02*
X1678320D01*
G01X1666978Y-7290D02*
X1666980Y-7292D01*
G01X1664610Y-7290D02*
X1666978D01*
G01X1664609Y-7291D02*
X1664610Y-7290D01*
G01X1663821Y-7291D02*
X1664609D01*
G01X1657876Y-13236D02*
X1663821Y-7291D01*
G01X1700747Y782D02*
X1778048D01*
G01X1693982Y-5983D02*
X1700747Y782D01*
G01X1663782Y-5983D02*
X1693982D01*
G01X1657848Y-11917D02*
X1663782Y-5983D01*
G01X1662724Y-3000D02*
X1656663Y-9061D01*
G01X1692924Y-3000D02*
X1662724D01*
G01X1699562Y3638D02*
X1692924Y-3000D01*
G01X1771704Y3638D02*
X1699562D01*
G01X1665400Y-11100D02*
X1658100Y-18400D01*
G01X1679900Y-11100D02*
X1665400D01*
G01X1679924Y-11124D02*
X1679900Y-11100D01*
G01X1822452Y-11124D02*
X1679924D01*
G01X1662377Y-2000D02*
X1656268Y-8109D01*
G01X1692577Y-2000D02*
X1662377D01*
G01X1699167Y4590D02*
X1692577Y-2000D01*
G01X1771309Y4590D02*
X1699167D01*
G01X1700352Y1734D02*
X1774388D01*
G01X1693618Y-5000D02*
X1700352Y1734D01*
G01X1663418Y-5000D02*
X1693618D01*
G01X1657453Y-10965D02*
X1663418Y-5000D01*
G01X1695793Y15176D02*
X1738824D01*
G01X1695311Y15658D02*
X1695793Y15176D01*
G01X1694005Y15658D02*
X1695311D01*
G01X1693523Y15176D02*
X1694005Y15658D01*
G01X1658775Y15176D02*
X1693523D01*
G01X1655593Y11994D02*
X1658775Y15176D01*
G01X1655593Y11094D02*
Y11994D01*
G01X1653622Y9123D02*
X1655593Y11094D01*
G01X1698772Y5542D02*
X1770032D01*
G01X1692230Y-1000D02*
X1698772Y5542D01*
G01X1662030Y-1000D02*
X1692230D01*
G01X1655873Y-7157D02*
X1662030Y-1000D01*
G01X1696910Y-8996D02*
X1820990D01*
G01X1696686Y-9220D02*
X1696910Y-8996D01*
G01X1681214Y-9220D02*
X1696686D01*
G01X1681190Y-9196D02*
X1681214Y-9220D01*
G01X1680690Y-9196D02*
X1681190D01*
G01X1680689Y-9195D02*
X1680690Y-9196D01*
G01X1679111Y-9195D02*
X1680689D01*
G01X1679110Y-9196D02*
X1679111Y-9195D01*
G01X1666190Y-9196D02*
X1679110D01*
G01X1666188Y-9194D02*
X1666190Y-9196D01*
G01X1665400Y-9194D02*
X1666188D01*
G01X1665399Y-9195D02*
X1665400Y-9194D01*
G01X1664611Y-9195D02*
X1665399D01*
G01X1658666Y-15140D02*
X1664611Y-9195D01*
G01X1653100Y14200D02*
Y11500D01*
G01X1665173Y26273D02*
X1653100Y14200D01*
G01X1761035Y26273D02*
X1665173D01*
G01X1664216Y-8243D02*
X1658271Y-14188D01*
G01X1665004Y-8243D02*
X1664216D01*
G01X1665005Y-8242D02*
X1665004Y-8243D01*
G01X1666583Y-8242D02*
X1665005D01*
G01X1666585Y-8244D02*
X1666583Y-8242D01*
G01X1678715Y-8244D02*
X1666585D01*
G01X1678716Y-8243D02*
X1678715Y-8244D01*
G01X1681584Y-8243D02*
X1678716D01*
G01X1681609Y-8268D02*
X1681584Y-8243D01*
G01X1694391Y-8268D02*
X1681609D01*
G01X1701536Y-1123D02*
X1694391Y-8268D01*
G01X1790333Y-1123D02*
X1701536D01*
G01X1661683Y0D02*
X1655478Y-6205D01*
G01X1691883Y0D02*
X1661683D01*
G01X1698377Y6494D02*
X1691883Y0D01*
G01X1758789Y6494D02*
X1698377D01*
G01X1697304Y-9949D02*
X1822280D01*
G01X1697081Y-10172D02*
X1697304Y-9949D01*
G01X1680819Y-10172D02*
X1697081D01*
G01X1680795Y-10148D02*
X1680819Y-10172D01*
G01X1680295Y-10148D02*
X1680795D01*
G01X1680294Y-10147D02*
X1680295Y-10148D01*
G01X1679506Y-10147D02*
X1680294D01*
G01X1679505Y-10148D02*
X1679506Y-10147D01*
G01X1665795Y-10148D02*
X1679505D01*
G01X1665794Y-10147D02*
X1665795Y-10148D01*
G01X1665006Y-10147D02*
X1665794D01*
G01X1659061Y-16092D02*
X1665006Y-10147D01*
G01X1654738Y66838D02*
X1651815Y69761D01*
G01X1679740Y66838D02*
X1654738D01*
G01X1682587Y63991D02*
X1679740Y66838D01*
G01X1683209Y63991D02*
X1682587D01*
G01X1683210Y63992D02*
X1683209Y63991D01*
G01X1748744Y63992D02*
X1683210D01*
G01X1704371Y97982D02*
X1712324Y90029D01*
G01X1660943Y90328D02*
X1659565Y91706D01*
G01X1669757Y90328D02*
X1660943D01*
G01X1670996Y91567D02*
X1669757Y90328D01*
G01X1670996Y93258D02*
Y91567D01*
G01X1671951Y94213D02*
X1670996Y93258D01*
G01X1676566Y94213D02*
X1671951D01*
G01X1678109Y92670D02*
X1676566Y94213D01*
G01X1681433Y92670D02*
X1678109D01*
G01X1683295Y90808D02*
X1681433Y92670D01*
G01X1697919Y90808D02*
X1683295D01*
G01X1707225Y81502D02*
X1697919Y90808D01*
G01X1732202Y81502D02*
X1707225D01*
G01X1662747Y84148D02*
X1660619Y82020D01*
G01X1679820Y84148D02*
X1662747D01*
G01X1684168Y88496D02*
X1679820Y84148D01*
G01X1698079Y88496D02*
X1684168D01*
G01X1706577Y79998D02*
X1698079Y88496D01*
G01X1731063Y79998D02*
X1706577D01*
G01X1709051Y86909D02*
X1712140Y83820D01*
G01X1705442Y86909D02*
X1709051D01*
G01X1697800Y94551D02*
X1705442Y86909D01*
G01X1652900Y54096D02*
X1652548Y54448D01*
G01X1652900Y52447D02*
Y54096D01*
G01X1652548Y52095D02*
X1652900Y52447D01*
G01X1664380Y59780D02*
X1654342Y49742D01*
G01X1723619Y59780D02*
X1664380D01*
G01X1711072Y86728D02*
X1712728Y85072D01*
G01X1711072Y89510D02*
Y86728D01*
G01X1703852Y96730D02*
X1711072Y89510D01*
G01X1660000Y62700D02*
X1725871D01*
G01X1654550Y57250D02*
X1660000Y62700D01*
G01X1714870Y90318D02*
X1703360Y101828D01*
G01X1673800Y74600D02*
Y75200D01*
G01X1678754Y69646D02*
X1673800Y74600D01*
G01X1680124Y69646D02*
X1678754D01*
G01X1683522Y66248D02*
X1680124Y69646D01*
G01X1750288Y66248D02*
X1683522D01*
G01X1703672Y102580D02*
X1715182Y91070D01*
G01X1664924Y85924D02*
X1667000Y88000D01*
G01X1661936Y85924D02*
X1664924D01*
G01X1659736Y83724D02*
X1661936Y85924D01*
G01X1703357Y73343D02*
X1726826D01*
G01X1701769Y74931D02*
X1703357Y73343D01*
G01X1694715Y74931D02*
X1701769D01*
G01X1691655Y77991D02*
X1694715Y74931D01*
G01X1662600Y61300D02*
X1657100Y55800D01*
G01X1724798Y61300D02*
X1662600D01*
G01X1683834Y67000D02*
X1750600D01*
G01X1676428Y74406D02*
X1683834Y67000D01*
G01X1676428Y74646D02*
Y74406D01*
G01X1672599Y84900D02*
X1674749Y87050D01*
G01X1662399Y84900D02*
X1672599D01*
G01X1660271Y82772D02*
X1662399Y84900D01*
G01X1674796Y83396D02*
X1673000Y81600D01*
G01X1680132Y83396D02*
X1674796D01*
G01X1684480Y87744D02*
X1680132Y83396D01*
G01X1697767Y87744D02*
X1684480D01*
G01X1706265Y79246D02*
X1697767Y87744D01*
G01X1730751Y79246D02*
X1706265D01*
G01X1704172Y74096D02*
X1727420D01*
G01X1702585Y75683D02*
X1704172Y74096D01*
G01X1695755Y75683D02*
X1702585D01*
G01X1694155Y77283D02*
X1695755Y75683D01*
G01X1694155Y77991D02*
Y77283D01*
G01X1714558Y89566D02*
X1703048Y101076D01*
G01X1655050Y67590D02*
X1652127Y70513D01*
G01X1680052Y67590D02*
X1655050D01*
G01X1682898Y64744D02*
X1680052Y67590D01*
G01X1749056Y64744D02*
X1682898D01*
G01X1677204Y44004D02*
X1767733D01*
G01X1676324Y43124D02*
X1677204Y44004D01*
G01X1654826Y43124D02*
X1676324D01*
G01X1652750Y45200D02*
X1654826Y43124D01*
G01X1707537Y82254D02*
X1752438D01*
G01X1698231Y91560D02*
X1707537Y82254D01*
G01X1684486Y91560D02*
X1698231D01*
G01X1682624Y93422D02*
X1684486Y91560D01*
G01X1678938Y93422D02*
X1682624D01*
G01X1677396Y94964D02*
X1678938Y93422D01*
G01X1660056Y92785D02*
X1662235Y94964D01*
G01X1661922Y95715D02*
X1659743Y93536D01*
G01X1679343Y94174D02*
X1677802Y95715D01*
G01X1688872Y94174D02*
X1679343D01*
G01X1691369Y96671D02*
X1688872Y94174D01*
G01X1660348Y89576D02*
X1659170Y90754D01*
G01X1669445Y89576D02*
X1660348D01*
G01X1669446Y89575D02*
X1669445Y89576D01*
G01X1670068Y89575D02*
X1669446D01*
G01X1671748Y91255D02*
X1670068Y89575D01*
G01X1671748Y92536D02*
Y91255D01*
G01X1671747Y92537D02*
X1671748Y92536D01*
G01X1671747Y92946D02*
Y92537D01*
G01X1672263Y93462D02*
X1671747Y92946D01*
G01X1676254Y93462D02*
X1672263D01*
G01X1677798Y91918D02*
X1676254Y93462D01*
G01X1680878Y91918D02*
X1677798D01*
G01X1682740Y90056D02*
X1680878Y91918D01*
G01X1697607Y90056D02*
X1682740D01*
G01X1706913Y80750D02*
X1697607Y90056D01*
G01X1731890Y80750D02*
X1706913D01*
G01X1707922Y83006D02*
X1752750D01*
G01X1698616Y92312D02*
X1707922Y83006D01*
G01X1694938Y92312D02*
X1698616D01*
G01X1692647Y94603D02*
X1694938Y92312D01*
G01X1680099Y77600D02*
X1653000D01*
G01X1684343Y81844D02*
X1680099Y77600D01*
G01X1696962Y81844D02*
X1684343D01*
G01X1702338Y76468D02*
X1696962Y81844D01*
G01X1702864Y76468D02*
X1702338D01*
G01X1704284Y75048D02*
X1702864Y76468D01*
G01X1729058Y75048D02*
X1704284D01*
G01X1667629Y58628D02*
X1657403Y48402D01*
G01X1722201Y58628D02*
X1667629D01*
G01X1653593Y79500D02*
X1650800D01*
G01X1654541Y78552D02*
X1653593Y79500D01*
G01X1679704Y78552D02*
X1654541D01*
G01X1683948Y82796D02*
X1679704Y78552D01*
G01X1697217Y82796D02*
X1683948D01*
G01X1702793Y77220D02*
X1697217Y82796D01*
G01X1705404Y77220D02*
X1702793D01*
G01X1706824Y75800D02*
X1705404Y77220D01*
G01X1730335Y75800D02*
X1706824D01*
G01X1651816Y71266D02*
X1651815Y71265D01*
G01X1652438Y71266D02*
X1651816D01*
G01X1655362Y68342D02*
X1652438Y71266D01*
G01X1680364Y68342D02*
X1655362D01*
G01X1683210Y65496D02*
X1680364Y68342D01*
G01X1749368Y65496D02*
X1683210D01*
G01X1684949Y149532D02*
X1675026Y159455D01*
G01X1704816Y149532D02*
X1684949D01*
G01X1710121Y154837D02*
X1704816Y149532D01*
G01X1756107Y154837D02*
X1710121D01*
G01X1699579Y97982D02*
X1704371D01*
G01X1699050Y97453D02*
X1699579Y97982D01*
G01X1696559Y97453D02*
X1699050D01*
G01X1696472Y97540D02*
X1696559Y97453D01*
G01X1695661Y97540D02*
X1696472D01*
G01X1688526Y104675D02*
X1695661Y97540D01*
G01X1668616Y104675D02*
X1688526D01*
G01X1666414Y102473D02*
X1668616Y104675D01*
G01X1656940Y102473D02*
X1666414D01*
G01X1653489Y99022D02*
X1656940Y102473D01*
G01X1654129Y100765D02*
X1650902D01*
G01X1656589Y103225D02*
X1654129Y100765D01*
G01X1666102Y103225D02*
X1656589D01*
G01X1668804Y105927D02*
X1666102Y103225D01*
G01X1690965Y105927D02*
X1668804D01*
G01X1696907Y99985D02*
X1690965Y105927D01*
G01X1696907Y99077D02*
Y99985D01*
G01X1653293Y116402D02*
X1652319Y117376D01*
G01X1656660Y116402D02*
X1653293D01*
G01X1657224Y116966D02*
X1656660Y116402D01*
G01X1658446Y116966D02*
X1657224D01*
G01X1659310Y116102D02*
X1658446Y116966D01*
G01X1659310Y115080D02*
Y116102D01*
G01X1660374Y114016D02*
X1659310Y115080D01*
G01X1661719Y114016D02*
X1660374D01*
G01X1662660Y113075D02*
X1661719Y114016D01*
G01X1662660Y111729D02*
Y113075D01*
G01X1663523Y110866D02*
X1662660Y111729D01*
G01X1668939Y110866D02*
X1663523D01*
G01X1670625Y112552D02*
X1668939Y110866D01*
G01X1670625Y112853D02*
Y112552D01*
G01X1671788Y114016D02*
X1670625Y112853D01*
G01X1692110Y114016D02*
X1671788D01*
G01X1699769Y106357D02*
X1692110Y114016D01*
G01X1704999Y106357D02*
X1699769D01*
G01X1705167Y106189D02*
X1704999Y106357D01*
G01X1705168Y106189D02*
X1705167D01*
G01X1713043Y98314D02*
X1705168Y106189D01*
G01X1653777Y109191D02*
X1652302Y110666D01*
G01X1654686Y109191D02*
X1653777D01*
G01X1697800Y94612D02*
Y94551D01*
G01X1700098Y96730D02*
X1703852D01*
G01X1699569Y96201D02*
X1700098Y96730D01*
G01X1696040Y96201D02*
X1699569D01*
G01X1695953Y96288D02*
X1696040Y96201D01*
G01X1695142Y96288D02*
X1695953D01*
G01X1693507Y97923D02*
X1695142Y96288D01*
G01X1690850Y97923D02*
X1693507D01*
G01X1688353Y95426D02*
X1690850Y97923D01*
G01X1679741Y95426D02*
X1688353D01*
G01X1678440Y96727D02*
X1679741Y95426D01*
G01X1657999Y96727D02*
X1678440D01*
G01X1656197Y94925D02*
X1657999Y96727D01*
G01X1704067Y103532D02*
X1715778Y91821D01*
G01X1698267Y103532D02*
X1704067D01*
G01X1692510Y109289D02*
X1698267Y103532D01*
G01X1665953Y109289D02*
X1692510D01*
G01X1664162Y107498D02*
X1665953Y109289D01*
G01X1659936Y107498D02*
X1664162D01*
G01X1659332Y108102D02*
X1659936Y107498D01*
G01X1659332Y109876D02*
Y108102D01*
G01X1658342Y110866D02*
X1659332Y109876D01*
G01X1656514Y110866D02*
X1658342D01*
G01X1656161Y111219D02*
X1656514Y110866D01*
G01X1656161Y112951D02*
Y111219D01*
G01X1655241Y113871D02*
X1656161Y112951D01*
G01X1692255Y112200D02*
X1672200D01*
G01X1693262Y111193D02*
X1692255Y112200D01*
G01X1693300Y111193D02*
X1693262D01*
G01X1699057Y105436D02*
X1693300Y111193D01*
G01X1704857Y105436D02*
X1699057D01*
G01X1716468Y93825D02*
X1704857Y105436D01*
G01X1705386Y108704D02*
X1713860Y100230D01*
G01X1700317Y108704D02*
X1705386D01*
G01X1693203Y115818D02*
X1700317Y108704D01*
G01X1676694Y115818D02*
X1693203D01*
G01X1674102Y118410D02*
X1676694Y115818D01*
G01X1665995Y118410D02*
X1674102D01*
G01X1664747Y117165D02*
X1665995Y118410D01*
G01X1663523Y117165D02*
X1664747D01*
G01X1662460Y118228D02*
X1663523Y117165D01*
G01X1662460Y119252D02*
Y118228D01*
G01X1661597Y120115D02*
X1662460Y119252D01*
G01X1660373Y120115D02*
X1661597D01*
G01X1660347Y120089D02*
X1660373Y120115D01*
G01X1659310Y121126D02*
X1660347Y120089D01*
G01X1659310Y122402D02*
Y121126D01*
G01X1658447Y123265D02*
X1659310Y122402D01*
G01X1657223Y123265D02*
X1658447D01*
G01X1656797Y122839D02*
X1657223Y123265D01*
G01X1655864Y122839D02*
X1656797D01*
G01X1655338Y123365D02*
X1655864Y122839D01*
G01X1654032Y123365D02*
X1655338D01*
G01X1653043Y122376D02*
X1654032Y123365D01*
G01X1653043Y121181D02*
Y122376D01*
G01X1652177Y120315D02*
X1653043Y121181D01*
G01X1650817Y120315D02*
X1652177D01*
G01X1652937Y119564D02*
X1650505D01*
G01X1653488Y120115D02*
X1652937Y119564D01*
G01X1658693Y120115D02*
X1653488D01*
G01X1659396Y119412D02*
X1658693Y120115D01*
G01X1659396Y118095D02*
Y119412D01*
G01X1660326Y117165D02*
X1659396Y118095D01*
G01X1661676Y117165D02*
X1660326D01*
G01X1662660Y116181D02*
X1661676Y117165D01*
G01X1662660Y114879D02*
Y116181D01*
G01X1663523Y114016D02*
X1662660Y114879D01*
G01X1667896Y114016D02*
X1663523D01*
G01X1668759Y114879D02*
X1667896Y114016D01*
G01X1668759Y116103D02*
Y114879D01*
G01X1669821Y117165D02*
X1668759Y116103D01*
G01X1673413Y117165D02*
X1669821D01*
G01X1675712Y114866D02*
X1673413Y117165D01*
G01X1692658Y114866D02*
X1675712D01*
G01X1700168Y107356D02*
X1692658Y114866D01*
G01X1705387Y107356D02*
X1700168D01*
G01X1713834Y98909D02*
X1705387Y107356D01*
G01X1657377Y106500D02*
X1651332D01*
G01X1658665Y105212D02*
X1657377Y106500D01*
G01X1664135Y105212D02*
X1658665D01*
G01X1664136Y105211D02*
X1664135Y105212D01*
G01X1664758Y105211D02*
X1664136D01*
G01X1667027Y107480D02*
X1664758Y105211D01*
G01X1678937Y107480D02*
X1667027D01*
G01X1678938Y107481D02*
X1678937Y107480D01*
G01X1691907Y107481D02*
X1678938D01*
G01X1697560Y101828D02*
X1691907Y107481D01*
G01X1703360Y101828D02*
X1697560D01*
G01X1668629Y144574D02*
X1715012D01*
G01X1667804Y145399D02*
X1668629Y144574D01*
G01X1650621Y145399D02*
X1667804D01*
G01X1697872Y102580D02*
X1703672D01*
G01X1692219Y108233D02*
X1697872Y102580D01*
G01X1678938Y108233D02*
X1692219D01*
G01X1678937Y108232D02*
X1678938Y108233D01*
G01X1678626Y108232D02*
X1678937D01*
G01X1678625Y108231D02*
X1678626Y108232D01*
G01X1666715Y108231D02*
X1678625D01*
G01X1664447Y105963D02*
X1666715Y108231D01*
G01X1658977Y105963D02*
X1664447D01*
G01X1656200Y108740D02*
X1658977Y105963D01*
G01X1656200Y109763D02*
Y108740D01*
G01X1655113Y110850D02*
X1656200Y109763D01*
G01X1653630Y110850D02*
X1655113D01*
G01X1652139Y112341D02*
X1653630Y110850D01*
G01X1651536Y112341D02*
X1652139D01*
G01X1684237Y101601D02*
X1686876Y98962D01*
G01X1679229Y101601D02*
X1684237D01*
G01X1679053Y101425D02*
X1679229Y101601D01*
G01X1671552Y101425D02*
X1679053D01*
G01X1670657Y100530D02*
X1671552Y101425D01*
G01X1667109Y100530D02*
X1670657D01*
G01X1666011Y101628D02*
X1667109Y100530D01*
G01X1657159Y101628D02*
X1666011D01*
G01X1652985Y97454D02*
X1657159Y101628D01*
G01X1652963Y97454D02*
X1652985D01*
G01X1652962Y97453D02*
X1652963Y97454D01*
G01X1652362Y97453D02*
X1652962D01*
G01X1652361Y97454D02*
X1652362Y97453D01*
G01X1653070Y155615D02*
Y160496D01*
G01X1652365Y154910D02*
X1653070Y155615D01*
G01X1708171Y147343D02*
X1713478Y152650D01*
G01X1674418Y147343D02*
X1708171D01*
G01X1666998Y154763D02*
X1674418Y147343D01*
G01X1654074Y154763D02*
X1666998D01*
G01X1651081Y151770D02*
X1654074Y154763D01*
G01X1657264Y105550D02*
X1650938D01*
G01X1658353Y104461D02*
X1657264Y105550D01*
G01X1663823Y104461D02*
X1658353D01*
G01X1663825Y104459D02*
X1663823Y104461D01*
G01X1664447Y104459D02*
X1663825D01*
G01X1664448Y104460D02*
X1664447Y104459D01*
G01X1665070Y104460D02*
X1664448D01*
G01X1667339Y106729D02*
X1665070Y104460D01*
G01X1691595Y106729D02*
X1667339D01*
G01X1697249Y101075D02*
X1691595Y106729D01*
G01X1700267Y101075D02*
X1697249D01*
G01X1700268Y101076D02*
X1700267Y101075D01*
G01X1703048Y101076D02*
X1700268D01*
G01X1710080Y153732D02*
X1743569D01*
G01X1704792Y148444D02*
X1710080Y153732D01*
G01X1683906Y148444D02*
X1704792D01*
G01X1674137Y158213D02*
X1683906Y148444D01*
G01X1654684Y115491D02*
X1651536D01*
G01X1656159Y114016D02*
X1654684Y115491D01*
G01X1658246Y114016D02*
X1656159D01*
G01X1659310Y112952D02*
X1658246Y114016D01*
G01X1659310Y111930D02*
Y112952D01*
G01X1660574Y110666D02*
X1659310Y111930D01*
G01X1661744Y110666D02*
X1660574D01*
G01X1662169Y110241D02*
X1661744Y110666D01*
G01X1663085Y110241D02*
X1662169D01*
G01X1663211Y110115D02*
X1663085Y110241D01*
G01X1669251Y110115D02*
X1663211D01*
G01X1669377Y110241D02*
X1669251Y110115D01*
G01X1692905Y110241D02*
X1669377D01*
G01X1698662Y104484D02*
X1692905Y110241D01*
G01X1704462Y104484D02*
X1698662D01*
G01X1715872Y93074D02*
X1704462Y104484D01*
G01X1657471Y100876D02*
X1653043Y96448D01*
G01X1665699Y100876D02*
X1657471D01*
G01X1667207Y99368D02*
X1665699Y100876D01*
G01X1677922Y99368D02*
X1667207D01*
G01X1679228Y100674D02*
X1677922Y99368D01*
G01X1679365Y100674D02*
X1679228D01*
G01X1679540Y100849D02*
X1679365Y100674D01*
G01X1680875Y100849D02*
X1679540D01*
G01X1681338Y100386D02*
X1680875Y100849D01*
G01X1681363Y100386D02*
X1681338D01*
G01X1681743Y100006D02*
X1681363Y100386D01*
G01X1681766Y100006D02*
X1681743D01*
G01X1684624Y97148D02*
X1681766Y100006D01*
G01X1688178Y97148D02*
X1684624D01*
G01X1689348Y98318D02*
X1688178Y97148D01*
G01X1689348Y98750D02*
Y98318D01*
G01X1689368Y98750D02*
X1689348D01*
G01X1708411Y146519D02*
X1713542Y151650D01*
G01X1673881Y146519D02*
X1708411D01*
G01X1668600Y151800D02*
X1673881Y146519D01*
G01X1652900Y151800D02*
X1668600D01*
G01X1662460Y120315D02*
X1664135Y118640D01*
G01X1662460Y122402D02*
Y120315D01*
G01X1661597Y123265D02*
X1662460Y122402D01*
G01X1660373Y123265D02*
X1661597D01*
G01X1659310Y124328D02*
X1660373Y123265D01*
G01X1659310Y125552D02*
Y124328D01*
G01X1658437Y126425D02*
X1659310Y125552D01*
G01X1654084Y126425D02*
X1658437D01*
G01X1653211Y125552D02*
X1654084Y126425D01*
G01X1653211Y124527D02*
Y125552D01*
G01X1652010Y123326D02*
X1653211Y124527D01*
G01X1684639Y156141D02*
X1678497Y162283D01*
G01X1694455Y157706D02*
X1692890Y156141D01*
G01X1685427Y150684D02*
X1675601Y160510D01*
G01X1704338Y150684D02*
X1685427D01*
G01X1709643Y155989D02*
X1704338Y150684D01*
G01X1713743Y155989D02*
X1709643D01*
G01X1662235Y94964D02*
X1677396D01*
G01X1677802Y95715D02*
X1661922D01*
G01X1692881Y96671D02*
X1691369D01*
G01X1694751Y94801D02*
X1692881Y96671D01*
G01X1695211Y94801D02*
X1694751D01*
G01X1695300Y94712D02*
X1695211Y94801D01*
G01X1653087Y118127D02*
X1650879D01*
G01X1654061Y117153D02*
X1653087Y118127D01*
G01X1656348Y117153D02*
X1654061D01*
G01X1657835Y118640D02*
X1656348Y117153D01*
G01X1666523Y148577D02*
X1651027D01*
G01X1669333Y145767D02*
X1666523Y148577D01*
G01X1708723Y145767D02*
X1669333D01*
G01X1713756Y150800D02*
X1708723Y145767D01*
G01X1705580Y155300D02*
X1707021Y156741D01*
G01X1695807Y155300D02*
X1705580D01*
G01X1693662Y153155D02*
X1695807Y155300D01*
G01X1684074Y153155D02*
X1693662D01*
G01X1675861Y161368D02*
X1684074Y153155D01*
G01X1692285Y94603D02*
X1692647D01*
G01X1692285Y94612D02*
Y94603D01*
G01X1693514Y154637D02*
X1695079Y156202D01*
G01X1683862Y154637D02*
X1693514D01*
G01X1676380Y162119D02*
X1683862Y154637D01*
G01X1684228Y155389D02*
X1676526Y163091D01*
G01X1693202Y155389D02*
X1684228D01*
G01X1694767Y156954D02*
X1693202Y155389D01*
G01X1658318Y167589D02*
X1650895D01*
G01X1659310Y166597D02*
X1658318Y167589D01*
G01X1659310Y164940D02*
Y166597D01*
G01X1660040Y164210D02*
X1659310Y164940D01*
G01X1662095Y164210D02*
X1660040D01*
G01X1666850Y159455D02*
X1662095Y164210D01*
G01X1675026Y159455D02*
X1666850D01*
G01X1654515Y173296D02*
X1653097Y174714D01*
G01X1662039Y173296D02*
X1654515D01*
G01X1669712Y165623D02*
X1662039Y173296D01*
G01X1677610Y165623D02*
X1669712D01*
G01X1685256Y157977D02*
X1677610Y165623D01*
G01X1685257Y157977D02*
X1685256D01*
G01X1685575Y157659D02*
X1685257Y157977D01*
G01X1692280Y157659D02*
X1685575D01*
G01X1693832Y159211D02*
X1692280Y157659D01*
G01X1696201Y159211D02*
X1693832D01*
G01X1700532Y163542D02*
X1696201Y159211D01*
G01X1704305Y163542D02*
X1700532D01*
G01X1706027Y161820D02*
X1704305Y163542D01*
G01X1710520Y161820D02*
X1706027D01*
G01X1712082Y163382D02*
X1710520Y161820D01*
G01X1774126Y163382D02*
X1712082D01*
G01X1655103Y174834D02*
X1653721Y176216D01*
G01X1665987Y174834D02*
X1655103D01*
G01X1666520Y174301D02*
X1665987Y174834D01*
G01X1668656Y174301D02*
X1666520D01*
G01X1669788Y173169D02*
X1668656Y174301D01*
G01X1669788Y168950D02*
Y173169D01*
G01X1671421Y167317D02*
X1669788Y168950D01*
G01X1678044Y167317D02*
X1671421D01*
G01X1686199Y159162D02*
X1678044Y167317D01*
G01X1691657Y159162D02*
X1686199D01*
G01X1693445Y160950D02*
X1691657Y159162D01*
G01X1695300Y160950D02*
X1693445D01*
G01X1699396Y165046D02*
X1695300Y160950D01*
G01X1704929Y165046D02*
X1699396D01*
G01X1706605Y163370D02*
X1704929Y165046D01*
G01X1709570Y163370D02*
X1706605D01*
G01X1711086Y164886D02*
X1709570Y163370D01*
G01X1777986Y164886D02*
X1711086D01*
G01X1651536Y162735D02*
X1650690D01*
G01X1710860Y160960D02*
X1712530Y162630D01*
G01X1706320Y160960D02*
X1710860D01*
G01X1703819Y158459D02*
X1706320Y160960D01*
G01X1694144Y158459D02*
X1703819D01*
G01X1692578Y156893D02*
X1694144Y158459D01*
G01X1684951Y156893D02*
X1692578D01*
G01X1677242Y164602D02*
X1684951Y156893D01*
G01X1669670Y164602D02*
X1677242D01*
G01X1661727Y172545D02*
X1669670Y164602D01*
G01X1654203Y172545D02*
X1661727D01*
G01X1652785Y173963D02*
X1654203Y172545D01*
G01X1694929Y166624D02*
X1712400D01*
G01X1691805Y163500D02*
X1694929Y166624D01*
G01X1683410Y163500D02*
X1691805D01*
G01X1678703Y168207D02*
X1683410Y163500D01*
G01X1672189Y168207D02*
X1678703D01*
G01X1670539Y169857D02*
X1672189Y168207D01*
G01X1670539Y172857D02*
Y169857D01*
G01X1670540Y172858D02*
X1670539Y172857D01*
G01X1670540Y173480D02*
Y172858D01*
G01X1668968Y175052D02*
X1670540Y173480D01*
G01X1666832Y175052D02*
X1668968D01*
G01X1666191Y175693D02*
X1666832Y175052D01*
G01X1655307Y175693D02*
X1666191D01*
G01X1654033Y176967D02*
X1655307Y175693D01*
G01X1654685Y162111D02*
Y162735D01*
G01X1653070Y160496D02*
X1654685Y162111D01*
G01X1666784Y158213D02*
X1674137D01*
G01X1663798Y161199D02*
X1666784Y158213D01*
G01X1660093Y161199D02*
X1663798D01*
G01X1659318Y161974D02*
X1660093Y161199D01*
G01X1659318Y163496D02*
Y161974D01*
G01X1658542Y164272D02*
X1659318Y163496D01*
G01X1653889Y164272D02*
X1658542D01*
G01X1653210Y163593D02*
X1653889Y164272D01*
G01X1653210Y162322D02*
Y163593D01*
G01X1652087Y161199D02*
X1653210Y162322D01*
G01X1650744Y161199D02*
X1652087D01*
G01X1669367Y163842D02*
X1661415Y171794D01*
G01X1676939Y163842D02*
X1669367D01*
G01X1678497Y162284D02*
X1676939Y163842D01*
G01X1678497Y162283D02*
Y162284D01*
G01X1692890Y156141D02*
X1684639D01*
G01X1704206Y157706D02*
X1694455D01*
G01X1706690Y160190D02*
X1704206Y157706D01*
G01X1711154Y160190D02*
X1706690D01*
G01X1712842Y161878D02*
X1711154Y160190D01*
G01X1660236Y168720D02*
X1650869D01*
G01X1662460Y166496D02*
X1660236Y168720D01*
G01X1662460Y165277D02*
Y166496D01*
G01X1667227Y160510D02*
X1662460Y165277D01*
G01X1675601Y160510D02*
X1667227D01*
G01X1707021Y156741D02*
X1758829D01*
G01X1668652Y161368D02*
X1675861D01*
G01X1660514Y169506D02*
X1668652Y161368D01*
G01X1650559Y169506D02*
X1660514D01*
G01X1711770Y164134D02*
X1779634D01*
G01X1710208Y162572D02*
X1711770Y164134D01*
G01X1706339Y162572D02*
X1710208D01*
G01X1704617Y164294D02*
X1706339Y162572D01*
G01X1699984Y164294D02*
X1704617D01*
G01X1695680Y159990D02*
X1699984Y164294D01*
G01X1677813Y166484D02*
X1685567Y158730D01*
G01X1670687Y166484D02*
X1677813D01*
G01X1666485Y170686D02*
X1670687Y166484D01*
G01X1666485Y171943D02*
Y170686D01*
G01X1666538Y171996D02*
X1666485Y171943D01*
G01X1666538Y173220D02*
Y171996D01*
G01X1665675Y174083D02*
X1666538Y173220D01*
G01X1654791Y174083D02*
X1665675D01*
G01X1653409Y175465D02*
X1654791Y174083D01*
G01X1706740Y157930D02*
X1752319D01*
G01X1705012Y156202D02*
X1706740Y157930D01*
G01X1695079Y156202D02*
X1705012D01*
G01X1668964Y162119D02*
X1676380D01*
G01X1660826Y170257D02*
X1668964Y162119D01*
G01X1655031Y184505D02*
X1654526Y184000D01*
G01X1669055Y163091D02*
X1661103Y171043D01*
G01X1676526Y163091D02*
X1669055D01*
G01X1704544Y156954D02*
X1694767D01*
G01X1706994Y159404D02*
X1704544Y156954D01*
G01X1711432Y159404D02*
X1706994D01*
G01X1713154Y161126D02*
X1711432Y159404D01*
G01X1656784Y177416D02*
X1652392Y181808D01*
G01X1666594Y177416D02*
X1656784D01*
G01X1667456Y176554D02*
X1666594Y177416D01*
G01X1671152Y176554D02*
X1667456D01*
G01X1673367Y174339D02*
X1671152Y176554D01*
G01X1675096Y174339D02*
X1673367D01*
G01X1676735Y172700D02*
X1675096Y174339D01*
G01X1677600Y172700D02*
X1676735D01*
G01X1655653Y176444D02*
X1651500Y180597D01*
G01X1666503Y176444D02*
X1655653D01*
G01X1667144Y175803D02*
X1666503Y176444D01*
G01X1670407Y175803D02*
X1667144D01*
G01X1673552Y172658D02*
X1670407Y175803D01*
G01X1674455Y172658D02*
X1673552D01*
G01X1661208Y241860D02*
X1658219D01*
G01X1661905Y241163D02*
X1661208Y241860D01*
G01X1665521Y241163D02*
X1661905D01*
G01X1666345Y241987D02*
X1665521Y241163D01*
G01X1682169Y247971D02*
X1684509Y245631D01*
G01X1678173Y247971D02*
X1682169D01*
G01X1670613Y240411D02*
X1678173Y247971D01*
G01X1661593Y240411D02*
X1670613D01*
G01X1660896Y241108D02*
X1661593Y240411D01*
G01X1657907Y241108D02*
X1660896D01*
G01X1677544Y252953D02*
X1774429D01*
G01X1674933Y250342D02*
X1677544Y252953D01*
G01X1667381Y250342D02*
X1674933D01*
G01X1667380Y250341D02*
X1667381Y250342D01*
G01X1666134Y250341D02*
X1667380D01*
G01X1663488Y252987D02*
X1666134Y250341D01*
G01X1656080Y252987D02*
X1663488D01*
G01X1662956Y245972D02*
Y243582D01*
G01X1662000Y246928D02*
X1662956Y245972D01*
G01X1656343Y246928D02*
X1662000D01*
G01X1663275Y252136D02*
X1655391D01*
G01X1665822Y249589D02*
X1663275Y252136D01*
G01X1675447Y249589D02*
X1665822D01*
G01X1678059Y252201D02*
X1675447Y249589D01*
G01X1687382Y252201D02*
X1678059D01*
G01X1688451Y251132D02*
X1687382Y252201D01*
G01X1688451Y249716D02*
Y251132D01*
G01X1661186Y245352D02*
X1656855D01*
G01X1676512Y255209D02*
X1830992D01*
G01X1673901Y252598D02*
X1676512Y255209D01*
G01X1667069Y252598D02*
X1673901D01*
G01X1662022Y257645D02*
X1667069Y252598D01*
G01X1662022Y290587D02*
Y257645D01*
G01X1676262Y273900D02*
X1679100D01*
G01X1671904Y278258D02*
X1676262Y273900D01*
G01X1671904Y371227D02*
Y278258D01*
G01X1671043Y256644D02*
X1670140Y257547D01*
G01X1675819Y256644D02*
X1671043D01*
G01X1675888Y256713D02*
X1675819Y256644D01*
G01X1835056Y256713D02*
X1675888D01*
G01X1663800Y253739D02*
X1656392D01*
G01X1666446Y251093D02*
X1663800Y253739D01*
G01X1667068Y251093D02*
X1666446D01*
G01X1667069Y251094D02*
X1667068Y251093D01*
G01X1674525Y251094D02*
X1667069D01*
G01X1677136Y253705D02*
X1674525Y251094D01*
G01X1774741Y253705D02*
X1677136D01*
G01X1670952Y277863D02*
Y412695D01*
G01X1677515Y271300D02*
X1670952Y277863D01*
G01X1679100Y271300D02*
X1677515D01*
G01X1672023Y255892D02*
X1670822Y254691D01*
G01X1676131Y255892D02*
X1672023D01*
G01X1676200Y255961D02*
X1676131Y255892D01*
G01X1834744Y255961D02*
X1676200D01*
G01X1663894Y248432D02*
X1656967D01*
G01X1664324Y248002D02*
X1663894Y248432D01*
G01X1664861Y245139D02*
X1666329D01*
G01X1662320Y247680D02*
X1664861Y245139D01*
G01X1656655Y247680D02*
X1662320D01*
G01X1673330Y282170D02*
X1679100Y276400D01*
G01X1664015Y254588D02*
X1658087D01*
G01X1666757Y251846D02*
X1664015Y254588D01*
G01X1674213Y251846D02*
X1666757D01*
G01X1676824Y254457D02*
X1674213Y251846D01*
G01X1800179Y254457D02*
X1676824D01*
G01X1673129Y257865D02*
X1857665D01*
G01X1671666Y259328D02*
X1673129Y257865D01*
G01X1669329Y259328D02*
X1671666D01*
G01X1667921Y257920D02*
X1669329Y259328D01*
G01X1667667Y257920D02*
X1667921D01*
G01X1690565Y249456D02*
Y251052D01*
G01X1685305Y244196D02*
X1690565Y249456D01*
G01X1685305Y241317D02*
Y244196D01*
G01X1684758Y240770D02*
X1685305Y241317D01*
G01X1679103Y240770D02*
X1684758D01*
G01X1677992Y239659D02*
X1679103Y240770D01*
G01X1661281Y239659D02*
X1677992D01*
G01X1660584Y240356D02*
X1661281Y239659D01*
G01X1657595Y240356D02*
X1660584D01*
G01X1662000Y250008D02*
X1656455D01*
G01X1667099Y260480D02*
X1666968Y260611D01*
G01X1672144Y260480D02*
X1667099D01*
G01X1673607Y259017D02*
X1672144Y260480D01*
G01X1859113Y259017D02*
X1673607D01*
G01X1674082Y283942D02*
X1679100Y278924D01*
G01X1684232Y248723D02*
X1686113Y250604D01*
G01X1677861Y248723D02*
X1684232D01*
G01X1672701Y243563D02*
X1677861Y248723D01*
G01X1665692Y243563D02*
X1672701D01*
G01X1664044Y241915D02*
X1665692Y243563D01*
G01X1662217Y241915D02*
X1664044D01*
G01X1661520Y242612D02*
X1662217Y241915D01*
G01X1658531Y242612D02*
X1661520D01*
G01X1676020Y287173D02*
X1679100Y284093D01*
G01X1676020Y306877D02*
Y287173D01*
G01X1678399Y309256D02*
X1676020Y306877D01*
G01X1678399Y432544D02*
Y309256D01*
G01X1652600Y300009D02*
X1662022Y290587D01*
G01X1652600Y315400D02*
Y300009D01*
G01X1655524Y318324D02*
X1652600Y315400D01*
G01X1655524Y324067D02*
Y318324D01*
G01X1653091Y326500D02*
X1655524Y324067D01*
G01X1655005Y328414D02*
Y377485D01*
G01X1653091Y326500D02*
X1655005Y328414D01*
G01X1674834Y285859D02*
X1679100Y281593D01*
G01X1674834Y423804D02*
Y285859D01*
G01X1673330Y420035D02*
Y282170D01*
G01X1676772Y288921D02*
X1679100Y286593D01*
G01X1676772Y305665D02*
Y288921D01*
G01X1679151Y308044D02*
X1676772Y305665D01*
G01X1679151Y432232D02*
Y308044D01*
G01X1677524Y291076D02*
X1679100Y289500D01*
G01X1677524Y305353D02*
Y291076D01*
G01X1679903Y307732D02*
X1677524Y305353D01*
G01X1679903Y431549D02*
Y307732D01*
G01X1674082Y423492D02*
Y283942D01*
G01X1660495Y392195D02*
X1661243Y392943D01*
G01X1659196Y392195D02*
X1660495D01*
G01X1660890Y397300D02*
Y395070D01*
G01X1662900Y400200D02*
Y405099D01*
G01X1662000Y399300D02*
X1662900Y400200D01*
G01Y398400D02*
X1662000Y399300D01*
G01X1662900Y385380D02*
Y398400D01*
G01X1655005Y377485D02*
X1662900Y385380D01*
G01X1659200Y397980D02*
Y394650D01*
G01X1660520Y399300D02*
X1659200Y397980D01*
G01X1662000Y399300D02*
X1660520D01*
G01X1671905Y371228D02*
X1671904Y371227D01*
G01X1671905Y372016D02*
Y371228D01*
G01X1671904Y372017D02*
X1671905Y372016D01*
G01X1671904Y408832D02*
Y372017D01*
G01X1651361Y353875D02*
X1652186Y354700D01*
G01X1651361Y352925D02*
X1652186Y352100D01*
G01X1650679Y352925D02*
X1651361D01*
G01X1653354Y403100D02*
X1654809Y401645D01*
G01X1660613Y390994D02*
X1661243Y390364D01*
G01X1659342Y390994D02*
X1660613D01*
G01X1654861Y396637D02*
X1654398Y397100D01*
G01X1703194Y471141D02*
X1716006Y458329D01*
G01X1683412Y462512D02*
Y465171D01*
G01X1678953Y458053D02*
X1683412Y462512D01*
G01X1678953Y452443D02*
Y458053D01*
G01X1676304Y449794D02*
X1678953Y452443D01*
G01X1666413Y412987D02*
X1667946D01*
G01X1684833Y456832D02*
X1684435D01*
G01X1685775Y457725D02*
X1684833Y456832D01*
G01X1686761Y457725D02*
X1685775D01*
G01X1695286Y466250D02*
X1686761Y457725D01*
G01X1710500Y458950D02*
X1703200Y466250D01*
G01X1710500Y452100D02*
Y458950D01*
G01X1715450Y447150D02*
X1710500Y452100D01*
G01X1682603Y436748D02*
X1678399Y432544D01*
G01X1850570Y436748D02*
X1682603D01*
G01X1684843Y459421D02*
X1684435D01*
G01X1685672Y458675D02*
X1684843Y459421D01*
G01X1686647Y458675D02*
X1685672D01*
G01X1694974Y467002D02*
X1686647Y458675D01*
G01X1711450Y459344D02*
X1703594Y467200D01*
G01X1711450Y452494D02*
Y459344D01*
G01X1715844Y448100D02*
X1711450Y452494D01*
G01X1662900Y405099D02*
X1657757Y410242D01*
G01X1671915Y408843D02*
X1671904Y408832D01*
G01X1671915Y418190D02*
Y408843D01*
G01X1669733Y420372D02*
X1671915Y418190D01*
G01X1662789Y420372D02*
X1669733D01*
G01X1654771Y428390D02*
X1662789Y420372D01*
G01X1654771Y460806D02*
Y428390D01*
G01X1657900Y463935D02*
X1654771Y460806D01*
G01X1657900Y478401D02*
Y463935D01*
G01X1671109Y427529D02*
X1674834Y423804D01*
G01X1671109Y434578D02*
Y427529D01*
G01X1668980Y436707D02*
X1671109Y434578D01*
G01X1665966Y436707D02*
X1668980D01*
G01X1665199Y435940D02*
X1665966Y436707D01*
G01X1661641Y435940D02*
X1665199D01*
G01X1659700Y437881D02*
X1661641Y435940D01*
G01X1659700Y459441D02*
Y437881D01*
G01X1660104Y459845D02*
X1659700Y459441D01*
G01X1668025Y459845D02*
X1660104D01*
G01X1668026Y459844D02*
X1668025Y459845D01*
G01X1669272Y459844D02*
X1668026D01*
G01X1669273Y459845D02*
X1669272Y459844D01*
G01X1670313Y459845D02*
X1669273D01*
G01X1684266Y473798D02*
X1670313Y459845D01*
G01X1653819Y427869D02*
Y474622D01*
G01X1667125Y414563D02*
X1653819Y427869D01*
G01X1669084Y414563D02*
X1667125D01*
G01X1670952Y412695D02*
X1669084Y414563D01*
G01X1660834Y404934D02*
X1656439Y409329D01*
G01X1673579Y442667D02*
X1673550Y442696D01*
G01X1675469Y442667D02*
X1673579D01*
G01X1679822Y447020D02*
X1675469Y442667D01*
G01X1682020Y447020D02*
X1679822D01*
G01X1683500Y448500D02*
X1682020Y447020D01*
G01X1683500Y455538D02*
Y448500D01*
G01X1682604Y456434D02*
X1683500Y455538D01*
G01X1682604Y460074D02*
Y456434D01*
G01X1686585Y464055D02*
X1682604Y460074D01*
G01X1689516Y464055D02*
X1686585D01*
G01X1693813Y468352D02*
X1689516Y464055D01*
G01X1715529Y457176D02*
X1704353Y468352D01*
G01X1670399Y422966D02*
X1673330Y420035D01*
G01X1664487Y422966D02*
X1670399D01*
G01X1657200Y430253D02*
X1664487Y422966D01*
G01X1657200Y459069D02*
Y430253D01*
G01X1659480Y461349D02*
X1657200Y459069D01*
G01X1668991Y461349D02*
X1659480D01*
G01X1671803Y464161D02*
X1668991Y461349D01*
G01X1671803Y469698D02*
Y464161D01*
G01X1673074Y460976D02*
X1684743Y472645D01*
G01X1673074Y453185D02*
Y460976D01*
G01X1682445Y435526D02*
X1679151Y432232D01*
G01X1853405Y435526D02*
X1682445D01*
G01X1703789Y471893D02*
X1716401Y459281D01*
G01X1682367Y462835D02*
Y465190D01*
G01X1678201Y458669D02*
X1682367Y462835D01*
G01X1678201Y453498D02*
Y458669D01*
G01X1676073Y451370D02*
X1678201Y453498D01*
G01X1675651Y451370D02*
X1676073D01*
G01X1674728Y450447D02*
X1675651Y451370D01*
G01X1674728Y449092D02*
Y450447D01*
G01X1676287Y447533D02*
X1674728Y449092D01*
G01X1676287Y447244D02*
Y447533D01*
G01X1682928Y434574D02*
X1679903Y431549D01*
G01X1853800Y434574D02*
X1682928D01*
G01X1670357Y427217D02*
X1674082Y423492D01*
G01X1670357Y434266D02*
Y427217D01*
G01X1668668Y435955D02*
X1670357Y434266D01*
G01X1666278Y435955D02*
X1668668D01*
G01X1665511Y435188D02*
X1666278Y435955D01*
G01X1660632Y435188D02*
X1665511D01*
G01X1658500Y437320D02*
X1660632Y435188D01*
G01X1658500Y459305D02*
Y437320D01*
G01X1659792Y460597D02*
X1658500Y459305D01*
G01X1668337Y460597D02*
X1659792D01*
G01X1668338Y460596D02*
X1668337Y460597D01*
G01X1668960Y460596D02*
X1668338D01*
G01X1668961Y460597D02*
X1668960Y460596D01*
G01X1669303Y460597D02*
X1668961D01*
G01X1672555Y463849D02*
X1669303Y460597D01*
G01X1672555Y470010D02*
Y463849D01*
G01X1672265Y472638D02*
Y473600D01*
G01X1675659Y469244D02*
X1672265Y472638D01*
G01X1678648Y469244D02*
X1675659D01*
G01X1683954Y474550D02*
X1678648Y469244D01*
G01X1685532Y474550D02*
X1683954D01*
G01X1685533Y474549D02*
X1685532Y474550D01*
G01X1707821Y474549D02*
X1685533D01*
G01X1720022Y462348D02*
X1707821Y474549D01*
G01X1689382Y471141D02*
X1703194D01*
G01X1683412Y465171D02*
X1689382Y471141D01*
G01X1703200Y466250D02*
X1695286D01*
G01X1695250Y467002D02*
X1694974D01*
G01X1695448Y467200D02*
X1695250Y467002D01*
G01X1703594Y467200D02*
X1695448D01*
G01X1656311Y479990D02*
X1657900Y478401D01*
G01X1685220Y473798D02*
X1684266D01*
G01X1685221Y473797D02*
X1685220Y473798D01*
G01X1707509Y473797D02*
X1685221D01*
G01X1719711Y461595D02*
X1707509Y473797D01*
G01X1653819Y474622D02*
X1655790Y476593D01*
G01X1704353Y468352D02*
X1693813D01*
G01X1669937Y471564D02*
X1671803Y469698D01*
G01X1669937Y474853D02*
Y471564D01*
G01X1671137Y476053D02*
X1669937Y474853D01*
G01X1683329Y476053D02*
X1671137D01*
G01X1683330Y476054D02*
X1683329Y476053D01*
G01X1686156Y476054D02*
X1683330D01*
G01X1686157Y476053D02*
X1686156Y476054D01*
G01X1709577Y476053D02*
X1686157D01*
G01X1720585Y465045D02*
X1709577Y476053D01*
G01X1707031Y472645D02*
X1719233Y460443D01*
G01X1684743Y472645D02*
X1707031D01*
G01X1689070Y471893D02*
X1703789D01*
G01X1682367Y465190D02*
X1689070Y471893D01*
G01X1670689Y471876D02*
X1672555Y470010D01*
G01X1670689Y474541D02*
Y471876D01*
G01X1671449Y475301D02*
X1670689Y474541D01*
G01X1683641Y475301D02*
X1671449D01*
G01X1683642Y475302D02*
X1683641Y475301D01*
G01X1685844Y475302D02*
X1683642D01*
G01X1685845Y475301D02*
X1685844Y475302D01*
G01X1708699Y475301D02*
X1685845D01*
G01X1720500Y463500D02*
X1708699Y475301D01*
G01X1710064Y555726D02*
X1715854Y549936D01*
G01X1657365Y555726D02*
X1710064D01*
G01X1654890Y553251D02*
X1657365Y555726D01*
G01X1653678Y574024D02*
X1650512D01*
G01X1654930Y575276D02*
X1653678Y574024D01*
G01X1735500Y575276D02*
X1654930D01*
G01X1726000Y559182D02*
X1653849D01*
G01X1655083Y573653D02*
X1736000D01*
G01X1654202Y572772D02*
X1655083Y573653D01*
G01X1650681Y563980D02*
Y568389D01*
G01X1654327Y560334D02*
X1650681Y563980D01*
G01X1712334Y560334D02*
X1654327D01*
G01X1716204Y551216D02*
X1710542Y556878D01*
G01X1668565Y604655D02*
X1654478Y618742D01*
G01X1704630Y604655D02*
X1668565D01*
G01X1707709Y601576D02*
X1704630Y604655D01*
G01X1744340Y601576D02*
X1707709D01*
G01X1700710Y608210D02*
X1737780D01*
G01X1698020Y610900D02*
X1700710Y608210D01*
G01X1698020Y615089D02*
Y610900D01*
G01X1691963Y621146D02*
X1698020Y615089D01*
G01X1696615Y614723D02*
X1691444Y619894D01*
G01X1696615Y610444D02*
Y614723D01*
G01X1697377Y609682D02*
X1696615Y610444D01*
G01X1697377Y609652D02*
Y609682D01*
G01X1700176Y606853D02*
X1697377Y609652D01*
G01X1740572Y606853D02*
X1700176D01*
G01X1791500Y22087D02*
X1772099Y2686D01*
G01X1764543Y25786D02*
X1779447Y40690D01*
G01X1762624Y25786D02*
X1764543D01*
G01X1759153Y22315D02*
X1762624Y25786D01*
G01X1756637Y22315D02*
X1759153D01*
G01X1755175Y20853D02*
X1756637Y22315D01*
G01X1755175Y14215D02*
Y20853D01*
G01X1759093Y10297D02*
X1755175Y14215D01*
G01X1759093Y9310D02*
Y10297D01*
G01X1789772Y21706D02*
X1771704Y3638D01*
G01X1788759Y22040D02*
X1771309Y4590D01*
G01X1738824Y15176D02*
X1744900Y9100D01*
G01X1770032Y5542D02*
X1786865Y22375D01*
G01X1763186Y28424D02*
X1761035Y26273D01*
G01X1764352Y28424D02*
X1763186D01*
G01X1764353Y28423D02*
X1764352Y28424D01*
G01X1765041Y28423D02*
X1764353D01*
G01X1779018Y42400D02*
X1765041Y28423D01*
G01X1762708Y29576D02*
X1760685Y27553D01*
G01X1764453Y29576D02*
X1762708D01*
G01X1778687Y43810D02*
X1764453Y29576D01*
G01X1779750Y27455D02*
X1758789Y6494D01*
G01X1751935Y60801D02*
X1748744Y63992D01*
G01X1767657Y60801D02*
X1751935D01*
G01X1774828Y67972D02*
X1767657Y60801D01*
G01X1749681Y86324D02*
X1759538Y96181D01*
G01X1713247Y86324D02*
X1749681D01*
G01X1712324Y87247D02*
X1713247Y86324D01*
G01X1712324Y90029D02*
Y87247D01*
G01X1740841Y92530D02*
X1737746Y95625D01*
G01X1746655Y92530D02*
X1740841D01*
G01X1751365Y97240D02*
X1746655Y92530D01*
G01X1770323Y92441D02*
X1786456Y108574D01*
G01X1769309Y92441D02*
X1770323D01*
G01X1767250Y94500D02*
X1769309Y92441D01*
G01X1736837Y76867D02*
X1732202Y81502D01*
G01X1752857Y76867D02*
X1736837D01*
G01X1756963Y80973D02*
X1752857Y76867D01*
G01X1760558Y80973D02*
X1756963D01*
G01X1763546Y83961D02*
X1760558Y80973D01*
G01X1763546Y90446D02*
Y83961D01*
G01X1765635Y92535D02*
X1763546Y90446D01*
G01X1766898Y92535D02*
X1765635D01*
G01X1767250Y92887D02*
X1766898Y92535D01*
G01X1767250Y94500D02*
Y92887D01*
G01X1735721Y75340D02*
X1731063Y79998D01*
G01X1753861Y75340D02*
X1735721D01*
G01X1757369Y78848D02*
X1753861Y75340D01*
G01X1765112Y78848D02*
X1757369D01*
G01X1768500Y82236D02*
X1765112Y78848D01*
G01X1768500Y88436D02*
Y82236D01*
G01X1786964Y106900D02*
X1768500Y88436D01*
G01X1761290Y93561D02*
X1765553Y97824D01*
G01X1761290Y88211D02*
Y93561D01*
G01X1760233Y87154D02*
X1761290Y88211D01*
G01X1754639Y87154D02*
X1760233D01*
G01X1751305Y83820D02*
X1754639Y87154D01*
G01X1712140Y83820D02*
X1751305D01*
G01X1732231Y51168D02*
X1723619Y59780D01*
G01X1766920Y51168D02*
X1732231D01*
G01X1780900Y65148D02*
X1766920Y51168D01*
G01X1750387Y85072D02*
X1760790Y95475D01*
G01X1712728Y85072D02*
X1750387D01*
G01X1748835Y41183D02*
X1746552Y38900D01*
G01X1771459Y41183D02*
X1748835D01*
G01X1788216Y57940D02*
X1771459Y41183D01*
G01X1737460Y55840D02*
X1735150Y58150D01*
G01X1765426Y55840D02*
X1737460D01*
G01X1776362Y66776D02*
X1765426Y55840D01*
G01X1747346Y90032D02*
X1755052Y97738D01*
G01X1720593Y90032D02*
X1747346D01*
G01X1718804Y91821D02*
X1720593Y90032D01*
G01X1715778Y91821D02*
X1718804D01*
G01X1723328Y93825D02*
X1716468D01*
G01X1724377Y94874D02*
X1723328Y93825D01*
G01X1740529Y91779D02*
X1737434Y94874D01*
G01X1746967Y91779D02*
X1740529D01*
G01X1752516Y97328D02*
X1746967Y91779D01*
G01X1765471Y54000D02*
X1777700Y66229D01*
G01X1734571Y54000D02*
X1765471D01*
G01X1725871Y62700D02*
X1734571Y54000D01*
G01X1741153Y93281D02*
X1738058Y96376D01*
G01X1746343Y93281D02*
X1741153D01*
G01X1750614Y97552D02*
X1746343Y93281D01*
G01X1717896Y90318D02*
X1714870D01*
G01X1719886Y88328D02*
X1717896Y90318D01*
G01X1748548Y88328D02*
X1719886D01*
G01X1757534Y97314D02*
X1748548Y88328D01*
G01X1753388Y63148D02*
X1750288Y66248D01*
G01X1766460Y63148D02*
X1753388D01*
G01X1772572Y69260D02*
X1766460Y63148D01*
G01X1772572Y71661D02*
Y69260D01*
G01X1782582Y81671D02*
X1772572Y71661D01*
G01X1748236Y89080D02*
X1756782Y97626D01*
G01X1720198Y89080D02*
X1748236D01*
G01X1718208Y91070D02*
X1720198Y89080D01*
G01X1715182Y91070D02*
X1718208D01*
G01X1769750Y73439D02*
X1782000Y85689D01*
G01X1766592Y73439D02*
X1769750D01*
G01X1762958Y69805D02*
X1766592Y73439D01*
G01X1730364Y69805D02*
X1762958D01*
G01X1726826Y73343D02*
X1730364Y69805D01*
G01X1733578Y52520D02*
X1724798Y61300D01*
G01X1766262Y52520D02*
X1733578D01*
G01X1779300Y65558D02*
X1766262Y52520D01*
G01X1771819Y71972D02*
X1782270Y82423D01*
G01X1771819Y69571D02*
Y71972D01*
G01X1766148Y63900D02*
X1771819Y69571D01*
G01X1753700Y63900D02*
X1766148D01*
G01X1750600Y67000D02*
X1753700Y63900D01*
G01X1735409Y74588D02*
X1730751Y79246D01*
G01X1754173Y74588D02*
X1735409D01*
G01X1757681Y78096D02*
X1754173Y74588D01*
G01X1764800Y78096D02*
X1757681D01*
G01X1764801Y78095D02*
X1764800Y78096D01*
G01X1765423Y78095D02*
X1764801D01*
G01X1769400Y82072D02*
X1765423Y78095D01*
G01X1769400Y88272D02*
Y82072D01*
G01X1787228Y106100D02*
X1769400Y88272D01*
G01X1769355Y74391D02*
X1781000Y86036D01*
G01X1765973Y74391D02*
X1769355D01*
G01X1762139Y70557D02*
X1765973Y74391D01*
G01X1730959Y70557D02*
X1762139D01*
G01X1727420Y74096D02*
X1730959Y70557D01*
G01X1717584Y89566D02*
X1714558D01*
G01X1719574Y87576D02*
X1717584Y89566D01*
G01X1748860Y87576D02*
X1719574D01*
G01X1758286Y97002D02*
X1748860Y87576D01*
G01X1723640Y93074D02*
X1715872D01*
G01X1724689Y94123D02*
X1723640Y93074D01*
G01X1737122Y94123D02*
X1724689D01*
G01X1740217Y91028D02*
X1737122Y94123D01*
G01X1747279Y91028D02*
X1740217D01*
G01X1754100Y97849D02*
X1747279Y91028D01*
G01X1752247Y61553D02*
X1749056Y64744D01*
G01X1766993Y61553D02*
X1752247D01*
G01X1774076Y68636D02*
X1766993Y61553D01*
G01X1767733Y44004D02*
X1782500Y58771D01*
G01X1762794Y92406D02*
X1766464Y96076D01*
G01X1762794Y84273D02*
Y92406D01*
G01X1760246Y81725D02*
X1762794Y84273D01*
G01X1752967Y81725D02*
X1760246D01*
G01X1752438Y82254D02*
X1752967Y81725D01*
G01X1770599Y91633D02*
X1786788Y107822D01*
G01X1769383Y91633D02*
X1770599D01*
G01X1767250Y89500D02*
X1769383Y91633D01*
G01X1736525Y76115D02*
X1731890Y80750D01*
G01X1753169Y76115D02*
X1736525D01*
G01X1757275Y80221D02*
X1753169Y76115D01*
G01X1760870Y80221D02*
X1757275D01*
G01X1764298Y83649D02*
X1760870Y80221D01*
G01X1764298Y90099D02*
Y83649D01*
G01X1765782Y91583D02*
X1764298Y90099D01*
G01X1766897Y91583D02*
X1765782D01*
G01X1767250Y91230D02*
X1766897Y91583D01*
G01X1767250Y89500D02*
Y91230D01*
G01X1762042Y92718D02*
X1766152Y96828D01*
G01X1762042Y84585D02*
Y92718D01*
G01X1759934Y82477D02*
X1762042Y84585D01*
G01X1753279Y82477D02*
X1759934D01*
G01X1752750Y83006D02*
X1753279Y82477D01*
G01X1732797Y71309D02*
X1729058Y75048D01*
G01X1761337Y71309D02*
X1732797D01*
G01X1765600Y75572D02*
X1761337Y71309D01*
G01X1769466Y75572D02*
X1765600D01*
G01X1775440Y81546D02*
X1769466Y75572D01*
G01X1731117Y49712D02*
X1722201Y58628D01*
G01X1731400Y49712D02*
X1731117D01*
G01X1731401Y49711D02*
X1731400Y49712D01*
G01X1732355Y49711D02*
X1731401D01*
G01X1732356Y49712D02*
X1732355Y49711D01*
G01X1742488Y49712D02*
X1732356D01*
G01X1745094Y47106D02*
X1742488Y49712D01*
G01X1734074Y72061D02*
X1730335Y75800D01*
G01X1759253Y72061D02*
X1734074D01*
G01X1764535Y77343D02*
X1759253Y72061D01*
G01X1765735Y77343D02*
X1764535D01*
G01X1774500Y86108D02*
X1765735Y77343D01*
G01X1752559Y62305D02*
X1749368Y65496D01*
G01X1766681Y62305D02*
X1752559D01*
G01X1773324Y68948D02*
X1766681Y62305D01*
G01X1773324Y71349D02*
Y68948D01*
G01X1782894Y80919D02*
X1773324Y71349D01*
G01X1765496Y145448D02*
X1756107Y154837D01*
G01X1801715Y145448D02*
X1765496D01*
G01X1769124Y102527D02*
X1781865Y115268D01*
G01X1765300Y102527D02*
X1769124D01*
G01X1759538Y96765D02*
X1765300Y102527D01*
G01X1759538Y96181D02*
Y96765D01*
G01X1713043Y98313D02*
Y98314D01*
G01X1716684Y94672D02*
X1713043Y98313D01*
G01X1723112Y94672D02*
X1716684D01*
G01X1724065Y95625D02*
X1723112Y94672D01*
G01X1737746Y95625D02*
X1724065D01*
G01X1751365Y114862D02*
Y97240D01*
G01X1757950Y121447D02*
X1751365Y114862D01*
G01X1768844Y121447D02*
X1757950D01*
G01X1782657Y135260D02*
X1768844Y121447D01*
G01X1769408Y119150D02*
X1781309Y131051D01*
G01X1765065Y119150D02*
X1769408D01*
G01X1765015Y119100D02*
X1765065Y119150D01*
G01X1768719Y97824D02*
X1783195Y112300D01*
G01X1765553Y97824D02*
X1768719D01*
G01X1769643Y101275D02*
X1782228Y113860D01*
G01X1765819Y101275D02*
X1769643D01*
G01X1760790Y96246D02*
X1765819Y101275D01*
G01X1760790Y95475D02*
Y96246D01*
G01X1755052Y101399D02*
X1779429Y125776D01*
G01X1755052Y97738D02*
Y101399D01*
G01X1737434Y94874D02*
X1724377D01*
G01X1752516Y111236D02*
Y97328D01*
G01X1757247Y115967D02*
X1752516Y111236D01*
G01X1760679Y115967D02*
X1757247D01*
G01X1763305Y118593D02*
X1760679Y115967D01*
G01X1763305Y119785D02*
Y118593D01*
G01X1764215Y120695D02*
X1763305Y119785D01*
G01X1769323Y120695D02*
X1764215D01*
G01X1782831Y134203D02*
X1769323Y120695D01*
G01X1769120Y125480D02*
X1780930Y137290D01*
G01X1756943Y125480D02*
X1769120D01*
G01X1755907Y124444D02*
X1756943Y125480D01*
G01X1755907Y122009D02*
Y124444D01*
G01X1749174Y115276D02*
X1755907Y122009D01*
G01X1749174Y104327D02*
Y115276D01*
G01X1745077Y100230D02*
X1749174Y104327D01*
G01X1713860Y100230D02*
X1745077D01*
G01X1713834Y98585D02*
Y98909D01*
G01X1716996Y95423D02*
X1713834Y98585D01*
G01X1722800Y95423D02*
X1716996D01*
G01X1723753Y96376D02*
X1722800Y95423D01*
G01X1738058Y96376D02*
X1723753D01*
G01X1750614Y115373D02*
Y97552D01*
G01X1757587Y122346D02*
X1750614Y115373D01*
G01X1767897Y122346D02*
X1757587D01*
G01X1781811Y136260D02*
X1767897Y122346D01*
G01X1757534Y100206D02*
Y97314D01*
G01X1771302Y113974D02*
X1757534Y100206D01*
G01X1777736Y113974D02*
X1771302D01*
G01X1761165Y138460D02*
X1805276D01*
G01X1755281Y144344D02*
X1761165Y138460D01*
G01X1752467Y144344D02*
X1755281D01*
G01X1749271Y147540D02*
X1752467Y144344D01*
G01X1734060Y147540D02*
X1749271D01*
G01X1733021Y148579D02*
X1734060Y147540D01*
G01X1719017Y148579D02*
X1733021D01*
G01X1715012Y144574D02*
X1719017Y148579D01*
G01X1756782Y100518D02*
X1774488Y118224D01*
G01X1756782Y97626D02*
Y100518D01*
G01X1761740Y142020D02*
X1796126D01*
G01X1753460Y150300D02*
X1761740Y142020D01*
G01X1745365Y150300D02*
X1753460D01*
G01X1743015Y152650D02*
X1745365Y150300D01*
G01X1713478Y152650D02*
X1743015D01*
G01X1758286Y99894D02*
Y97002D01*
G01X1771614Y113222D02*
X1758286Y99894D01*
G01X1778048Y113222D02*
X1771614D01*
G01X1765958Y143100D02*
X1796110D01*
G01X1756838Y152220D02*
X1765958Y143100D01*
G01X1748494Y152220D02*
X1756838D01*
G01X1747911Y151637D02*
X1748494Y152220D01*
G01X1745664Y151637D02*
X1747911D01*
G01X1743569Y153732D02*
X1745664Y151637D01*
G01X1754100Y101794D02*
Y97849D01*
G01X1779034Y126728D02*
X1754100Y101794D01*
G01X1761309Y141152D02*
X1795930D01*
G01X1753098Y149363D02*
X1761309Y141152D01*
G01X1745239Y149363D02*
X1753098D01*
G01X1742952Y151650D02*
X1745239Y149363D01*
G01X1713542Y151650D02*
X1742952D01*
G01X1713744Y155990D02*
X1713743Y155989D01*
G01X1756978Y155990D02*
X1713744D01*
G01X1766368Y146600D02*
X1756978Y155990D01*
G01X1801237Y146600D02*
X1766368D01*
G01X1772625Y96188D02*
X1785763Y109326D01*
G01X1769786Y96188D02*
X1772625D01*
G01X1769674Y96076D02*
X1769786Y96188D01*
G01X1766464Y96076D02*
X1769674D01*
G01X1742739Y150800D02*
X1713756D01*
G01X1745090Y148449D02*
X1742739Y150800D01*
G01X1752891Y148449D02*
X1745090D01*
G01X1761439Y139901D02*
X1752891Y148449D01*
G01X1805087Y139901D02*
X1761439D01*
G01X1767330Y148240D02*
X1800420D01*
G01X1758829Y156741D02*
X1767330Y148240D01*
G01X1768794Y96828D02*
X1783397Y111431D01*
G01X1766152Y96828D02*
X1768794D01*
G01X1773814Y162630D02*
X1775346Y161098D01*
G01X1712530Y162630D02*
X1773814D01*
G01X1713386Y165638D02*
X1775538D01*
G01X1712400Y166624D02*
X1713386Y165638D01*
G01X1773502Y161878D02*
X1712842D01*
G01X1776300Y159080D02*
X1773502Y161878D01*
G01X1773019Y160233D02*
X1775676Y157576D01*
G01X1754622Y160233D02*
X1773019D01*
G01X1752319Y157930D02*
X1754622Y160233D01*
G01X1773190Y161126D02*
X1713154D01*
G01X1775988Y158328D02*
X1773190Y161126D01*
G01X1728581Y245490D02*
X1799131D01*
G01X1727896Y246175D02*
X1728581Y245490D01*
G01X1722740Y248230D02*
X1720651Y246141D01*
G01X1730681Y248230D02*
X1722740D01*
G01X1732669Y246242D02*
X1730681Y248230D01*
G01X1799443Y246242D02*
X1732669D01*
G01X1741022Y462348D02*
X1720022D01*
G01X1744966Y458404D02*
X1741022Y462348D01*
G01X1825210Y458404D02*
X1744966D01*
G01X1742022Y454596D02*
X1828279D01*
G01X1738289Y458329D02*
X1742022Y454596D01*
G01X1716006Y458329D02*
X1738289D01*
G01X1730506Y447150D02*
X1715450D01*
G01X1734282Y443374D02*
X1730506Y447150D01*
G01X1842577Y443374D02*
X1734282D01*
G01X1728869Y441601D02*
X1724369D01*
G01X1732130Y438340D02*
X1728869Y441601D01*
G01X1850815Y438340D02*
X1732130D01*
G01X1730900Y448100D02*
X1715844D01*
G01X1734676Y444324D02*
X1730900Y448100D01*
G01X1842183Y444324D02*
X1734676D01*
G01X1720333Y461595D02*
X1719711D01*
G01X1720334Y461596D02*
X1720333Y461595D01*
G01X1740710Y461596D02*
X1720334D01*
G01X1745054Y457252D02*
X1740710Y461596D01*
G01X1825688Y457252D02*
X1745054D01*
G01X1737812Y457176D02*
X1715529D01*
G01X1741544Y453444D02*
X1737812Y457176D01*
G01X1830244Y453444D02*
X1741544D01*
G01X1744770Y461860D02*
X1741585Y465045D01*
G01X1821940Y461860D02*
X1744770D01*
G01X1744576Y456100D02*
X1826166D01*
G01X1740232Y460444D02*
X1744576Y456100D01*
G01X1720812Y460444D02*
X1740232D01*
G01X1720811Y460443D02*
X1720812Y460444D01*
G01X1719233Y460443D02*
X1720811D01*
G01X1742617Y455348D02*
X1827684D01*
G01X1738684Y459281D02*
X1742617Y455348D01*
G01X1716401Y459281D02*
X1738684D01*
G01X1733442Y440358D02*
X1847002D01*
G01X1730996Y442804D02*
X1733442Y440358D01*
G01X1741500Y463500D02*
X1720500D01*
G01X1744292Y460708D02*
X1741500Y463500D01*
G01X1824254Y460708D02*
X1744292D01*
G01X1741585Y465045D02*
X1720585D01*
G01X1769267Y540433D02*
X1775264D01*
G01X1759764Y549936D02*
X1769267Y540433D01*
G01X1749350Y549936D02*
X1759764D01*
G01X1744675Y545261D02*
X1749350Y549936D01*
G01X1737609Y545261D02*
X1744675D01*
G01X1737359Y545511D02*
X1737609Y545261D01*
G01X1737085Y545511D02*
X1737359D01*
G01X1735488Y547108D02*
X1737085Y545511D01*
G01X1735488Y547382D02*
Y547108D01*
G01X1732934Y549936D02*
X1735488Y547382D01*
G01X1715854Y549936D02*
X1732934D01*
G01X1741224Y581000D02*
X1735500Y575276D01*
G01X1743396Y581000D02*
X1741224D01*
G01X1756196Y593800D02*
X1743396Y581000D01*
G01X1731432Y553750D02*
X1726000Y559182D01*
G01X1734750Y553750D02*
X1731432D01*
G01X1736830Y555830D02*
X1734750Y553750D01*
G01X1737844Y555830D02*
X1736830D01*
G01X1737845Y555831D02*
X1737844Y555830D01*
G01X1739151Y555831D02*
X1737845D01*
G01X1739152Y555830D02*
X1739151Y555831D01*
G01X1741830Y555830D02*
X1739152D01*
G01X1744200Y558200D02*
X1741830Y555830D01*
G01X1769200Y558200D02*
X1744200D01*
G01X1770000Y559000D02*
X1769200Y558200D01*
G01X1780729Y559000D02*
X1770000D01*
G01X1762087Y583000D02*
X1769279Y590192D01*
G01X1748500Y583000D02*
X1762087D01*
G01X1745000Y579500D02*
X1748500Y583000D01*
G01X1741847Y579500D02*
X1745000D01*
G01X1736000Y573653D02*
X1741847Y579500D01*
G01X1719000Y567000D02*
X1712334Y560334D01*
G01X1734771Y567000D02*
X1719000D01*
G01X1742271Y559500D02*
X1734771Y567000D01*
G01X1744500Y559500D02*
X1742271D01*
G01X1757700Y572700D02*
X1744500Y559500D01*
G01X1765700Y572700D02*
X1757700D01*
G01X1766271Y573271D02*
X1765700Y572700D01*
G01X1768229Y573271D02*
X1766271D01*
G01X1769200Y572300D02*
X1768229Y573271D01*
G01X1782000Y572300D02*
X1769200D01*
G01X1730953Y552368D02*
X1725291Y558030D01*
G01X1734502Y552368D02*
X1730953D01*
G01X1734732Y552598D02*
X1734502Y552368D01*
G01X1740044Y552598D02*
X1734732D01*
G01X1741368Y551274D02*
X1740044Y552598D01*
G01X1743630Y551274D02*
X1741368D01*
G01X1743703Y551347D02*
X1743630Y551274D01*
G01X1743977Y551347D02*
X1743703D01*
G01X1744998Y552368D02*
X1743977Y551347D01*
G01X1745128Y552368D02*
X1744998D01*
G01X1749260Y556500D02*
X1745128Y552368D01*
G01X1762030Y556500D02*
X1749260D01*
G01X1765030Y553500D02*
X1762030Y556500D01*
G01X1768000Y553500D02*
X1765030D01*
G01X1772000Y557500D02*
X1768000Y553500D01*
G01X1785101Y557500D02*
X1772000D01*
G01X1770271Y578300D02*
X1772578Y575993D01*
G01X1758299Y578300D02*
X1770271D01*
G01X1744499Y564500D02*
X1758299Y578300D01*
G01X1743500Y564500D02*
X1744499D01*
G01X1733284Y551216D02*
X1716204D01*
G01X1736640Y547860D02*
X1733284Y551216D01*
G01X1736640Y547586D02*
Y547860D01*
G01X1737563Y546663D02*
X1736640Y547586D01*
G01X1737837Y546663D02*
X1737563D01*
G01X1738087Y546413D02*
X1737837Y546663D01*
G01X1744197Y546413D02*
X1738087D01*
G01X1749000Y551216D02*
X1744197Y546413D01*
G01X1772217Y551216D02*
X1749000D01*
G01X1773586Y552585D02*
X1772217Y551216D01*
G01X1781816Y552585D02*
X1773586D01*
G01X1761295Y593800D02*
X1756196D01*
G01X1761326Y593831D02*
X1761295Y593800D01*
G01X1762798Y593831D02*
X1761326D01*
G01X1762829Y593800D02*
X1762798Y593831D01*
G01X1779399Y593800D02*
X1762829D01*
G01X1758569Y606953D02*
X1757319D01*
G01X1762748Y602774D02*
X1758569Y606953D01*
G01X1791826Y602774D02*
X1762748D01*
G01X1757752Y595848D02*
X1779122D01*
G01X1750399Y603201D02*
X1757752Y595848D01*
G01X1745965Y603201D02*
X1744340Y601576D01*
G01X1750399Y603201D02*
X1745965D01*
G01X1769279Y590192D02*
X1780308D01*
G01X1763259Y604252D02*
X1793802D01*
G01X1756961Y610550D02*
X1763259Y604252D01*
G01X1740120Y610550D02*
X1756961D01*
G01X1737780Y608210D02*
X1740120Y610550D01*
G01X1742169Y608450D02*
X1740572Y606853D01*
G01X1752240Y608450D02*
X1742169D01*
G01X1756974Y603716D02*
X1752240Y608450D01*
G01X1756974Y603697D02*
Y603716D01*
G01X1757897Y602774D02*
X1756974Y603697D01*
G01X1757916Y602774D02*
X1757897D01*
G01X1759246Y601444D02*
X1757916Y602774D01*
G01X1767256Y601444D02*
X1759246D01*
G01X1771400Y597300D02*
X1767256Y601444D01*
G01X1780824Y597300D02*
X1771400D01*
G01X1791500Y26918D02*
Y22087D01*
G01X1801800Y26932D02*
X1810426Y35558D01*
G01X1801800Y24280D02*
Y26932D01*
G01X1806169Y19911D02*
X1801800Y24280D01*
G01X1806169Y11290D02*
Y19911D01*
G01X1806048Y11169D02*
X1806169Y11290D01*
G01X1806048Y7978D02*
Y11169D01*
G01X1805079Y7009D02*
X1806048Y7978D01*
G01X1797098Y7009D02*
X1805079D01*
G01X1789918Y-171D02*
X1797098Y7009D01*
G01X1778048Y782D02*
X1785366Y8100D01*
G01X1819504Y-1395D02*
Y-5000D01*
G01X1821376Y477D02*
X1819504Y-1395D01*
G01X1821376Y2753D02*
Y477D01*
G01X1821005Y3124D02*
X1821376Y2753D01*
G01X1821005Y13726D02*
Y3124D01*
G01X1816209Y18522D02*
X1821005Y13726D01*
G01X1813821Y18522D02*
X1816209D01*
G01X1812765Y19578D02*
X1813821Y18522D01*
G01X1812765Y31007D02*
Y19578D01*
G01X1813927Y32169D02*
X1812765Y31007D01*
G01X1820845Y32169D02*
X1813927D01*
G01X1820848Y32172D02*
X1820845Y32169D01*
G01X1821179Y32172D02*
X1820848D01*
G01X1823650Y34643D02*
X1821179Y32172D01*
G01X1789772Y27419D02*
Y21706D01*
G01X1793501Y31148D02*
X1789772Y27419D01*
G01X1799608Y31148D02*
X1793501D01*
G01X1802302Y33842D02*
X1799608Y31148D01*
G01X1828744Y-4832D02*
X1822452Y-11124D01*
G01X1828744Y-632D02*
Y-4832D01*
G01X1831702Y2326D02*
X1828744Y-632D01*
G01X1831702Y6873D02*
Y2326D01*
G01X1834476Y9647D02*
X1831702Y6873D01*
G01X1834476Y14095D02*
Y9647D01*
G01X1827900Y20671D02*
X1834476Y14095D01*
G01X1827900Y22800D02*
Y20671D01*
G01X1823850Y26850D02*
X1827900Y22800D01*
G01X1823850Y30550D02*
Y26850D01*
G01X1828700Y35400D02*
X1823850Y30550D01*
G01X1788759Y27753D02*
Y22040D01*
G01X1793106Y32100D02*
X1788759Y27753D01*
G01X1799213Y32100D02*
X1793106D01*
G01X1801350Y34237D02*
X1799213Y32100D01*
G01X1793672Y21018D02*
X1797700D01*
G01X1774388Y1734D02*
X1793672Y21018D01*
G01X1823775Y-17025D02*
X1821600Y-19200D01*
G01X1823775Y-10925D02*
Y-17025D01*
G01X1829496Y-5204D02*
X1823775Y-10925D01*
G01X1829496Y-944D02*
Y-5204D01*
G01X1832454Y2014D02*
X1829496Y-944D01*
G01X1832454Y6561D02*
Y2014D01*
G01X1835229Y9336D02*
X1832454Y6561D01*
G01X1835229Y9958D02*
Y9336D01*
G01X1835228Y9959D02*
X1835229Y9958D01*
G01X1835228Y14407D02*
Y9959D01*
G01X1828800Y20835D02*
X1835228Y14407D01*
G01X1828800Y22964D02*
Y20835D01*
G01X1825066Y26698D02*
X1828800Y22964D01*
G01X1825066Y30631D02*
Y26698D01*
G01X1828366Y33931D02*
X1825066Y30631D01*
G01X1825300Y-17200D02*
X1822100Y-20400D01*
G01X1825300Y-11100D02*
Y-17200D01*
G01X1830648Y-5752D02*
X1825300Y-11100D01*
G01X1830648Y-1422D02*
Y-5752D01*
G01X1833098Y1028D02*
X1830648Y-1422D01*
G01X1839828Y1028D02*
X1833098D01*
G01X1822500Y7700D02*
X1823600Y8800D01*
G01X1822500Y1200D02*
Y7700D01*
G01X1824100Y-400D02*
X1822500Y1200D01*
G01X1824100Y-5886D02*
Y-400D01*
G01X1820990Y-8996D02*
X1824100Y-5886D01*
G01X1797456Y6000D02*
X1790333Y-1123D01*
G01X1805500Y6000D02*
X1797456D01*
G01X1807026Y7526D02*
X1805500Y6000D01*
G01X1807026Y10800D02*
Y7526D01*
G01X1807121Y10895D02*
X1807026Y10800D01*
G01X1807121Y20821D02*
Y10895D01*
G01X1808100Y21800D02*
X1807121Y20821D01*
G01X1779750Y36530D02*
Y27455D01*
G01X1826547Y-17653D02*
X1822600Y-21600D01*
G01X1826547Y-11553D02*
Y-17653D01*
G01X1831800Y-6300D02*
X1826547Y-11553D01*
G01X1831800Y-1900D02*
Y-6300D01*
G01X1833576Y-124D02*
X1831800Y-1900D01*
G01X1840306Y-124D02*
X1833576D01*
G01X1830750Y8150D02*
X1832900Y10300D01*
G01X1830750Y2874D02*
Y8150D01*
G01X1827576Y-300D02*
X1830750Y2874D01*
G01X1827576Y-4653D02*
Y-300D01*
G01X1822280Y-9949D02*
X1827576Y-4653D01*
G01X1809504Y-2196D02*
Y-5000D01*
G01X1812005Y305D02*
X1809504Y-2196D01*
G01X1814406Y305D02*
X1812005D01*
G01X1819118Y5017D02*
X1814406Y305D01*
G01X1819118Y13418D02*
Y5017D01*
G01X1815566Y16970D02*
X1819118Y13418D01*
G01X1813178Y16970D02*
X1815566D01*
G01X1811398Y18750D02*
X1813178Y16970D01*
G01X1811398Y31835D02*
Y18750D01*
G01X1813284Y33721D02*
X1811398Y31835D01*
G01X1774828Y70725D02*
Y67972D01*
G01X1783518Y79415D02*
X1774828Y70725D01*
G01X1791700Y79415D02*
X1783518D01*
G01X1796293Y84008D02*
X1791700Y79415D01*
G01X1801136Y84008D02*
X1796293D01*
G01X1804352Y80792D02*
X1801136Y84008D01*
G01X1815448Y80792D02*
X1804352D01*
G01X1824277Y89621D02*
X1815448Y80792D01*
G01X1829198Y89621D02*
X1824277D01*
G01X1829199Y89620D02*
X1829198Y89621D01*
G01X1829821Y89620D02*
X1829199D01*
G01X1843261Y103060D02*
X1829821Y89620D01*
G01X1830560Y43807D02*
X1847747D01*
G01X1830130Y43377D02*
X1830560Y43807D01*
G01X1815748Y43377D02*
X1830130D01*
G01X1810426Y38055D02*
X1815748Y43377D01*
G01X1810426Y35558D02*
Y38055D01*
G01X1780900Y65906D02*
Y65148D01*
G01X1787812Y72818D02*
X1780900Y65906D01*
G01X1817351Y72818D02*
X1787812D01*
G01X1818689Y74156D02*
X1817351Y72818D01*
G01X1825201Y74156D02*
X1818689D01*
G01X1826616Y72741D02*
X1825201Y74156D01*
G01X1826616Y68095D02*
Y72741D01*
G01X1833812Y60899D02*
X1826616Y68095D01*
G01X1858081Y60899D02*
X1833812D01*
G01X1823650Y38701D02*
Y34643D01*
G01X1824130Y39181D02*
X1823650Y38701D01*
G01X1824130Y39703D02*
Y39181D01*
G01X1788216Y59197D02*
Y57940D01*
G01X1786952Y40690D02*
X1789356Y38286D01*
G01X1779447Y40690D02*
X1786952D01*
G01X1776362Y68754D02*
Y66776D01*
G01X1776361Y68755D02*
X1776362Y68754D01*
G01X1776361Y69028D02*
Y68755D01*
G01X1784434Y77101D02*
X1776361Y69028D01*
G01X1793055Y77101D02*
X1784434D01*
G01X1794218Y78264D02*
X1793055Y77101D01*
G01X1814550Y78264D02*
X1794218D01*
G01X1820229Y83943D02*
X1814550Y78264D01*
G01X1823977Y83943D02*
X1820229D01*
G01X1824240Y83680D02*
X1823977Y83943D01*
G01X1835027Y64037D02*
X1857202D01*
G01X1829481Y69583D02*
X1835027Y64037D01*
G01X1829481Y76528D02*
Y69583D01*
G01X1823970Y82039D02*
X1829481Y76528D01*
G01X1820213Y82039D02*
X1823970D01*
G01X1813674Y75500D02*
X1820213Y82039D01*
G01X1812298Y75500D02*
X1813674D01*
G01X1811946Y75852D02*
X1812298Y75500D01*
G01X1811946Y76748D02*
Y75852D01*
G01X1811594Y77100D02*
X1811946Y76748D01*
G01X1809945Y77100D02*
X1811594D01*
G01X1809593Y76748D02*
X1809945Y77100D01*
G01X1809593Y75852D02*
Y76748D01*
G01X1809241Y75500D02*
X1809593Y75852D01*
G01X1807592Y75500D02*
X1809241D01*
G01X1807240Y75852D02*
X1807592Y75500D01*
G01X1807240Y76748D02*
Y75852D01*
G01X1806888Y77100D02*
X1807240Y76748D01*
G01X1805239Y77100D02*
X1806888D01*
G01X1804887Y76748D02*
X1805239Y77100D01*
G01X1804887Y75852D02*
Y76748D01*
G01X1804535Y75500D02*
X1804887Y75852D01*
G01X1802886Y75500D02*
X1804535D01*
G01X1802534Y75852D02*
X1802886Y75500D01*
G01X1802534Y76748D02*
Y75852D01*
G01X1802182Y77100D02*
X1802534Y76748D01*
G01X1800533Y77100D02*
X1802182D01*
G01X1800181Y76748D02*
X1800533Y77100D01*
G01X1800181Y75852D02*
Y76748D01*
G01X1799829Y75500D02*
X1800181Y75852D01*
G01X1798180Y75500D02*
X1799829D01*
G01X1797828Y75852D02*
X1798180Y75500D01*
G01X1797828Y76748D02*
Y75852D01*
G01X1797476Y77100D02*
X1797828Y76748D01*
G01X1795827Y77100D02*
X1797476D01*
G01X1795475Y76748D02*
X1795827Y77100D01*
G01X1795475Y75852D02*
Y76748D01*
G01X1795123Y75500D02*
X1795475Y75852D01*
G01X1785663Y75500D02*
X1795123D01*
G01X1777700Y67537D02*
X1785663Y75500D01*
G01X1777700Y66229D02*
Y67537D01*
G01X1802302Y36198D02*
Y33842D01*
G01X1801724Y36776D02*
X1802302Y36198D01*
G01X1801724Y40553D02*
Y36776D01*
G01X1805930Y44759D02*
X1801724Y40553D01*
G01X1847298Y44759D02*
X1805930D01*
G01X1834641Y35400D02*
X1828700D01*
G01X1836741Y33300D02*
X1834641Y35400D01*
G01X1790764Y81671D02*
X1782582D01*
G01X1795357Y86264D02*
X1790764Y81671D01*
G01X1802072Y86264D02*
X1795357D01*
G01X1805288Y83048D02*
X1802072Y86264D01*
G01X1814512Y83048D02*
X1805288D01*
G01X1823686Y92222D02*
X1814512Y83048D01*
G01X1828986Y92222D02*
X1823686D01*
G01X1842772Y106008D02*
X1828986Y92222D01*
G01X1801350Y35543D02*
Y34237D01*
G01X1800772Y36121D02*
X1801350Y35543D01*
G01X1800772Y40948D02*
Y36121D01*
G01X1805535Y45711D02*
X1800772Y40948D01*
G01X1846751Y45711D02*
X1805535D01*
G01X1782000Y92200D02*
X1784800Y95000D01*
G01X1782000Y85689D02*
Y92200D01*
G01X1779300Y66682D02*
Y65558D01*
G01X1786788Y74170D02*
X1779300Y66682D01*
G01X1816790Y74170D02*
X1786788D01*
G01X1818170Y75550D02*
X1816790Y74170D01*
G01X1825897Y75550D02*
X1818170D01*
G01X1827995Y73452D02*
X1825897Y75550D01*
G01X1827995Y68849D02*
Y73452D01*
G01X1834481Y62363D02*
X1827995Y68849D01*
G01X1857620Y62363D02*
X1834481D01*
G01X1828674Y92974D02*
X1842460Y106760D01*
G01X1823374Y92974D02*
X1828674D01*
G01X1814200Y83800D02*
X1823374Y92974D01*
G01X1805600Y83800D02*
X1814200D01*
G01X1802384Y87016D02*
X1805600Y83800D01*
G01X1795045Y87016D02*
X1802384D01*
G01X1790452Y82423D02*
X1795045Y87016D01*
G01X1782270Y82423D02*
X1790452D01*
G01X1835046Y33931D02*
X1828366D01*
G01X1836430Y32547D02*
X1835046Y33931D01*
G01X1781000Y92700D02*
X1784300Y96000D01*
G01X1781000Y86036D02*
Y92700D01*
G01X1794478Y42400D02*
X1779018D01*
G01X1796406Y44328D02*
X1794478Y42400D01*
G01X1799438Y44328D02*
X1796406D01*
G01X1796492Y68408D02*
X1796100Y68800D01*
G01X1817431Y68408D02*
X1796492D01*
G01X1820969Y64870D02*
X1817431Y68408D01*
G01X1774076Y71037D02*
Y68636D01*
G01X1783206Y80167D02*
X1774076Y71037D01*
G01X1791388Y80167D02*
X1783206D01*
G01X1795981Y84760D02*
X1791388Y80167D01*
G01X1801448Y84760D02*
X1795981D01*
G01X1804664Y81544D02*
X1801448Y84760D01*
G01X1815136Y81544D02*
X1804664D01*
G01X1823965Y90373D02*
X1815136Y81544D01*
G01X1829510Y90373D02*
X1823965D01*
G01X1842949Y103812D02*
X1829510Y90373D01*
G01X1834914Y52928D02*
X1856684D01*
G01X1817230Y66617D02*
X1820708Y63139D01*
G01X1783605Y66617D02*
X1817230D01*
G01X1782500Y65512D02*
X1783605Y66617D01*
G01X1782500Y58771D02*
Y65512D01*
G01X1793373Y43810D02*
X1778687D01*
G01X1802119Y52556D02*
X1793373Y43810D01*
G01X1802119Y56581D02*
Y52556D01*
G01X1834178Y58304D02*
X1857826D01*
G01X1818015Y69816D02*
X1821071Y66760D01*
G01X1797973Y69816D02*
X1818015D01*
G01X1796891Y70898D02*
X1797973Y69816D01*
G01X1794100Y70898D02*
X1796891D01*
G01X1775440Y91090D02*
Y81546D01*
G01X1787868Y103518D02*
X1775440Y91090D01*
G01X1774500Y91497D02*
Y86108D01*
G01X1787473Y104470D02*
X1774500Y91497D01*
G01X1791076Y80919D02*
X1782894D01*
G01X1795669Y85512D02*
X1791076Y80919D01*
G01X1801760Y85512D02*
X1795669D01*
G01X1804976Y82296D02*
X1801760Y85512D01*
G01X1814824Y82296D02*
X1804976D01*
G01X1823653Y91125D02*
X1814824Y82296D01*
G01X1829166Y91125D02*
X1823653D01*
G01X1842605Y104564D02*
X1829166Y91125D01*
G01X1820533Y33721D02*
X1813284D01*
G01X1821576Y34764D02*
X1820533Y33721D01*
G01X1821576Y38009D02*
Y34764D01*
G01X1820457Y39128D02*
X1821576Y38009D01*
G01X1807924Y151657D02*
X1801715Y145448D01*
G01X1822257Y151657D02*
X1807924D01*
G01X1830770Y160170D02*
X1822257Y151657D01*
G01X1834700Y132845D02*
X1841055Y139200D01*
G01X1826667Y132845D02*
X1834700D01*
G01X1817718Y123896D02*
X1826667Y132845D01*
G01X1812732Y123896D02*
X1817718D01*
G01X1807195Y118359D02*
X1812732Y123896D01*
G01X1801931Y118359D02*
X1807195D01*
G01X1798840Y115268D02*
X1801931Y118359D01*
G01X1781865Y115268D02*
X1798840D01*
G01X1807315Y135260D02*
X1782657D01*
G01X1808226Y136171D02*
X1807315Y135260D01*
G01X1829569Y129589D02*
X1849006D01*
G01X1821415Y121435D02*
X1829569Y129589D01*
G01X1821415Y120257D02*
Y121435D01*
G01X1821416Y120256D02*
X1821415Y120257D01*
G01X1821416Y116144D02*
Y120256D01*
G01X1813846Y108574D02*
X1821416Y116144D01*
G01X1786456Y108574D02*
X1813846D01*
G01X1810238Y106900D02*
X1786964D01*
G01X1812743Y104395D02*
X1810238Y106900D01*
G01X1832518Y138105D02*
X1838916Y144503D01*
G01X1823748Y138105D02*
X1832518D01*
G01X1821963Y136320D02*
X1823748Y138105D01*
G01X1817556Y136320D02*
X1821963D01*
G01X1817553Y136317D02*
X1817556Y136320D01*
G01X1816599Y136317D02*
X1817553D01*
G01X1816598Y136318D02*
X1816599Y136317D01*
G01X1815976Y136318D02*
X1816598D01*
G01X1815975Y136319D02*
X1815976Y136318D01*
G01X1815187Y136319D02*
X1815975D01*
G01X1815186Y136320D02*
X1815187Y136319D01*
G01X1814641Y136320D02*
X1815186D01*
G01X1810238Y131917D02*
X1814641Y136320D01*
G01X1801519Y131917D02*
X1810238D01*
G01X1800653Y131051D02*
X1801519Y131917D01*
G01X1781309Y131051D02*
X1800653D01*
G01X1807718Y112300D02*
X1808313Y111705D01*
G01X1783195Y112300D02*
X1807718D01*
G01X1835219Y131593D02*
X1841237Y137611D01*
G01X1828738Y131593D02*
X1835219D01*
G01X1816845Y119700D02*
X1828738Y131593D01*
G01X1810377Y119700D02*
X1816845D01*
G01X1807700Y117023D02*
X1810377Y119700D01*
G01X1802366Y117023D02*
X1807700D01*
G01X1799203Y113860D02*
X1802366Y117023D01*
G01X1782228Y113860D02*
X1799203D01*
G01X1833391Y136001D02*
X1839746Y142356D01*
G01X1824621Y136001D02*
X1833391D01*
G01X1819638Y131018D02*
X1824621Y136001D01*
G01X1812316Y131018D02*
X1819638D01*
G01X1808222Y126924D02*
X1812316Y131018D01*
G01X1805177Y126924D02*
X1808222D01*
G01X1804029Y125776D02*
X1805177Y126924D01*
G01X1779429Y125776D02*
X1804029D01*
G01X1803319Y134203D02*
X1782831D01*
G01X1804145Y133377D02*
X1803319Y134203D01*
G01X1810068Y133377D02*
X1804145D01*
G01X1814163Y137472D02*
X1810068Y133377D01*
G01X1815664Y137472D02*
X1814163D01*
G01X1815665Y137471D02*
X1815664Y137472D01*
G01X1816453Y137471D02*
X1815665D01*
G01X1816454Y137470D02*
X1816453Y137471D01*
G01X1817076Y137470D02*
X1816454D01*
G01X1817078Y137472D02*
X1817076Y137470D01*
G01X1821485Y137472D02*
X1817078D01*
G01X1823270Y139257D02*
X1821485Y137472D01*
G01X1831892Y139257D02*
X1823270D01*
G01X1838293Y145655D02*
X1831892Y139257D01*
G01X1831032Y140961D02*
X1837756Y147685D01*
G01X1822563Y140961D02*
X1831032D01*
G01X1820778Y139176D02*
X1822563Y140961D01*
G01X1807607Y139176D02*
X1820778D01*
G01X1805721Y137290D02*
X1807607Y139176D01*
G01X1780930Y137290D02*
X1805721D01*
G01X1806080Y136260D02*
X1781811D01*
G01X1808044Y138224D02*
X1806080Y136260D01*
G01X1815976Y138224D02*
X1808044D01*
G01X1815977Y138223D02*
X1815976Y138224D01*
G01X1816765Y138223D02*
X1815977D01*
G01X1816766Y138224D02*
X1816765Y138223D01*
G01X1821173Y138224D02*
X1816766D01*
G01X1822958Y140009D02*
X1821173Y138224D01*
G01X1831453Y140009D02*
X1822958D01*
G01X1837851Y146407D02*
X1831453Y140009D01*
G01X1781234Y117472D02*
X1777736Y113974D01*
G01X1798209Y117472D02*
X1781234D01*
G01X1801100Y120363D02*
X1798209Y117472D01*
G01X1806364Y120363D02*
X1801100D01*
G01X1811901Y125900D02*
X1806364Y120363D01*
G01X1816695Y125900D02*
X1811901D01*
G01X1825644Y134849D02*
X1816695Y125900D01*
G01X1833869Y134849D02*
X1825644D01*
G01X1840224Y141204D02*
X1833869Y134849D01*
G01X1833993Y149830D02*
X1837090D01*
G01X1829438Y145275D02*
X1833993Y149830D01*
G01X1829438Y143400D02*
Y145275D01*
G01X1827951Y141913D02*
X1829438Y143400D01*
G01X1822168Y141913D02*
X1827951D01*
G01X1820383Y140128D02*
X1822168Y141913D01*
G01X1806944Y140128D02*
X1820383D01*
G01X1805276Y138460D02*
X1806944Y140128D01*
G01X1814679Y129715D02*
X1816418Y127976D01*
G01X1812360Y129715D02*
X1814679D01*
G01X1808662Y126017D02*
X1812360Y129715D01*
G01X1808602Y126017D02*
X1808662D01*
G01X1808557Y125972D02*
X1808602Y126017D01*
G01X1805972Y125972D02*
X1808557D01*
G01X1804267Y124267D02*
X1805972Y125972D01*
G01X1788539Y124267D02*
X1804267D01*
G01X1782496Y118224D02*
X1788539Y124267D01*
G01X1774488Y118224D02*
X1782496D01*
G01X1822537Y107538D02*
X1847548D01*
G01X1814999Y100000D02*
X1822537Y107538D01*
G01X1807937Y100000D02*
X1814999D01*
G01X1804637Y96700D02*
X1807937Y100000D01*
G01X1791800Y96700D02*
X1804637D01*
G01X1790100Y95000D02*
X1791800Y96700D01*
G01X1784800Y95000D02*
X1790100D01*
G01X1808645Y106100D02*
X1787228D01*
G01X1810245Y104500D02*
X1808645Y106100D01*
G01X1831702Y155153D02*
X1840738D01*
G01X1830910Y154361D02*
X1831702Y155153D01*
G01X1830910Y150109D02*
Y154361D01*
G01X1828285Y147484D02*
X1830910Y150109D01*
G01X1825812Y147484D02*
X1828285D01*
G01X1823096Y150200D02*
X1825812Y147484D01*
G01X1822928Y150200D02*
X1823096D01*
G01X1822881Y150153D02*
X1822928Y150200D01*
G01X1813211Y150153D02*
X1822881D01*
G01X1804463Y141405D02*
X1813211Y150153D01*
G01X1796741Y141405D02*
X1804463D01*
G01X1796126Y142020D02*
X1796741Y141405D01*
G01X1821890Y108290D02*
X1847110D01*
G01X1814500Y100900D02*
X1821890Y108290D01*
G01X1807490Y100900D02*
X1814500D01*
G01X1804145Y97555D02*
X1807490Y100900D01*
G01X1791455Y97555D02*
X1804145D01*
G01X1789900Y96000D02*
X1791455Y97555D01*
G01X1784300Y96000D02*
X1789900D01*
G01X1781526Y116700D02*
X1778048Y113222D01*
G01X1798501Y116700D02*
X1781526D01*
G01X1801412Y119611D02*
X1798501Y116700D01*
G01X1806676Y119611D02*
X1801412D01*
G01X1812213Y125148D02*
X1806676Y119611D01*
G01X1817007Y125148D02*
X1812213D01*
G01X1825956Y134097D02*
X1817007Y125148D01*
G01X1834181Y134097D02*
X1825956D01*
G01X1840536Y140452D02*
X1834181Y134097D01*
G01X1822569Y150905D02*
X1829653Y157989D01*
G01X1812899Y150905D02*
X1822569D01*
G01X1804151Y142157D02*
X1812899Y150905D01*
G01X1797053Y142157D02*
X1804151D01*
G01X1796110Y143100D02*
X1797053Y142157D01*
G01X1799508Y126728D02*
X1779034D01*
G01X1803545Y130765D02*
X1799508Y126728D01*
G01X1809760Y130765D02*
X1803545D01*
G01X1809761Y130764D02*
X1809760Y130765D01*
G01X1810715Y130764D02*
X1809761D01*
G01X1815118Y135167D02*
X1810715Y130764D01*
G01X1815497Y135167D02*
X1815118D01*
G01X1815498Y135166D02*
X1815497Y135167D01*
G01X1816120Y135166D02*
X1815498D01*
G01X1816121Y135165D02*
X1816120Y135166D01*
G01X1818031Y135165D02*
X1816121D01*
G01X1818032Y135166D02*
X1818031Y135165D01*
G01X1822439Y135166D02*
X1818032D01*
G01X1824226Y136953D02*
X1822439Y135166D01*
G01X1832996Y136953D02*
X1824226D01*
G01X1839394Y143351D02*
X1832996Y136953D01*
G01X1822320Y145842D02*
X1824509Y143653D01*
G01X1809964Y145842D02*
X1822320D01*
G01X1804775Y140653D02*
X1809964Y145842D01*
G01X1796429Y140653D02*
X1804775D01*
G01X1795930Y141152D02*
X1796429Y140653D01*
G01X1794684Y155905D02*
X1791509Y159080D01*
G01X1805241Y155905D02*
X1794684D01*
G01X1807847Y158511D02*
X1805241Y155905D01*
G01X1807446Y152809D02*
X1801237Y146600D01*
G01X1821779Y152809D02*
X1807446D01*
G01X1830292Y161322D02*
X1821779Y152809D01*
G01X1829257Y130341D02*
X1840310D01*
G01X1820310Y121394D02*
X1829257Y130341D01*
G01X1820310Y116509D02*
Y121394D01*
G01X1813127Y109326D02*
X1820310Y116509D01*
G01X1785763Y109326D02*
X1813127D01*
G01X1810276Y145090D02*
X1805087Y139901D01*
G01X1819874Y145090D02*
X1810276D01*
G01X1821348Y143616D02*
X1819874Y145090D01*
G01X1821348Y143437D02*
Y143616D01*
G01X1827500Y145160D02*
Y144900D01*
G01X1833728Y151388D02*
X1827500Y145160D01*
G01X1836419Y151388D02*
X1833728D01*
G01X1829881Y128837D02*
X1848694D01*
G01X1822168Y121124D02*
X1829881Y128837D01*
G01X1822168Y115732D02*
Y121124D01*
G01X1814258Y107822D02*
X1822168Y115732D01*
G01X1786788Y107822D02*
X1814258D01*
G01X1814900Y113538D02*
Y116900D01*
G01X1811440Y110078D02*
X1814900Y113538D01*
G01X1794203Y110078D02*
X1811440D01*
G01X1792850Y111431D02*
X1794203Y110078D01*
G01X1783397Y111431D02*
X1792850D01*
G01X1791981Y103518D02*
X1787868D01*
G01X1793699Y101800D02*
X1791981Y103518D01*
G01X1813900Y101800D02*
X1793699D01*
G01X1821331Y109231D02*
X1813900Y101800D01*
G01X1846987Y109231D02*
X1821331D01*
G01X1792430Y104470D02*
X1787473D01*
G01X1794200Y102700D02*
X1792430Y104470D01*
G01X1813699Y102700D02*
X1794200D01*
G01X1821182Y110183D02*
X1813699Y102700D01*
G01X1846875Y110183D02*
X1821182D01*
G01X1821301Y153961D02*
X1830140Y162800D01*
G01X1794500Y153961D02*
X1821301D01*
G01X1790885Y157576D02*
X1794500Y153961D01*
G01X1794572Y154953D02*
X1791197Y158328D01*
G01X1805968Y154953D02*
X1794572D01*
G01X1808574Y157559D02*
X1805968Y154953D01*
G01X1837929Y160170D02*
X1830770D01*
G01X1834400Y216900D02*
X1833009Y218291D01*
G01X1774584Y162924D02*
X1774126Y163382D01*
G01X1780500Y162924D02*
X1774584D01*
G01X1783576Y166000D02*
X1780500Y162924D01*
G01X1790200Y166000D02*
X1783576D01*
G01X1793450Y169250D02*
X1790200Y166000D01*
G01X1803406Y169250D02*
X1793450D01*
G01X1807489Y173333D02*
X1803406Y169250D01*
G01X1837355Y173333D02*
X1807489D01*
G01X1835365Y214572D02*
X1840500Y219707D01*
G01X1833435Y214572D02*
X1835365D01*
G01X1830907Y217100D02*
X1833435Y214572D01*
G01X1830907Y240489D02*
Y217100D01*
G01X1778900Y165800D02*
X1777986Y164886D01*
G01X1807883Y172383D02*
X1837749D01*
G01X1796598Y161098D02*
X1807883Y172383D01*
G01X1775346Y161098D02*
X1796598D01*
G01X1830405Y180591D02*
X1844100Y194286D01*
G01X1830405Y177565D02*
Y180591D01*
G01X1826932Y174092D02*
X1830405Y177565D01*
G01X1791192Y174092D02*
X1826932D01*
G01X1787400Y170300D02*
X1791192Y174092D01*
G01X1780200Y170300D02*
X1787400D01*
G01X1775538Y165638D02*
X1780200Y170300D01*
G01X1831659Y217412D02*
Y240801D01*
G01X1833747Y215324D02*
X1831659Y217412D01*
G01X1835053Y215324D02*
X1833747D01*
G01X1840188Y220459D02*
X1835053Y215324D01*
G01X1835497Y159158D02*
X1837797Y156858D01*
G01X1831871Y159158D02*
X1835497D01*
G01X1830702Y157989D02*
X1831871Y159158D01*
G01X1829653Y157989D02*
X1830702D01*
G01X1791509Y159080D02*
X1776300D01*
G01X1812261Y158511D02*
X1807847D01*
G01X1813000Y159250D02*
X1812261Y158511D01*
G01X1813000Y165050D02*
Y159250D01*
G01X1815052Y167102D02*
X1813000Y165050D01*
G01X1825995Y167102D02*
X1815052D01*
G01X1827795Y168902D02*
X1825995Y167102D01*
G01X1840001Y168902D02*
X1827795D01*
G01X1837368Y161322D02*
X1830292D01*
G01X1832168Y211515D02*
X1835615D01*
G01X1827850Y215833D02*
X1832168Y211515D01*
G01X1827850Y228774D02*
Y215833D01*
G01X1785250Y167750D02*
X1785500Y168000D01*
G01X1783250Y167750D02*
X1785250D01*
G01X1779634Y164134D02*
X1783250Y167750D01*
G01X1828603Y217525D02*
Y238707D01*
G01X1828602Y217524D02*
X1828603Y217525D01*
G01X1828602Y216145D02*
Y217524D01*
G01X1832480Y212267D02*
X1828602Y216145D01*
G01X1835303Y212267D02*
X1832480D01*
G01X1841991Y218955D02*
X1835303Y212267D01*
G01X1830140Y162800D02*
X1837136D01*
G01X1775676Y157576D02*
X1790885D01*
G01X1791197Y158328D02*
X1775988D01*
G01X1812656Y157559D02*
X1808574D01*
G01X1813952Y158855D02*
X1812656Y157559D01*
G01X1813952Y164655D02*
Y158855D01*
G01X1815447Y166150D02*
X1813952Y164655D01*
G01X1826206Y166150D02*
X1815447D01*
G01X1828006Y167950D02*
X1826206Y166150D01*
G01X1840396Y167950D02*
X1828006D01*
G01X1833009Y250963D02*
X1831700Y252272D01*
G01X1833009Y218291D02*
Y250963D01*
G01X1825956Y245440D02*
X1830907Y240489D01*
G01X1803298Y245440D02*
X1825956D01*
G01X1801744Y246994D02*
X1803298Y245440D01*
G01X1780388Y246994D02*
X1801744D01*
G01X1774429Y252953D02*
X1780388Y246994D01*
G01X1834000Y228275D02*
X1839816Y222459D01*
G01X1834000Y252201D02*
Y228275D01*
G01X1830992Y255209D02*
X1834000Y252201D01*
G01X1844555Y247214D02*
X1835056Y256713D01*
G01X1780700Y247746D02*
X1774741Y253705D01*
G01X1802056Y247746D02*
X1780700D01*
G01X1803566Y246236D02*
X1802056Y247746D01*
G01X1826224Y246236D02*
X1803566D01*
G01X1831659Y240801D02*
X1826224Y246236D01*
G01X1844722Y245983D02*
X1834744Y255961D01*
G01X1804388Y250248D02*
X1800179Y254457D01*
G01X1804388Y249904D02*
Y250248D01*
G01X1825086Y231538D02*
X1827850Y228774D01*
G01X1825086Y232844D02*
Y231538D01*
G01X1826009Y233767D02*
X1825086Y232844D01*
G01X1826047Y233767D02*
X1826009D01*
G01X1827851Y235571D02*
X1826047Y233767D01*
G01X1827851Y237781D02*
Y235571D01*
G01X1822015Y243617D02*
X1827851Y237781D01*
G01X1801004Y243617D02*
X1822015D01*
G01X1799131Y245490D02*
X1801004Y243617D01*
G01X1801027Y244658D02*
X1799443Y246242D01*
G01X1822652Y244658D02*
X1801027D01*
G01X1828603Y238707D02*
X1822652Y244658D01*
G01X1829710Y462904D02*
X1825210Y458404D01*
G01X1846370Y462904D02*
X1829710D01*
G01X1832579Y458896D02*
X1852156D01*
G01X1828279Y454596D02*
X1832579Y458896D01*
G01X1830188Y461752D02*
X1825688Y457252D01*
G01X1847132Y461752D02*
X1830188D01*
G01X1834200Y457400D02*
X1830244Y453444D01*
G01X1852290Y457400D02*
X1834200D01*
G01X1830780Y470700D02*
X1821940Y461860D01*
G01X1830666Y460600D02*
X1847610D01*
G01X1826166Y456100D02*
X1830666Y460600D01*
G01X1832184Y459848D02*
X1851761D01*
G01X1827684Y455348D02*
X1832184Y459848D01*
G01X1828754Y465208D02*
X1824254Y460708D01*
G01X1806076Y529324D02*
Y523525D01*
G01X1834195Y502952D02*
X1843195D01*
G01X1822400Y514747D02*
X1834195Y502952D01*
G01X1822400Y536801D02*
Y514747D01*
G01X1828200Y519000D02*
Y532000D01*
G01X1815224Y523914D02*
Y526907D01*
G01X1816428Y522710D02*
X1815224Y523914D01*
G01X1816428Y513603D02*
Y522710D01*
G01X1809700Y506875D02*
X1816428Y513603D01*
G01X1843465Y470700D02*
X1830780D01*
G01X1796153Y524747D02*
Y514200D01*
G01X1795200Y525700D02*
X1796153Y524747D01*
G01X1821448Y514352D02*
Y537196D01*
G01X1833800Y502000D02*
X1821448Y514352D01*
G01X1842800Y502000D02*
X1833800D01*
G01X1798883Y512683D02*
Y515636D01*
G01X1797500Y511300D02*
X1798883Y512683D01*
G01X1795378Y511300D02*
X1797500D01*
G01X1793878Y512800D02*
X1795378Y511300D01*
G01X1793878Y517800D02*
Y512800D01*
G01X1792000Y519678D02*
X1793878Y517800D01*
G01X1792000Y544622D02*
Y519678D01*
G01X1846416Y465208D02*
X1828754D01*
G01X1806024Y529376D02*
X1806076Y529324D01*
G01X1806024Y545176D02*
Y529376D01*
G01X1804600Y546600D02*
X1806024Y545176D01*
G01X1804600Y553573D02*
Y546600D01*
G01X1809008Y557981D02*
X1804600Y553573D01*
G01X1809008Y561428D02*
Y557981D01*
G01X1811963Y564383D02*
X1809008Y561428D01*
G01X1811963Y572088D02*
Y564383D01*
G01X1809350Y574701D02*
X1811963Y572088D01*
G01X1805562Y574701D02*
X1809350D01*
G01X1779200Y548339D02*
X1805562Y574701D01*
G01X1779200Y544369D02*
Y548339D01*
G01X1775264Y540433D02*
X1779200Y544369D01*
G01X1826252Y540653D02*
X1822400Y536801D01*
G01X1826252Y581705D02*
Y540653D01*
G01X1828834Y584287D02*
X1826252Y581705D01*
G01X1829176Y584287D02*
X1828834D01*
G01X1788229Y566500D02*
X1780729Y559000D01*
G01X1789300Y566500D02*
X1788229D01*
G01X1801338Y578538D02*
X1789300Y566500D01*
G01X1810436Y578538D02*
X1801338D01*
G01X1815351Y573623D02*
X1810436Y578538D01*
G01X1816074Y573623D02*
X1815351D01*
G01X1817751Y571946D02*
X1816074Y573623D01*
G01X1817751Y554971D02*
Y571946D01*
G01X1816280Y553500D02*
X1817751Y554971D01*
G01X1835000Y538800D02*
Y550300D01*
G01X1828200Y532000D02*
X1835000Y538800D01*
G01X1802924Y586800D02*
X1811100D01*
G01X1798328Y582204D02*
X1802924Y586800D01*
G01X1784989Y582204D02*
X1798328D01*
G01X1783061Y584132D02*
X1784989Y582204D01*
G01X1783061Y587439D02*
Y584132D01*
G01X1780308Y590192D02*
X1783061Y587439D01*
G01X1819909Y529293D02*
X1818509Y527893D01*
G01X1819909Y540679D02*
Y529293D01*
G01X1822528Y543298D02*
X1819909Y540679D01*
G01X1822528Y573948D02*
Y543298D01*
G01X1815055Y581421D02*
X1822528Y573948D01*
G01X1811671Y581421D02*
X1815055D01*
G01X1811202Y580952D02*
X1811671Y581421D01*
G01X1784470Y580952D02*
X1811202D01*
G01X1781808Y583614D02*
X1784470Y580952D01*
G01X1781808Y584650D02*
Y583614D01*
G01X1781809Y584651D02*
X1781808Y584650D01*
G01X1781809Y584868D02*
Y584651D01*
G01X1781177Y585500D02*
X1781809Y584868D01*
G01X1779000Y585500D02*
X1781177D01*
G01X1784876Y569424D02*
X1782000Y572300D01*
G01X1790424Y569424D02*
X1784876D01*
G01X1800781Y579781D02*
X1790424Y569424D01*
G01X1811661Y579781D02*
X1800781D01*
G01X1812149Y580269D02*
X1811661Y579781D01*
G01X1814577Y580269D02*
X1812149D01*
G01X1821376Y573470D02*
X1814577Y580269D01*
G01X1821376Y543776D02*
Y573470D01*
G01X1818757Y541157D02*
X1821376Y543776D01*
G01X1818757Y530440D02*
Y541157D01*
G01X1815224Y526907D02*
X1818757Y530440D01*
G01X1804920Y577319D02*
X1785101Y557500D01*
G01X1809992Y577319D02*
X1804920D01*
G01X1814444Y572867D02*
X1809992Y577319D01*
G01X1814444Y552236D02*
Y572867D01*
G01X1816280Y550400D02*
X1814444Y552236D01*
G01X1816876Y584925D02*
X1816052Y584101D01*
G01X1818182Y584925D02*
X1816876D01*
G01X1825300Y577807D02*
X1818182Y584925D01*
G01X1825300Y541048D02*
Y577807D01*
G01X1821448Y537196D02*
X1825300Y541048D01*
G01X1793551Y546173D02*
X1792000Y544622D01*
G01X1793551Y549751D02*
Y546173D01*
G01X1793900Y550100D02*
X1793551Y549751D01*
G01X1805381Y576150D02*
X1781816Y552585D01*
G01X1809531Y576150D02*
X1805381D01*
G01X1813292Y572389D02*
X1809531Y576150D01*
G01X1813292Y548062D02*
Y572389D01*
G01X1814754Y546600D02*
X1813292Y548062D01*
G01X1814754Y532372D02*
Y546600D01*
G01X1816584Y530542D02*
X1814754Y532372D01*
G01X1832724Y615604D02*
X1829665Y618663D01*
G01X1832724Y614452D02*
Y615604D01*
G01X1855799Y591377D02*
X1832724Y614452D01*
G01X1823926Y624402D02*
X1829665Y618663D01*
G01X1782501Y590698D02*
X1779399Y593800D01*
G01X1804598Y590698D02*
X1782501D01*
G01X1807300Y593400D02*
X1804598Y590698D01*
G01X1815200Y593400D02*
X1807300D01*
G01X1817212Y595412D02*
X1815200Y593400D01*
G01X1821907Y595412D02*
X1817212D01*
G01X1822273Y595046D02*
X1821907Y595412D01*
G01X1795000Y599600D02*
X1791826Y602774D01*
G01X1829051Y591949D02*
Y591299D01*
G01X1824300Y596700D02*
X1829051Y591949D01*
G01X1816138Y596700D02*
X1824300D01*
G01X1814138Y594700D02*
X1816138Y596700D01*
G01X1806700Y594700D02*
X1814138D01*
G01X1803950Y591950D02*
X1806700Y594700D01*
G01X1783020Y591950D02*
X1803950D01*
G01X1779122Y595848D02*
X1783020Y591950D01*
G01X1834480Y602920D02*
X1845000Y592400D01*
G01X1815420Y602920D02*
X1834480D01*
G01X1797192Y621148D02*
X1815420Y602920D01*
G01X1780648Y621148D02*
X1797192D01*
G01X1778400Y618900D02*
X1780648Y621148D01*
G01X1817618Y610710D02*
X1809665Y618663D01*
G01X1831493Y610710D02*
X1817618D01*
G01X1851923Y590280D02*
X1831493Y610710D01*
G01X1804678Y623650D02*
X1809665Y618663D01*
G01X1800352Y597702D02*
Y596101D01*
G01X1793802Y604252D02*
X1800352Y597702D01*
G01X1834875Y603872D02*
X1847997Y590750D01*
G01X1815556Y603872D02*
X1834875D01*
G01X1797380Y622048D02*
X1815556Y603872D01*
G01X1777348Y622048D02*
X1797380D01*
G01X1776500Y621200D02*
X1777348Y622048D01*
G01X1784200Y593924D02*
X1780824Y597300D01*
G01X1842011Y32547D02*
X1836430D01*
G01X1844440Y34976D02*
X1842011Y32547D01*
G01X1845900Y7100D02*
X1839828Y1028D01*
G01X1845900Y11200D02*
Y7100D01*
G01X1845366Y11734D02*
X1845900Y11200D01*
G01X1844767Y11734D02*
X1845366D01*
G01X1843800Y12701D02*
X1844767Y11734D01*
G01X1843800Y15800D02*
Y12701D01*
G01X1844238Y16238D02*
X1843800Y15800D01*
G01X1844238Y30788D02*
Y16238D01*
G01X1846381Y32931D02*
X1844238Y30788D01*
G01X1854895Y32096D02*
X1853467Y33524D01*
G01X1867446Y32096D02*
X1854895D01*
G01X1876116Y40766D02*
X1867446Y32096D01*
G01X1891131Y-4874D02*
X1898472Y-12215D01*
G01X1891131Y51451D02*
Y-4874D01*
G01X1848322Y7892D02*
X1840306Y-124D01*
G01X1848322Y12723D02*
Y7892D01*
G01X1890729Y75343D02*
X1901911Y86525D01*
G01X1887038Y75343D02*
X1890729D01*
G01X1881089Y69394D02*
X1887038Y75343D01*
G01X1877683Y69394D02*
X1881089D01*
G01X1857147Y48858D02*
X1877683Y69394D01*
G01X1852798Y48858D02*
X1857147D01*
G01X1847747Y43807D02*
X1852798Y48858D01*
G01X1874602Y77420D02*
X1858081Y60899D01*
G01X1874602Y83104D02*
Y77420D01*
G01X1876834Y85336D02*
X1874602Y83104D01*
G01X1876834Y85832D02*
Y85336D01*
G01X1874972Y87695D02*
X1876834Y85832D01*
G01X1874972Y88191D02*
Y87695D01*
G01X1876140Y89359D02*
X1874972Y88191D01*
G01X1876636Y89359D02*
X1876140D01*
G01X1878498Y87496D02*
X1876636Y89359D01*
G01X1878994Y87496D02*
X1878498D01*
G01X1880162Y88664D02*
X1878994Y87496D01*
G01X1880162Y89160D02*
Y88664D01*
G01X1878300Y91023D02*
X1880162Y89160D01*
G01X1878300Y91519D02*
Y91023D01*
G01X1879511Y92730D02*
X1878300Y91519D01*
G01X1889580Y92730D02*
X1879511D01*
G01X1889718Y92868D02*
X1889580Y92730D01*
G01X1889911Y92868D02*
X1889718D01*
G01X1895450Y98407D02*
X1889911Y92868D01*
G01X1877096Y94297D02*
X1878569Y95770D01*
G01X1876598Y94297D02*
X1877096D01*
G01X1874697Y96198D02*
X1876598Y94297D01*
G01X1874934Y92633D02*
X1873033Y94534D01*
G01X1874934Y92135D02*
Y92633D01*
G01X1873768Y90969D02*
X1874934Y92135D01*
G01X1873270Y90969D02*
X1873768D01*
G01X1871369Y92870D02*
X1873270Y90969D01*
G01X1870871Y92870D02*
X1871369D01*
G01X1869705Y91704D02*
X1870871Y92870D01*
G01X1869705Y91206D02*
Y91704D01*
G01X1871606Y89305D02*
X1869705Y91206D01*
G01X1871606Y88807D02*
Y89305D01*
G01X1870468Y87669D02*
X1871606Y88807D01*
G01X1870468Y77303D02*
Y87669D01*
G01X1857202Y64037D02*
X1870468Y77303D01*
G01X1852349Y49810D02*
X1847298Y44759D01*
G01X1856752Y49810D02*
X1852349D01*
G01X1877288Y70346D02*
X1856752Y49810D01*
G01X1880522Y70346D02*
X1877288D01*
G01X1900959Y90783D02*
X1880522Y70346D01*
G01X1841700Y33300D02*
X1836741D01*
G01X1843400Y35000D02*
X1841700Y33300D01*
G01X1843400Y38059D02*
Y35000D01*
G01X1853247Y47906D02*
X1843400Y38059D01*
G01X1857542Y47906D02*
X1853247D01*
G01X1878078Y68442D02*
X1857542Y47906D01*
G01X1881484Y68442D02*
X1878078D01*
G01X1887433Y74391D02*
X1881484Y68442D01*
G01X1891124Y74391D02*
X1887433D01*
G01X1894066Y77333D02*
X1891124Y74391D01*
G01X1896426Y77333D02*
X1894066D01*
G01X1896970Y76789D02*
X1896426Y77333D01*
G01X1896970Y73460D02*
Y76789D01*
G01X1851850Y50810D02*
X1846751Y45711D01*
G01X1856405Y50810D02*
X1851850D01*
G01X1876893Y71298D02*
X1856405Y50810D01*
G01X1880127Y71298D02*
X1876893D01*
G01X1900007Y91178D02*
X1880127Y71298D01*
G01X1873020Y77763D02*
X1857620Y62363D01*
G01X1873020Y88152D02*
Y77763D01*
G01X1879088Y94220D02*
X1873020Y88152D01*
G01X1889350Y94220D02*
X1879088D01*
G01X1894098Y98968D02*
X1889350Y94220D01*
G01X1844440Y37999D02*
Y34976D01*
G01X1853351Y46910D02*
X1844440Y37999D01*
G01X1857610Y46910D02*
X1853351D01*
G01X1878390Y67690D02*
X1857610Y46910D01*
G01X1881796Y67690D02*
X1878390D01*
G01X1887745Y73639D02*
X1881796Y67690D01*
G01X1891436Y73639D02*
X1887745D01*
G01X1893447Y75650D02*
X1891436Y73639D01*
G01X1895354Y75650D02*
X1893447D01*
G01X1851448Y41348D02*
X1850600D01*
G01X1854300Y44200D02*
X1851448Y41348D01*
G01X1867026Y44200D02*
X1854300D01*
G01X1869170Y46344D02*
X1867026Y44200D01*
G01X1869170Y47710D02*
Y46344D01*
G01X1879400Y57940D02*
X1869170Y47710D01*
G01X1879400Y61967D02*
Y57940D01*
G01X1888720Y71287D02*
X1879400Y61967D01*
G01X1899887Y71287D02*
X1888720D01*
G01X1846381Y34289D02*
Y32931D01*
G01X1846527Y34435D02*
X1846381Y34289D01*
G01X1853467Y33524D02*
Y35000D01*
G01X1876116Y44236D02*
Y40766D01*
G01X1878668Y46788D02*
X1876116Y44236D01*
G01X1880888Y46788D02*
X1878668D01*
G01X1886000Y51900D02*
X1880888Y46788D01*
G01X1886000Y60800D02*
Y51900D01*
G01X1891783Y66583D02*
X1886000Y60800D01*
G01X1901837Y66583D02*
X1891783D01*
G01X1856114Y54600D02*
X1835562D01*
G01X1877610Y76096D02*
X1856114Y54600D01*
G01X1877610Y81630D02*
Y76096D01*
G01X1883363Y87383D02*
X1877610Y81630D01*
G01X1889419Y87383D02*
X1883363D01*
G01X1898393Y96357D02*
X1889419Y87383D01*
G01X1907280Y67600D02*
X1891131Y51451D01*
G01X1878850Y72250D02*
X1883200Y76600D01*
G01X1876006Y72250D02*
X1878850D01*
G01X1856684Y52928D02*
X1876006Y72250D01*
G01X1890808Y68935D02*
X1900862D01*
G01X1882800Y60927D02*
X1890808Y68935D01*
G01X1882800Y52027D02*
Y60927D01*
G01X1879913Y49140D02*
X1882800Y52027D01*
G01X1876830Y49140D02*
X1879913D01*
G01X1873680Y45990D02*
X1876830Y49140D01*
G01X1873680Y41950D02*
Y45990D01*
G01X1867872Y36142D02*
X1873680Y41950D01*
G01X1858147Y36142D02*
X1867872D01*
G01X1857486Y36803D02*
X1858147Y36142D01*
G01X1857486Y38714D02*
Y36803D01*
G01X1855400Y40800D02*
X1857486Y38714D01*
G01X1888844Y88800D02*
X1896985Y96941D01*
G01X1882481Y88800D02*
X1888844D01*
G01X1876010Y82329D02*
X1882481Y88800D01*
G01X1876010Y76488D02*
Y82329D01*
G01X1857826Y58304D02*
X1876010Y76488D01*
G01X1864988Y103060D02*
X1843261D01*
G01X1870102Y108174D02*
X1864988Y103060D01*
G01X1887544Y108174D02*
X1870102D01*
G01X1890485Y111115D02*
X1887544Y108174D01*
G01X1890485Y125216D02*
Y111115D01*
G01X1898935Y133666D02*
X1890485Y125216D01*
G01X1866726Y143808D02*
X1869668Y146750D01*
G01X1865092Y143808D02*
X1866726D01*
G01X1865080Y143820D02*
X1865092Y143808D01*
G01X1862736Y143820D02*
X1865080D01*
G01X1862724Y143808D02*
X1862736Y143820D01*
G01X1855026Y143808D02*
X1862724D01*
G01X1850418Y139200D02*
X1855026Y143808D01*
G01X1841055Y139200D02*
X1850418D01*
G01X1875709Y135163D02*
X1872254Y138618D01*
G01X1884605Y135163D02*
X1875709D01*
G01X1888544Y139102D02*
X1884605Y135163D01*
G01X1888544Y143088D02*
Y139102D01*
G01X1891053Y145597D02*
X1888544Y143088D01*
G01X1891053Y187097D02*
Y145597D01*
G01X1855883Y128482D02*
X1857020Y129619D01*
G01X1850113Y128482D02*
X1855883D01*
G01X1849006Y129589D02*
X1850113Y128482D01*
G01X1859778Y153267D02*
X1862767Y156256D01*
G01X1856311Y153267D02*
X1859778D01*
G01X1853361Y150317D02*
X1856311Y153267D01*
G01X1846170Y150317D02*
X1853361D01*
G01X1840356Y144503D02*
X1846170Y150317D01*
G01X1838916Y144503D02*
X1840356D01*
G01X1895450Y124900D02*
Y98407D01*
G01X1902245Y131695D02*
X1895450Y124900D01*
G01X1870337Y142556D02*
X1872400Y144619D01*
G01X1864573Y142556D02*
X1870337D01*
G01X1864561Y142568D02*
X1864573Y142556D01*
G01X1863255Y142568D02*
X1864561D01*
G01X1863243Y142556D02*
X1863255Y142568D01*
G01X1855545Y142556D02*
X1863243D01*
G01X1850600Y137611D02*
X1855545Y142556D01*
G01X1841237Y137611D02*
X1850600D01*
G01X1881324Y152495D02*
Y153250D01*
G01X1879144Y150315D02*
X1881324Y152495D01*
G01X1874266Y150315D02*
X1879144D01*
G01X1873484Y151097D02*
X1874266Y150315D01*
G01X1872601Y151097D02*
X1873484D01*
G01X1872569Y151065D02*
X1872601Y151097D01*
G01X1870473Y151065D02*
X1872569D01*
G01X1870441Y151097D02*
X1870473Y151065D01*
G01X1857565Y151097D02*
X1870441D01*
G01X1854681Y148213D02*
X1857565Y151097D01*
G01X1847043Y148213D02*
X1854681D01*
G01X1841196Y142366D02*
X1847043Y148213D01*
G01X1840903Y142366D02*
X1841196D01*
G01X1840903Y142356D02*
Y142366D01*
G01X1839746Y142356D02*
X1840903D01*
G01X1839878Y145655D02*
X1838293D01*
G01X1845692Y151469D02*
X1839878Y145655D01*
G01X1852883Y151469D02*
X1845692D01*
G01X1855833Y154419D02*
X1852883Y151469D01*
G01X1859300Y154419D02*
X1855833D01*
G01X1860624Y155743D02*
X1859300Y154419D01*
G01X1860624Y170946D02*
Y155743D01*
G01X1892550Y125522D02*
X1900144Y133116D01*
G01X1892550Y99890D02*
Y125522D01*
G01X1888430Y95770D02*
X1892550Y99890D01*
G01X1878569Y95770D02*
X1888430D01*
G01X1874199Y96198D02*
X1874697D01*
G01X1873033Y95032D02*
X1874199Y96198D01*
G01X1873033Y94534D02*
Y95032D01*
G01X1843856Y152116D02*
Y159194D01*
G01X1839425Y147685D02*
X1843856Y152116D01*
G01X1837756Y147685D02*
X1839425D01*
G01X1839566Y146407D02*
X1837851D01*
G01X1844925Y151766D02*
X1839566Y146407D01*
G01X1844925Y158805D02*
Y151766D01*
G01X1841664Y141204D02*
X1840224D01*
G01X1847437Y146977D02*
X1841664Y141204D01*
G01X1850284Y146977D02*
X1847437D01*
G01X1851324Y145937D02*
X1850284Y146977D01*
G01X1858145Y145937D02*
X1851324D01*
G01X1862153Y149945D02*
X1858145Y145937D01*
G01X1869963Y149945D02*
X1862153D01*
G01X1869995Y149913D02*
X1869963Y149945D01*
G01X1873038Y149913D02*
X1869995D01*
G01X1874214Y148737D02*
X1873038Y149913D01*
G01X1879414Y148737D02*
X1874214D01*
G01X1879482Y148805D02*
X1879414Y148737D01*
G01X1879535Y148805D02*
X1879482D01*
G01X1883015Y152285D02*
X1879535Y148805D01*
G01X1883015Y155328D02*
Y152285D01*
G01X1882920Y155423D02*
X1883015Y155328D01*
G01X1882920Y158394D02*
Y155423D01*
G01X1850991Y106008D02*
X1842772D01*
G01X1851341Y106358D02*
X1850991Y106008D01*
G01X1890448Y139957D02*
X1898466Y147975D01*
G01X1890448Y137763D02*
Y139957D01*
G01X1885203Y132518D02*
X1890448Y137763D01*
G01X1866818Y132518D02*
X1885203D01*
G01X1860861Y126561D02*
X1866818Y132518D01*
G01X1860861Y125039D02*
Y126561D01*
G01X1859755Y123933D02*
X1860861Y125039D01*
G01X1859755Y119745D02*
Y123933D01*
G01X1847548Y107538D02*
X1859755Y119745D01*
G01X1894098Y125548D02*
Y98968D01*
G01X1901021Y132471D02*
X1894098Y125548D01*
G01X1862400Y121300D02*
Y124500D01*
G01X1847860Y106760D02*
X1862400Y121300D01*
G01X1842460Y106760D02*
X1847860D01*
G01X1890787Y136099D02*
X1895060D01*
G01X1884928Y130240D02*
X1890787Y136099D01*
G01X1869704Y130240D02*
X1884928D01*
G01X1867412Y127948D02*
X1869704Y130240D01*
G01X1867412Y117243D02*
Y127948D01*
G01X1864904Y114735D02*
X1867412Y117243D01*
G01X1841655Y156070D02*
Y158669D01*
G01X1840738Y155153D02*
X1841655Y156070D01*
G01X1889696Y140269D02*
X1897376Y147949D01*
G01X1889696Y138075D02*
Y140269D01*
G01X1884891Y133270D02*
X1889696Y138075D01*
G01X1866506Y133270D02*
X1884891D01*
G01X1860109Y126873D02*
X1866506Y133270D01*
G01X1860109Y125351D02*
Y126873D01*
G01X1859003Y124245D02*
X1860109Y125351D01*
G01X1859003Y120183D02*
Y124245D01*
G01X1847110Y108290D02*
X1859003Y120183D01*
G01X1841976Y140452D02*
X1840536D01*
G01X1842239Y140715D02*
X1841976Y140452D01*
G01X1842321Y140715D02*
X1842239D01*
G01X1847831Y146225D02*
X1842321Y140715D01*
G01X1849972Y146225D02*
X1847831D01*
G01X1851012Y145185D02*
X1849972Y146225D01*
G01X1858457Y145185D02*
X1851012D01*
G01X1862116Y148844D02*
X1858457Y145185D01*
G01X1873043Y148844D02*
X1862116D01*
G01X1873948Y147939D02*
X1873043Y148844D01*
G01X1879733Y147939D02*
X1873948D01*
G01X1883862Y152068D02*
X1879733Y147939D01*
G01X1883862Y155545D02*
Y152068D01*
G01X1883672Y155735D02*
X1883862Y155545D01*
G01X1883672Y158773D02*
Y155735D01*
G01X1840834Y143351D02*
X1839394D01*
G01X1846648Y149165D02*
X1840834Y143351D01*
G01X1854226Y149165D02*
X1846648D01*
G01X1857110Y152049D02*
X1854226Y149165D01*
G01X1870836Y152049D02*
X1857110D01*
G01X1870868Y152017D02*
X1870836Y152049D01*
G01X1872174Y152017D02*
X1870868D01*
G01X1872206Y152049D02*
X1872174Y152017D01*
G01X1874549Y152049D02*
X1872206D01*
G01X1875425Y152925D02*
X1874549Y152049D01*
G01X1864676Y103812D02*
X1842949D01*
G01X1869790Y108926D02*
X1864676Y103812D01*
G01X1887232Y108926D02*
X1869790D01*
G01X1889733Y111427D02*
X1887232Y108926D01*
G01X1889733Y125955D02*
Y111427D01*
G01X1897885Y134107D02*
X1889733Y125955D01*
G01X1840310Y130341D02*
X1845469Y135500D01*
G01X1896985Y103696D02*
X1899914Y106625D01*
G01X1896985Y96941D02*
Y103696D01*
G01X1836437Y151406D02*
X1836419Y151388D01*
G01X1837743Y151406D02*
X1836437D01*
G01X1837761Y151388D02*
X1837743Y151406D01*
G01X1838091Y151388D02*
X1837761D01*
G01X1838091Y151341D02*
Y151388D01*
G01X1839014Y150418D02*
X1838091Y151341D01*
G01X1840517Y150418D02*
X1839014D01*
G01X1842664Y152565D02*
X1840517Y150418D01*
G01X1842664Y158614D02*
Y152565D01*
G01X1855909Y127730D02*
X1857020Y126619D01*
G01X1849801Y127730D02*
X1855909D01*
G01X1848694Y128837D02*
X1849801Y127730D01*
G01X1858251Y120495D02*
X1846987Y109231D01*
G01X1858251Y123933D02*
Y120495D01*
G01X1858250Y123934D02*
X1858251Y123933D01*
G01X1858250Y124556D02*
Y123934D01*
G01X1859348Y125654D02*
X1858250Y124556D01*
G01X1859348Y127584D02*
Y125654D01*
G01X1859347Y127585D02*
X1859348Y127584D01*
G01X1859347Y128653D02*
Y127585D01*
G01X1859349Y128655D02*
X1859347Y128653D01*
G01X1859349Y129277D02*
Y128655D01*
G01X1859348Y129278D02*
X1859349Y129277D01*
G01X1859348Y130584D02*
Y129278D01*
G01X1859347Y130585D02*
X1859348Y130584D01*
G01X1859347Y136976D02*
Y130585D01*
G01X1861035Y138664D02*
X1859347Y136976D01*
G01X1867200Y138664D02*
X1861035D01*
G01X1868730Y140194D02*
X1867200Y138664D01*
G01X1876365Y140194D02*
X1868730D01*
G01X1884747Y148576D02*
X1876365Y140194D01*
G01X1886500Y148576D02*
X1884747D01*
G01X1889901Y151977D02*
X1886500Y148576D01*
G01X1889901Y186407D02*
Y151977D01*
G01X1857499Y120807D02*
X1846875Y110183D01*
G01X1857499Y123621D02*
Y120807D01*
G01X1857498Y123622D02*
X1857499Y123621D01*
G01X1857498Y124868D02*
Y123622D01*
G01X1858596Y125966D02*
X1857498Y124868D01*
G01X1858596Y127272D02*
Y125966D01*
G01X1858595Y127273D02*
X1858596Y127272D01*
G01X1858595Y128965D02*
Y127273D01*
G01X1858596Y128966D02*
X1858595Y128965D01*
G01X1858596Y130272D02*
Y128966D01*
G01X1858595Y130273D02*
X1858596Y130272D01*
G01X1858595Y137288D02*
Y130273D01*
G01X1860723Y139416D02*
X1858595Y137288D01*
G01X1866888Y139416D02*
X1860723D01*
G01X1868418Y140946D02*
X1866888Y139416D01*
G01X1876053Y140946D02*
X1868418D01*
G01X1884435Y149328D02*
X1876053Y140946D01*
G01X1886188Y149328D02*
X1884435D01*
G01X1889149Y152289D02*
X1886188Y149328D01*
G01X1889149Y186095D02*
Y152289D01*
G01X1884424Y156047D02*
Y159932D01*
G01X1886299Y154172D02*
X1884424Y156047D01*
G01X1886299Y153928D02*
Y154172D01*
G01X1864364Y104564D02*
X1842605D01*
G01X1869478Y109678D02*
X1864364Y104564D01*
G01X1886920Y109678D02*
X1869478D01*
G01X1888981Y111739D02*
X1886920Y109678D01*
G01X1888981Y126917D02*
Y111739D01*
G01X1896981Y134917D02*
X1888981Y126917D01*
G01X1896981Y138776D02*
Y134917D01*
G01X1898064Y139859D02*
X1896981Y138776D01*
G01X1844164Y166405D02*
X1837929Y160170D01*
G01X1844164Y168678D02*
Y166405D01*
G01X1845510Y170024D02*
X1844164Y168678D01*
G01X1854137Y170024D02*
X1845510D01*
G01X1859100Y174987D02*
X1854137Y170024D01*
G01X1859100Y176848D02*
Y174987D01*
G01X1864000Y181748D02*
X1859100Y176848D01*
G01X1864000Y184900D02*
Y181748D01*
G01X1887790Y190360D02*
X1891053Y187097D01*
G01X1887790Y202810D02*
Y190360D01*
G01X1884270Y206330D02*
X1887790Y202810D01*
G01X1881904Y206330D02*
X1884270D01*
G01X1877027Y211207D02*
X1881904Y206330D01*
G01X1877027Y214961D02*
Y211207D01*
G01X1879093Y217027D02*
X1877027Y214961D01*
G01X1879093Y218641D02*
Y217027D01*
G01X1875556Y156256D02*
X1875600Y156300D01*
G01X1862767Y156256D02*
X1875556D01*
G01X1840357Y176335D02*
X1837355Y173333D01*
G01X1844564Y176335D02*
X1840357D01*
G01X1850000Y181771D02*
X1844564Y176335D01*
G01X1850000Y205964D02*
Y181771D01*
G01X1857242Y213206D02*
X1850000Y205964D01*
G01X1859604Y213206D02*
X1857242D01*
G01X1873369Y210931D02*
X1876700Y207600D01*
G01X1871223Y210931D02*
X1873369D01*
G01X1871222Y210930D02*
X1871223Y210931D01*
G01X1870599Y210930D02*
X1871222D01*
G01X1869387Y212142D02*
X1870599Y210930D01*
G01X1869387Y212470D02*
Y212142D01*
G01X1869380Y212477D02*
X1869387Y212470D01*
G01X1869380Y220300D02*
Y212477D01*
G01X1861750Y172072D02*
X1860624Y170946D01*
G01X1866220Y172072D02*
X1861750D01*
G01X1869677Y175529D02*
X1866220Y172072D01*
G01X1869677Y199914D02*
Y175529D01*
G01X1867267Y202324D02*
X1869677Y199914D01*
G01X1867267Y208573D02*
Y202324D01*
G01X1867883Y209189D02*
X1867267Y208573D01*
G01X1867883Y211846D02*
Y209189D01*
G01X1867876Y211853D02*
X1867883Y211846D01*
G01X1867876Y218106D02*
Y211853D01*
G01X1866383Y201861D02*
X1864637D01*
G01X1868725Y199519D02*
X1866383Y201861D01*
G01X1868725Y175924D02*
Y199519D01*
G01X1865825Y173024D02*
X1868725Y175924D01*
G01X1860895Y173024D02*
X1865825D01*
G01X1857904Y170033D02*
X1860895Y173024D01*
G01X1857904Y164084D02*
Y170033D01*
G01X1855293Y161473D02*
X1857904Y164084D01*
G01X1846135Y161473D02*
X1855293D01*
G01X1843856Y159194D02*
X1846135Y161473D01*
G01X1856581Y211481D02*
X1861497D01*
G01X1850950Y205850D02*
X1856581Y211481D01*
G01X1850950Y181657D02*
Y205850D01*
G01X1844678Y175385D02*
X1850950Y181657D01*
G01X1840751Y175385D02*
X1844678D01*
G01X1837749Y172383D02*
X1840751Y175385D01*
G01X1846593Y160473D02*
X1844925Y158805D01*
G01X1855964Y160473D02*
X1846593D01*
G01X1857919Y158518D02*
X1855964Y160473D01*
G01X1857919Y156123D02*
Y158518D01*
G01X1877167Y164147D02*
X1882920Y158394D01*
G01X1877167Y171205D02*
Y164147D01*
G01X1875110Y173262D02*
X1877167Y171205D01*
G01X1875110Y175782D02*
Y173262D01*
G01X1875066Y175782D02*
X1875110D01*
G01X1875519Y215083D02*
X1874236Y213800D01*
G01X1875519Y242190D02*
Y215083D01*
G01X1892791Y200069D02*
X1897871D01*
G01X1881784Y209569D02*
Y218644D01*
G01X1882732Y208621D02*
X1881784Y209569D01*
G01X1884883Y208621D02*
X1882732D01*
G01X1889870Y203634D02*
X1884883Y208621D01*
G01X1889870Y195109D02*
Y203634D01*
G01X1893650Y191329D02*
X1889870Y195109D01*
G01X1893650Y163571D02*
Y191329D01*
G01X1898466Y158755D02*
X1893650Y163571D01*
G01X1891150Y195910D02*
X1899120Y187940D01*
G01X1891150Y203640D02*
Y195910D01*
G01X1891880Y204370D02*
X1891150Y203640D01*
G01X1844100Y198950D02*
X1847200Y202050D01*
G01X1844100Y194286D02*
Y198950D01*
G01X1870132Y212789D02*
Y220612D01*
G01X1870139Y212782D02*
X1870132Y212789D01*
G01X1870139Y212455D02*
Y212782D01*
G01X1870911Y211683D02*
X1870139Y212455D01*
G01X1874921Y211683D02*
X1870911D01*
G01X1882242Y204362D02*
X1874921Y211683D01*
G01X1883915Y204362D02*
X1882242D01*
G01X1886093Y202184D02*
X1883915Y204362D01*
G01X1865576Y197354D02*
X1864464Y198466D01*
G01X1865576Y178681D02*
Y197354D01*
G01X1861865Y174970D02*
X1865576Y178681D01*
G01X1861727Y174970D02*
X1861865D01*
G01X1861725Y174972D02*
X1861727Y174970D01*
G01X1861103Y174972D02*
X1861725D01*
G01X1861102Y174971D02*
X1861103Y174972D01*
G01X1860148Y174971D02*
X1861102D01*
G01X1851477Y166300D02*
X1860148Y174971D01*
G01X1846959Y166300D02*
X1851477D01*
G01X1841951Y161292D02*
X1846959Y166300D01*
G01X1841951Y158965D02*
Y161292D01*
G01X1841655Y158669D02*
X1841951Y158965D01*
G01X1880655Y209531D02*
Y218709D01*
G01X1882517Y207669D02*
X1880655Y209531D01*
G01X1884771Y207669D02*
X1882517D01*
G01X1889117Y203323D02*
X1884771Y207669D01*
G01X1889117Y194498D02*
Y203323D01*
G01X1892700Y190915D02*
X1889117Y194498D01*
G01X1892700Y163200D02*
Y190915D01*
G01X1897376Y158524D02*
X1892700Y163200D01*
G01X1895614Y204785D02*
X1909975Y190424D01*
G01X1877967Y164478D02*
X1883672Y158773D01*
G01X1877967Y172784D02*
Y164478D01*
G01X1876832Y173919D02*
X1877967Y172784D01*
G01X1837797Y156858D02*
X1839941D01*
G01X1895100Y201770D02*
X1897469D01*
G01X1840356Y169257D02*
X1840001Y168902D01*
G01X1840356Y170258D02*
Y169257D01*
G01X1843931Y173833D02*
X1840356Y170258D01*
G01X1846033Y173833D02*
X1843931D01*
G01X1852200Y180000D02*
X1846033Y173833D01*
G01X1852200Y188440D02*
Y180000D01*
G01X1856682Y192922D02*
X1852200Y188440D01*
G01X1856686Y192925D02*
X1856682Y192922D01*
G01X1857163Y193402D02*
X1856686Y192925D01*
G01X1857166Y193406D02*
X1857163Y193402D01*
G01X1857927Y194167D02*
X1857166Y193406D01*
G01X1857927Y197072D02*
Y194167D01*
G01X1855972Y199028D02*
X1857927Y197072D01*
G01X1855972Y202972D02*
Y199028D01*
G01X1856594Y203594D02*
X1855972Y202972D01*
G01X1856594Y205506D02*
Y203594D01*
G01X1855670Y206430D02*
X1856594Y205506D01*
G01X1843012Y166966D02*
X1837368Y161322D01*
G01X1843012Y169156D02*
Y166966D01*
G01X1845032Y171176D02*
X1843012Y169156D01*
G01X1848541Y171176D02*
X1845032D01*
G01X1853324Y175959D02*
X1848541Y171176D01*
G01X1853324Y176553D02*
Y175959D01*
G01X1854247Y177476D02*
X1853324Y176553D01*
G01X1854841Y177476D02*
X1854247D01*
G01X1855418Y178053D02*
X1854841Y177476D01*
G01X1858675Y178053D02*
X1855418D01*
G01X1861243Y180621D02*
X1858675Y178053D01*
G01X1861243Y183100D02*
Y180621D01*
G01X1842704Y158654D02*
X1842664Y158614D01*
G01X1842704Y158716D02*
Y158654D01*
G01X1842703Y158717D02*
X1842704Y158716D01*
G01X1842703Y159671D02*
Y158717D01*
G01X1845658Y162626D02*
X1842703Y159671D01*
G01X1846612Y162626D02*
X1845658D01*
G01X1846613Y162625D02*
X1846612Y162626D01*
G01X1853177Y162625D02*
X1846613D01*
G01X1856752Y166200D02*
X1853177Y162625D01*
G01X1856752Y170511D02*
Y166200D01*
G01X1860460Y174219D02*
X1856752Y170511D01*
G01X1861414Y174219D02*
X1860460D01*
G01X1861415Y174218D02*
X1861414Y174219D01*
G01X1862178Y174218D02*
X1861415D01*
G01X1866730Y178770D02*
X1862178Y174218D01*
G01X1866730Y199099D02*
Y178770D01*
G01X1865715Y200114D02*
X1866730Y199099D01*
G01X1862988Y200114D02*
X1865715D01*
G01X1862636Y200466D02*
X1862988Y200114D01*
G01X1862636Y207784D02*
Y200466D01*
G01X1865779Y210927D02*
X1862636Y207784D01*
G01X1865779Y210973D02*
Y210927D01*
G01X1865772Y210980D02*
X1865779Y210973D01*
G01X1865772Y212444D02*
Y210980D01*
G01X1865746Y212470D02*
X1865772Y212444D01*
G01X1865746Y212522D02*
Y212470D01*
G01X1864823Y213445D02*
X1865746Y212522D01*
G01X1864771Y213445D02*
X1864823D01*
G01X1862247Y215969D02*
X1864771Y213445D01*
G01X1840069Y215969D02*
X1862247D01*
G01X1835615Y211515D02*
X1840069Y215969D01*
G01X1886038Y190270D02*
X1889901Y186407D01*
G01X1886038Y197314D02*
Y190270D01*
G01X1883539Y199813D02*
X1886038Y197314D01*
G01X1884762Y190482D02*
X1889149Y186095D01*
G01X1884762Y196277D02*
Y190482D01*
G01X1881840Y199199D02*
X1884762Y196277D01*
G01X1881840Y200900D02*
Y199199D01*
G01X1883350Y202410D02*
X1881840Y200900D01*
G01X1868628Y212165D02*
Y219303D01*
G01X1868635Y212158D02*
X1868628Y212165D01*
G01X1868635Y211830D02*
Y212158D01*
G01X1870989Y209476D02*
X1868635Y211830D01*
G01X1872753Y209476D02*
X1870989D01*
G01X1873676Y208553D02*
X1872753Y209476D01*
G01X1873676Y192818D02*
Y208553D01*
G01X1878148Y188346D02*
X1873676Y192818D01*
G01X1878148Y174964D02*
Y188346D01*
G01X1880005Y173107D02*
X1878148Y174964D01*
G01X1880005Y164351D02*
Y173107D01*
G01X1884424Y159932D02*
X1880005Y164351D01*
G01X1864155Y211869D02*
X1864170D01*
G01X1864155Y211866D02*
Y211869D01*
G01X1864203Y211818D02*
X1864155Y211866D01*
G01X1864203Y211182D02*
Y211818D01*
G01X1860335Y207314D02*
X1864203Y211182D01*
G01X1860335Y184794D02*
Y207314D01*
G01X1854169Y178628D02*
X1860335Y184794D01*
G01X1853769Y178628D02*
X1854169D01*
G01X1852172Y177031D02*
X1853769Y178628D01*
G01X1852172Y176631D02*
Y177031D01*
G01X1847869Y172328D02*
X1852172Y176631D01*
G01X1845510Y172328D02*
X1847869D01*
G01X1845509Y172329D02*
X1845510Y172328D01*
G01X1844555Y172329D02*
X1845509D01*
G01X1841860Y169634D02*
X1844555Y172329D01*
G01X1841860Y167524D02*
Y169634D01*
G01X1837136Y162800D02*
X1841860Y167524D01*
G01X1841108Y168662D02*
X1840396Y167950D01*
G01X1841108Y169946D02*
Y168662D01*
G01X1844243Y173081D02*
X1841108Y169946D01*
G01X1846628Y173081D02*
X1844243D01*
G01X1853100Y179553D02*
X1846628Y173081D01*
G01X1853100Y187993D02*
Y179553D01*
G01X1858879Y193772D02*
X1853100Y187993D01*
G01X1858879Y197420D02*
Y193772D01*
G01X1856924Y199375D02*
X1858879Y197420D01*
G01X1856924Y202525D02*
Y199375D01*
G01X1857546Y203147D02*
X1856924Y202525D01*
G01X1857546Y205411D02*
Y203147D01*
G01X1858470Y206335D02*
X1857546Y205411D01*
G01X1876671Y221063D02*
X1879093Y218641D01*
G01X1876671Y241712D02*
Y221063D01*
G01X1876672Y241713D02*
X1876671Y241712D01*
G01X1876672Y242667D02*
Y241713D01*
G01X1871261Y248078D02*
X1876672Y242667D01*
G01X1861228Y248078D02*
X1871261D01*
G01X1846547Y233397D02*
X1861228Y248078D01*
G01X1846547Y226138D02*
Y233397D01*
G01X1844444Y224035D02*
X1846547Y226138D01*
G01X1866558Y223122D02*
X1869380Y220300D01*
G01X1850136Y223122D02*
X1866558D01*
G01X1846721Y219707D02*
X1850136Y223122D01*
G01X1840500Y219707D02*
X1846721D01*
G01X1867805Y218177D02*
X1867876Y218106D01*
G01X1867805Y219062D02*
Y218177D01*
G01X1865560Y221307D02*
X1867805Y219062D01*
G01X1858738Y221307D02*
X1865560D01*
G01X1856874Y219443D02*
X1858738Y221307D01*
G01X1870783Y246926D02*
X1875519Y242190D01*
G01X1861706Y246926D02*
X1870783D01*
G01X1847699Y232919D02*
X1861706Y246926D01*
G01X1847699Y223111D02*
Y232919D01*
G01X1847047Y222459D02*
X1847699Y223111D01*
G01X1839816Y222459D02*
X1847047D01*
G01X1857670Y247214D02*
X1844555D01*
G01X1860438Y249982D02*
X1857670Y247214D01*
G01X1872051Y249982D02*
X1860438D01*
G01X1878846Y243187D02*
X1872051Y249982D01*
G01X1878846Y221582D02*
Y243187D01*
G01X1881784Y218644D02*
X1878846Y221582D01*
G01X1846111Y220459D02*
X1840188D01*
G01X1849526Y223874D02*
X1846111Y220459D01*
G01X1867374Y223874D02*
X1849526D01*
G01X1870052Y221196D02*
X1867374Y223874D01*
G01X1870052Y220692D02*
Y221196D01*
G01X1870132Y220612D02*
X1870052Y220692D01*
G01X1857503Y245983D02*
X1844722D01*
G01X1860750Y249230D02*
X1857503Y245983D01*
G01X1871739Y249230D02*
X1860750D01*
G01X1878028Y242941D02*
X1871739Y249230D01*
G01X1878028Y221336D02*
Y242941D01*
G01X1880655Y218709D02*
X1878028Y221336D01*
G01X1857665Y257865D02*
X1861605Y253925D01*
G01X1864305Y253825D02*
X1859113Y259017D01*
G01X1847033Y218955D02*
X1841991D01*
G01X1850172Y222094D02*
X1847033Y218955D01*
G01X1865837Y222094D02*
X1850172D01*
G01X1868628Y219303D02*
X1865837Y222094D01*
G01X1850446Y466980D02*
X1846370Y462904D01*
G01X1861139Y463346D02*
X1866337Y468544D01*
G01X1856606Y463346D02*
X1861139D01*
G01X1852156Y458896D02*
X1856606Y463346D01*
G01X1857975Y458772D02*
X1842577Y443374D01*
G01X1877952Y458772D02*
X1857975D01*
G01X1884665Y465485D02*
X1877952Y458772D01*
G01X1855018Y441196D02*
X1850570Y436748D01*
G01X1938896Y441196D02*
X1855018D01*
G01X1854623Y442148D02*
X1850815Y438340D01*
G01X1936938Y442148D02*
X1854623D01*
G01X1857581Y459722D02*
X1842183Y444324D01*
G01X1877838Y459722D02*
X1857581D01*
G01X1883913Y465797D02*
X1877838Y459722D01*
G01X1851468Y466088D02*
X1847132Y461752D01*
G01X1857084Y462194D02*
X1852290Y457400D01*
G01X1870052Y462194D02*
X1857084D01*
G01X1878983Y471125D02*
X1870052Y462194D01*
G01X1847610Y460600D02*
X1852988Y465978D01*
G01X1856607Y438728D02*
X1853405Y435526D01*
G01X1910171Y438728D02*
X1856607D01*
G01X1860827Y464098D02*
X1865385Y468656D01*
G01X1856011Y464098D02*
X1860827D01*
G01X1851761Y459848D02*
X1856011Y464098D01*
G01X1850744Y444100D02*
X1928188D01*
G01X1847002Y440358D02*
X1850744Y444100D01*
G01X1857002Y437776D02*
X1853800Y434574D01*
G01X1910566Y437776D02*
X1857002D01*
G01X1850446Y475140D02*
Y466980D01*
G01X1862812Y487506D02*
X1850446Y475140D01*
G01X1862812Y496682D02*
Y487506D01*
G01X1861512Y497982D02*
X1862812Y496682D01*
G01X1858318Y497982D02*
X1861512D01*
G01X1856100Y500200D02*
X1858318Y497982D01*
G01X1856100Y525530D02*
Y500200D01*
G01X1852920Y528710D02*
X1856100Y525530D01*
G01X1864011Y521578D02*
X1870438Y528011D01*
G01X1864011Y515643D02*
Y521578D01*
G01X1862763Y514395D02*
X1864011Y515643D01*
G01X1862763Y507725D02*
Y514395D01*
G01X1869904Y500584D02*
X1862763Y507725D01*
G01X1869904Y488340D02*
Y500584D01*
G01X1866337Y484773D02*
X1869904Y488340D01*
G01X1866337Y468544D02*
Y484773D01*
G01X1842452Y477022D02*
X1843750Y475724D01*
G01X1842452Y477752D02*
Y477022D01*
G01X1844100Y479400D02*
X1842452Y477752D01*
G01X1844100Y488853D02*
Y479400D01*
G01X1846552Y491305D02*
X1844100Y488853D01*
G01X1846552Y499595D02*
Y491305D01*
G01X1843195Y502952D02*
X1846552Y499595D01*
G01X1884665Y482979D02*
Y465485D01*
G01X1880450Y487194D02*
X1884665Y482979D01*
G01X1880450Y502538D02*
Y487194D01*
G01X1868743Y514245D02*
X1880450Y502538D01*
G01X1868743Y516054D02*
Y514245D01*
G01X1869914Y517225D02*
X1868743Y516054D01*
G01X1883913Y482387D02*
Y465797D01*
G01X1879500Y486800D02*
X1883913Y482387D01*
G01X1879500Y502424D02*
Y486800D01*
G01X1867924Y514000D02*
X1879500Y502424D01*
G01X1867924Y515892D02*
Y514000D01*
G01X1866688Y517128D02*
X1867924Y515892D01*
G01X1848860Y513600D02*
Y541340D01*
G01X1844490Y509230D02*
X1848860Y513600D01*
G01X1851468Y474532D02*
Y466088D01*
G01X1867248Y490312D02*
X1851468Y474532D01*
G01X1867248Y499358D02*
Y490312D01*
G01X1859530Y507076D02*
X1867248Y499358D01*
G01X1859530Y516430D02*
Y507076D01*
G01X1850476Y501624D02*
Y549724D01*
G01X1856600Y495500D02*
X1850476Y501624D01*
G01X1860000Y495500D02*
X1856600D01*
G01X1878983Y482798D02*
Y471125D01*
G01X1875973Y485808D02*
X1878983Y482798D01*
G01X1875973Y499838D02*
Y485808D01*
G01X1845385Y472620D02*
X1843465Y470700D01*
G01X1845385Y488346D02*
Y472620D01*
G01X1847492Y490453D02*
X1845385Y488346D01*
G01X1858333Y490453D02*
X1847492D01*
G01X1862060Y494180D02*
X1858333Y490453D01*
G01X1862060Y496370D02*
Y494180D01*
G01X1861200Y497230D02*
X1862060Y496370D01*
G01X1857670Y497230D02*
X1861200D01*
G01X1854820Y500080D02*
X1857670Y497230D01*
G01X1854820Y524450D02*
Y500080D01*
G01X1851840Y527430D02*
X1854820Y524450D01*
G01X1862310Y522628D02*
X1866450Y526771D01*
G01X1862310Y516260D02*
Y522628D01*
G01X1861120Y515070D02*
X1862310Y516260D01*
G01X1861120Y507116D02*
Y515070D01*
G01X1868400Y499836D02*
X1861120Y507116D01*
G01X1868400Y489834D02*
Y499836D01*
G01X1852988Y474422D02*
X1868400Y489834D01*
G01X1852988Y465978D02*
Y474422D01*
G01X1863062Y522316D02*
X1869686Y528944D01*
G01X1863062Y515948D02*
Y522316D01*
G01X1862011Y514897D02*
X1863062Y515948D01*
G01X1862011Y507289D02*
Y514897D01*
G01X1869152Y500148D02*
X1862011Y507289D01*
G01X1869152Y488935D02*
Y500148D01*
G01X1865385Y485168D02*
X1869152Y488935D01*
G01X1865385Y468656D02*
Y485168D01*
G01X1845600Y499200D02*
X1842800Y502000D01*
G01X1845600Y491700D02*
Y499200D01*
G01X1843148Y489248D02*
X1845600Y491700D01*
G01X1843148Y479795D02*
Y489248D01*
G01X1841500Y478147D02*
X1843148Y479795D01*
G01X1841500Y476474D02*
Y478147D01*
G01X1840750Y475724D02*
X1841500Y476474D01*
G01X1839100Y510870D02*
X1842450Y507520D01*
G01X1839100Y523800D02*
Y510870D01*
G01X1837200Y525700D02*
X1839100Y523800D01*
G01X1847000Y465792D02*
X1846416Y465208D01*
G01X1847000Y487500D02*
Y465792D01*
G01X1852920Y538220D02*
Y528710D01*
G01X1856100Y541400D02*
X1852920Y538220D01*
G01X1856100Y542100D02*
Y541400D01*
G01X1858528Y544528D02*
X1856100Y542100D01*
G01X1867084Y580953D02*
X1856660Y591377D01*
G01X1867084Y541738D02*
Y580953D01*
G01X1870438Y538384D02*
X1867084Y541738D01*
G01X1870438Y528011D02*
Y538384D01*
G01X1861631Y550785D02*
X1859708Y552708D01*
G01X1861631Y540281D02*
Y550785D01*
G01X1854530Y533180D02*
X1861631Y540281D01*
G01X1854530Y533132D02*
Y533180D01*
G01X1846650Y545950D02*
X1848900Y548200D01*
G01X1846650Y543550D02*
Y545950D01*
G01X1848860Y541340D02*
X1846650Y543550D01*
G01X1866800Y588000D02*
X1867392Y588592D01*
G01X1850476Y549724D02*
X1848800Y551400D01*
G01X1895523Y586365D02*
X1905315D01*
G01X1851840Y540550D02*
Y527430D01*
G01X1854000Y542710D02*
X1851840Y540550D01*
G01X1854000Y549600D02*
Y542710D01*
G01X1857108Y552708D02*
X1854000Y549600D01*
G01X1856300Y554500D02*
X1854508Y552708D01*
G01X1860500Y554500D02*
X1856300D01*
G01X1865209Y549791D02*
X1860500Y554500D01*
G01X1865209Y539803D02*
Y549791D01*
G01X1866450Y538562D02*
X1865209Y539803D01*
G01X1866450Y526771D02*
Y538562D01*
G01X1865961Y581012D02*
X1856693Y590280D01*
G01X1865961Y541349D02*
Y581012D01*
G01X1869686Y537624D02*
X1865961Y541349D01*
G01X1869686Y528944D02*
Y537624D01*
G01X1856660Y591377D02*
X1855799D01*
G01X1879850Y597350D02*
X1905650D01*
G01X1871092Y588592D02*
X1879850Y597350D01*
G01X1867392Y588592D02*
X1871092D01*
G01X1845000Y592400D02*
Y590800D01*
G01X1856693Y590280D02*
X1851923D01*
G01X1847997Y590750D02*
X1848900D01*
G01X1903160Y-15062D02*
Y-19416D01*
G01X1900313Y-12215D02*
X1903160Y-15062D01*
G01X1898472Y-12215D02*
X1900313D01*
G01X1901911Y86525D02*
Y101819D01*
G01X1900959Y102214D02*
Y90783D01*
G01X1900007Y102734D02*
Y91178D01*
G01X1922524Y70524D02*
X1920300Y68300D01*
G01X1922524Y88224D02*
Y70524D01*
G01X1928548Y94248D02*
X1922524Y88224D01*
G01X1928548Y100552D02*
Y94248D01*
G01X1920665Y93765D02*
Y100668D01*
G01X1918352Y91452D02*
X1920665Y93765D01*
G01X1918352Y89300D02*
Y91452D01*
G01X1923300Y94300D02*
Y96900D01*
G01X1918052Y65548D02*
X1917600Y66000D01*
G01X1921512Y65548D02*
X1918052D01*
G01X1924328Y68364D02*
X1921512Y65548D01*
G01X1924328Y86600D02*
Y68364D01*
G01X1931329Y93601D02*
X1924328Y86600D01*
G01X1931329Y100229D02*
Y93601D01*
G01X1910400Y81800D02*
X1899887Y71287D01*
G01X1910400Y101253D02*
Y81800D01*
G01X1905818Y70564D02*
X1901837Y66583D01*
G01X1908744Y70564D02*
X1905818D01*
G01X1915104Y76924D02*
X1908744Y70564D01*
G01X1915104Y101253D02*
Y76924D01*
G01X1918600Y67600D02*
X1907280D01*
G01X1919900Y66300D02*
X1918600Y67600D01*
G01X1921200Y66300D02*
X1919900D01*
G01X1923576Y68676D02*
X1921200Y66300D01*
G01X1923576Y87700D02*
Y68676D01*
G01X1929780Y93904D02*
X1923576Y87700D01*
G01X1929780Y100720D02*
Y93904D01*
G01X1912752Y80825D02*
Y102228D01*
G01X1912572Y80645D02*
X1912752Y80825D01*
G01X1912572Y77719D02*
Y80645D01*
G01X1907770Y72917D02*
X1912572Y77719D01*
G01X1904844Y72917D02*
X1907770D01*
G01X1900862Y68935D02*
X1904844Y72917D01*
G01X1898935Y137816D02*
Y133666D01*
G01X1902439Y141320D02*
X1898935Y137816D01*
G01X1902439Y143548D02*
Y141320D01*
G01X1903345Y144454D02*
X1902439Y143548D01*
G01X1903345Y148676D02*
Y144454D01*
G01X1902396Y149625D02*
X1903345Y148676D01*
G01X1902396Y152446D02*
Y149625D01*
G01X1914940Y164990D02*
X1902396Y152446D01*
G01X1920164Y134396D02*
X1919195D01*
G01X1921278Y133282D02*
X1920164Y134396D01*
G01X1921278Y124755D02*
Y133282D01*
G01X1919677Y123154D02*
X1921278Y124755D01*
G01X1919677Y115807D02*
Y123154D01*
G01X1911495Y107625D02*
X1919677Y115807D01*
G01X1905915Y107625D02*
X1911495D01*
G01X1905261Y106971D02*
X1905915Y107625D01*
G01X1905261Y105169D02*
Y106971D01*
G01X1901911Y101819D02*
X1905261Y105169D01*
G01X1902245Y135709D02*
Y131695D01*
G01X1902836Y136300D02*
X1902245Y135709D01*
G01X1902928Y136300D02*
X1902836D01*
G01X1902954Y136326D02*
X1902928Y136300D01*
G01X1908076Y136326D02*
X1902954D01*
G01X1910800Y139050D02*
X1908076Y136326D01*
G01X1913081Y139050D02*
X1910800D01*
G01X1921931Y147900D02*
X1913081Y139050D01*
G01X1927398Y147900D02*
X1921931D01*
G01X1934449Y154951D02*
X1927398Y147900D01*
G01X1934449Y155599D02*
Y154951D01*
G01X1936450Y157600D02*
X1934449Y155599D01*
G01X1931700Y155451D02*
Y159900D01*
G01X1930224Y153975D02*
X1931700Y155451D01*
G01X1924468Y153975D02*
X1930224D01*
G01X1921917Y151424D02*
X1924468Y153975D01*
G01X1919124Y151424D02*
X1921917D01*
G01X1917908Y150208D02*
X1919124Y151424D01*
G01X1917908Y147608D02*
Y150208D01*
G01X1915000Y144700D02*
X1917908Y147608D01*
G01X1908356Y144700D02*
X1915000D01*
G01X1907400Y143744D02*
X1908356Y144700D01*
G01X1907400Y140900D02*
Y143744D01*
G01X1905000Y138500D02*
X1907400Y140900D01*
G01X1901249Y138500D02*
X1905000D01*
G01X1900144Y137395D02*
X1901249Y138500D01*
G01X1900144Y133116D02*
Y137395D01*
G01X1903682Y104937D02*
X1900959Y102214D01*
G01X1903682Y107687D02*
Y104937D01*
G01X1913531Y117536D02*
X1903682Y107687D01*
G01X1915980Y117536D02*
X1913531D01*
G01X1918725Y120281D02*
X1915980Y117536D01*
G01X1918725Y124943D02*
Y120281D01*
G01X1919702Y125920D02*
X1918725Y124943D01*
G01X1902730Y105457D02*
X1900007Y102734D01*
G01X1902730Y108082D02*
Y105457D01*
G01X1913136Y118488D02*
X1902730Y108082D01*
G01X1915585Y118488D02*
X1913136D01*
G01X1917773Y120676D02*
X1915585Y118488D01*
G01X1917773Y129960D02*
Y120676D01*
G01X1919514Y131701D02*
X1917773Y129960D01*
G01X1919689Y97582D02*
X1918210Y96103D01*
G01X1919689Y101073D02*
Y97582D01*
G01X1937139Y118523D02*
X1919689Y101073D01*
G01X1937139Y129065D02*
Y118523D01*
G01X1938000Y129926D02*
X1937139Y129065D01*
G01X1938000Y146000D02*
Y129926D01*
G01X1937100Y146900D02*
X1938000Y146000D01*
G01X1936297Y108301D02*
X1928548Y100552D01*
G01X1960172Y108301D02*
X1936297D01*
G01X1898466Y147975D02*
Y158755D01*
G01X1901021Y136306D02*
Y132471D01*
G01X1902215Y137500D02*
X1901021Y136306D01*
G01X1907337Y137500D02*
X1902215D01*
G01X1910239Y140402D02*
X1907337Y137500D01*
G01X1912803Y140402D02*
X1910239D01*
G01X1921501Y149100D02*
X1912803Y140402D01*
G01X1926685Y149100D02*
X1921501D01*
G01X1933097Y155512D02*
X1926685Y149100D01*
G01X1933097Y159147D02*
Y155512D01*
G01X1951536Y152252D02*
Y157798D01*
G01X1951888Y151900D02*
X1951536Y152252D01*
G01X1953537Y151900D02*
X1951888D01*
G01X1953889Y152252D02*
X1953537Y151900D01*
G01X1953889Y157798D02*
Y152252D01*
G01X1956242Y154652D02*
Y157798D01*
G01X1956594Y154300D02*
X1956242Y154652D01*
G01X1958243Y154300D02*
X1956594D01*
G01X1958595Y154652D02*
X1958243Y154300D01*
G01X1958595Y157798D02*
Y154652D01*
G01X1936187Y119009D02*
Y144013D01*
G01X1918002Y100824D02*
X1936187Y119009D01*
G01X1918002Y98902D02*
Y100824D01*
G01X1916310Y153410D02*
Y149676D01*
G01X1923870Y160970D02*
X1916310Y153410D01*
G01X1950934Y143487D02*
Y143730D01*
G01X1950000Y142553D02*
X1950934Y143487D01*
G01X1950000Y139380D02*
Y142553D01*
G01X1938235Y127615D02*
X1950000Y139380D01*
G01X1938235Y118238D02*
Y127615D01*
G01X1920665Y100668D02*
X1938235Y118238D01*
G01X1951700Y139340D02*
Y141000D01*
G01X1939356Y126996D02*
X1951700Y139340D01*
G01X1939356Y117844D02*
Y126996D01*
G01X1921655Y100143D02*
X1939356Y117844D01*
G01X1921655Y98545D02*
Y100143D01*
G01X1923300Y96900D02*
X1921655Y98545D01*
G01X1897376Y147949D02*
Y158524D01*
G01X1933000Y101900D02*
X1931329Y100229D01*
G01X1939703Y101900D02*
X1933000D01*
G01X1944600Y106797D02*
X1939703Y101900D01*
G01X1960796Y106797D02*
X1944600D01*
G01X1910399Y101254D02*
X1910400Y101253D01*
G01X1910399Y103202D02*
Y101254D01*
G01X1922029Y114832D02*
X1910399Y103202D01*
G01X1922029Y122179D02*
Y114832D01*
G01X1923630Y123780D02*
X1922029Y122179D01*
G01X1923630Y138170D02*
Y123780D01*
G01X1923500Y138300D02*
X1923630Y138170D01*
G01X1923500Y141400D02*
Y138300D01*
G01X1924600Y142500D02*
X1923500Y141400D01*
G01X1929700Y142500D02*
X1924600D01*
G01X1934000Y146800D02*
X1929700Y142500D01*
G01X1934000Y147100D02*
Y146800D01*
G01X1928700Y114849D02*
X1915104Y101253D01*
G01X1928700Y121300D02*
Y114849D01*
G01X1932108Y124708D02*
X1928700Y121300D01*
G01X1932108Y137292D02*
Y124708D01*
G01X1930100Y139300D02*
X1932108Y137292D01*
G01X1926743Y139300D02*
X1930100D01*
G01X1925358Y140685D02*
X1926743Y139300D01*
G01X1898393Y103112D02*
Y96357D01*
G01X1901322Y106041D02*
X1898393Y103112D01*
G01X1901322Y116499D02*
Y106041D01*
G01X1904839Y120016D02*
X1901322Y116499D01*
G01X1915121Y120016D02*
X1904839D01*
G01X1916364Y121259D02*
X1915121Y120016D01*
G01X1916364Y121883D02*
Y121259D01*
G01X1916365Y121884D02*
X1916364Y121883D01*
G01X1916365Y138264D02*
Y121884D01*
G01X1922953Y144852D02*
X1916365Y138264D01*
G01X1928632Y144852D02*
X1922953D01*
G01X1935580Y151800D02*
X1928632Y144852D01*
G01X1940604Y151800D02*
X1935580D01*
G01X1942280Y153476D02*
X1940604Y151800D01*
G01X1945484Y153476D02*
X1942280D01*
G01X1948653Y150307D02*
X1945484Y153476D01*
G01X1955704Y150307D02*
X1948653D01*
G01X1957797Y152400D02*
X1955704Y150307D01*
G01X1966700Y152400D02*
X1957797D01*
G01X1897885Y137830D02*
Y134107D01*
G01X1901624Y141569D02*
X1897885Y137830D01*
G01X1901624Y143855D02*
Y141569D01*
G01X1902593Y144824D02*
X1901624Y143855D01*
G01X1902593Y148364D02*
Y144824D01*
G01X1901644Y149313D02*
X1902593Y148364D01*
G01X1901644Y152758D02*
Y149313D01*
G01X1901676Y152790D02*
X1901644Y152758D01*
G01X1901676Y152983D02*
Y152790D01*
G01X1917517Y168824D02*
X1901676Y152983D01*
G01X1936609Y107549D02*
X1929780Y100720D01*
G01X1960484Y107549D02*
X1936609D01*
G01X1925982Y127263D02*
X1929756Y131037D01*
G01X1925982Y122805D02*
Y127263D01*
G01X1925116Y121939D02*
X1925982Y122805D01*
G01X1925116Y120467D02*
Y121939D01*
G01X1925613Y119970D02*
X1925116Y120467D01*
G01X1925613Y115089D02*
Y119970D01*
G01X1912752Y102228D02*
X1925613Y115089D01*
G01X1949389Y154292D02*
Y152083D01*
G01X1948305Y155376D02*
X1949389Y154292D01*
G01X1937164Y155376D02*
X1948305D01*
G01X1928188Y146400D02*
X1937164Y155376D01*
G01X1922423Y146400D02*
X1928188D01*
G01X1914957Y138934D02*
X1922423Y146400D01*
G01X1914957Y122468D02*
Y138934D01*
G01X1914956Y122467D02*
X1914957Y122468D01*
G01X1914956Y121843D02*
Y122467D01*
G01X1914537Y121424D02*
X1914956Y121843D01*
G01X1903956Y121424D02*
X1914537D01*
G01X1899914Y117382D02*
X1903956Y121424D01*
G01X1899914Y117083D02*
Y117382D01*
G01X1899913Y117082D02*
X1899914Y117083D01*
G01X1899913Y115916D02*
Y117082D01*
G01X1899914Y115915D02*
X1899913Y115916D01*
G01X1899914Y106625D02*
Y115915D01*
G01X1924924Y99475D02*
X1923329D01*
G01X1936229Y110780D02*
X1924924Y99475D01*
G01X1961200Y110780D02*
X1936229D01*
G01X1898064Y145579D02*
Y139859D01*
G01X1900872Y148387D02*
X1898064Y145579D01*
G01X1900872Y153243D02*
Y148387D01*
G01X1918029Y170400D02*
X1900872Y153243D01*
G01X1930428Y164990D02*
X1914940D01*
G01X1932400Y166962D02*
X1930428Y164990D01*
G01X1932400Y174185D02*
Y166962D01*
G01X1931065Y175520D02*
X1932400Y174185D01*
G01X1940500Y157600D02*
X1936450D01*
G01X1946600Y190200D02*
X1944300D01*
G01X1959900Y176900D02*
X1946600Y190200D01*
G01X1937600Y167330D02*
X1940240Y169970D01*
G01X1937600Y165800D02*
Y167330D01*
G01X1931700Y159900D02*
X1937600Y165800D01*
G01X1951437Y162300D02*
X1966076D01*
G01X1946326Y167411D02*
X1951437Y162300D01*
G01X1946326Y177186D02*
Y167411D01*
G01X1934691Y188821D02*
X1946326Y177186D01*
G01X1909119Y188821D02*
X1934691D01*
G01X1897871Y200069D02*
X1909119Y188821D01*
G01X1934275Y160325D02*
X1933097Y159147D01*
G01X1938975Y160325D02*
X1934275D01*
G01X1939600Y159700D02*
X1938975Y160325D01*
G01X1943200Y159700D02*
X1939600D01*
G01X1944750Y158150D02*
X1943200Y159700D01*
G01X1951184Y158150D02*
X1944750D01*
G01X1951536Y157798D02*
X1951184Y158150D01*
G01X1954241D02*
X1953889Y157798D01*
G01X1955890Y158150D02*
X1954241D01*
G01X1956242Y157798D02*
X1955890Y158150D01*
G01X1958947D02*
X1958595Y157798D01*
G01X1948973Y160874D02*
X1966226D01*
G01X1944895Y164952D02*
X1948973Y160874D01*
G01X1944895Y174148D02*
Y164952D01*
G01X1944543Y174500D02*
X1944895Y174148D01*
G01X1942894Y174500D02*
X1944543D01*
G01X1942542Y174148D02*
X1942894Y174500D01*
G01X1942542Y163652D02*
Y174148D01*
G01X1942190Y163300D02*
X1942542Y163652D01*
G01X1940550Y163300D02*
X1942190D01*
G01X1939550Y164300D02*
X1940550Y163300D01*
G01X1939550Y165600D02*
Y164300D01*
G01X1929990Y160970D02*
X1923870D01*
G01X1933850Y164830D02*
X1929990Y160970D01*
G01X1933850Y181640D02*
Y164830D01*
G01X1927550Y187940D02*
X1933850Y181640D01*
G01X1899120Y187940D02*
X1927550D01*
G01X1952013Y163852D02*
X1967677D01*
G01X1948299Y167566D02*
X1952013Y163852D01*
G01X1948299Y182330D02*
Y167566D01*
G01X1940205Y190424D02*
X1948299Y182330D01*
G01X1909975Y190424D02*
X1940205D01*
G01X1928977Y168824D02*
X1917517D01*
G01X1930300Y170147D02*
X1928977Y168824D01*
G01X1951749Y163052D02*
X1967112D01*
G01X1947154Y167647D02*
X1951749Y163052D01*
G01X1947154Y177611D02*
Y167647D01*
G01X1935192Y189573D02*
X1947154Y177611D01*
G01X1909666Y189573D02*
X1935192D01*
G01X1897469Y201770D02*
X1909666Y189573D01*
G01X1927500Y170400D02*
X1918029D01*
G01X1945600Y447900D02*
X1938896Y441196D01*
G01X1945600Y466100D02*
Y447900D01*
G01X1939845Y445055D02*
X1936938Y442148D01*
G01X1911765Y440322D02*
X1910171Y438728D01*
G01X1934016Y440322D02*
X1911765D01*
G01X1935610Y438728D02*
X1934016Y440322D01*
G01X1958928Y438728D02*
X1935610D01*
G01X1967778Y447578D02*
X1958928Y438728D01*
G01X1944192Y454892D02*
Y466684D01*
G01X1933324Y444024D02*
X1944192Y454892D01*
G01X1928264Y444024D02*
X1933324D01*
G01X1928188Y444100D02*
X1928264Y444024D01*
G01X1912160Y439370D02*
X1910566Y437776D01*
G01X1933621Y439370D02*
X1912160D01*
G01X1935215Y437776D02*
X1933621Y439370D01*
G01X1959323Y437776D02*
X1935215D01*
G01X1912300Y510700D02*
X1912800D01*
G01X1911800Y511200D02*
X1912300Y510700D01*
G01X1911800Y512000D02*
Y511200D01*
G01X1912500Y512700D02*
X1911800Y512000D01*
G01X1915900Y512700D02*
X1912500D01*
G01X1919500Y509100D02*
X1915900Y512700D01*
G01X1919500Y503036D02*
Y509100D01*
G01X1922636Y499900D02*
X1919500Y503036D01*
G01X1936126Y499900D02*
X1922636D01*
G01X1949196Y486830D02*
X1936126Y499900D01*
G01X1949196Y479260D02*
Y486830D01*
G01X1946247Y476311D02*
X1949196Y479260D01*
G01X1946247Y474847D02*
Y476311D01*
G01X1945400Y474000D02*
X1946247Y474847D01*
G01X1945000Y474000D02*
X1945400D01*
G01X1910400Y510700D02*
X1909800D01*
G01X1911018Y511318D02*
X1910400Y510700D01*
G01X1911018Y512282D02*
Y511318D01*
G01X1912188Y513452D02*
X1911018Y512282D01*
G01X1916212Y513452D02*
X1912188D01*
G01X1920252Y509412D02*
X1916212Y513452D01*
G01X1920252Y503348D02*
Y509412D01*
G01X1922948Y500652D02*
X1920252Y503348D01*
G01X1936438Y500652D02*
X1922948D01*
G01X1949948Y487142D02*
X1936438Y500652D01*
G01X1949948Y478948D02*
Y487142D01*
G01X1946999Y475999D02*
X1949948Y478948D01*
G01X1946999Y475001D02*
Y475999D01*
G01X1947700Y474300D02*
X1946999Y475001D01*
G01X1948200Y474300D02*
X1947700D01*
G01X1953200Y473700D02*
X1945600Y466100D01*
G01X1953200Y492320D02*
Y473700D01*
G01X1968375Y507495D02*
X1953200Y492320D01*
G01X1958990Y476569D02*
X1960180Y475379D01*
G01X1958184Y476569D02*
X1958990D01*
G01X1957063Y475448D02*
X1958184Y476569D01*
G01X1957063Y474769D02*
Y475448D01*
G01X1908469Y525415D02*
X1910700Y527646D01*
G01X1951792Y492372D02*
X1966730Y507310D01*
G01X1951792Y474284D02*
Y492372D01*
G01X1944192Y466684D02*
X1951792Y474284D01*
G01X1958032Y477321D02*
X1959302D01*
G01X1957212Y478141D02*
X1958032Y477321D01*
G01X1957212Y479521D02*
Y478141D01*
G01X1902400Y527220D02*
X1900595Y525415D01*
G01X1958250Y561900D02*
X1962950Y566600D01*
G01X1934600Y561900D02*
X1958250D01*
G01X1905315Y586365D02*
X1911750Y592800D01*
G01X1907200Y551300D02*
Y551600D01*
G01X1910700Y547800D02*
X1907200Y551300D01*
G01X1910700Y527646D02*
Y547800D01*
G01X1902400Y558150D02*
Y527220D01*
G01X1913350Y569100D02*
X1902400Y558150D01*
G01X1913350Y584575D02*
Y569100D01*
G01X1923175Y594400D02*
X1913350Y584575D01*
G01X1922800Y614500D02*
X1927000D01*
G01X1905650Y597350D02*
X1922800Y614500D01*
G01X1917900Y592800D02*
X1911750D01*
G01X1922450Y597350D02*
X1917900Y592800D01*
G01X1929720Y597350D02*
X1922450D01*
G01X1934220Y592850D02*
X1929720Y597350D01*
G01X1939898Y592850D02*
X1934220D01*
G01X1944882Y597834D02*
X1939898Y592850D01*
G01X1931606Y594400D02*
X1923175D01*
G01X1933908Y592098D02*
X1931606Y594400D01*
G01X1940210Y592098D02*
X1933908D01*
G01X1942512Y594400D02*
X1940210Y592098D01*
G01X1969300Y594400D02*
X1942512D01*
G01X1968476Y116605D02*
X1960172Y108301D01*
G01X1968476Y159900D02*
Y116605D01*
G01X1960948Y154652D02*
Y157798D01*
G01X1961300Y154300D02*
X1960948Y154652D01*
G01X1962949Y154300D02*
X1961300D01*
G01X1963301Y154652D02*
X1962949Y154300D01*
G01X1963301Y157798D02*
Y154652D01*
G01X1970127Y116128D02*
X1960796Y106797D01*
G01X1970127Y149198D02*
Y116128D01*
G01X1972776Y151847D02*
X1970127Y149198D01*
G01X1972776Y158753D02*
Y151847D01*
G01X1969228Y116293D02*
X1960484Y107549D01*
G01X1969228Y160936D02*
Y116293D01*
G01X1967250Y116830D02*
X1961200Y110780D01*
G01X1967250Y133550D02*
Y116830D01*
G01X1960065Y140735D02*
X1967250Y133550D01*
G01X1960065Y146565D02*
Y140735D01*
G01X1962800Y149300D02*
X1960065Y146565D01*
G01X1959900Y171128D02*
Y176900D01*
G01X1963092Y167936D02*
X1959900Y171128D01*
G01X1966076Y162300D02*
X1968476Y159900D01*
G01X1960596Y158150D02*
X1958947D01*
G01X1960948Y157798D02*
X1960596Y158150D01*
G01X1963653D02*
X1963301Y157798D01*
G01X1966748Y158150D02*
X1963653D01*
G01X1967100Y158502D02*
X1966748Y158150D01*
G01X1967100Y160000D02*
Y158502D01*
G01X1966226Y160874D02*
X1967100Y160000D01*
G01X1967677Y163852D02*
X1972776Y158753D01*
G01X1967112Y163052D02*
X1969228Y160936D01*
G01X1967778Y462279D02*
Y447578D01*
G01X1960180Y469877D02*
X1967778Y462279D01*
G01X1968730Y447183D02*
X1959323Y437776D01*
G01X1968730Y462462D02*
Y447183D01*
G01X1960932Y470260D02*
X1968730Y462462D01*
G01X1968375Y509375D02*
Y507495D01*
G01X1960180Y475379D02*
Y469877D01*
G01X1969329Y513729D02*
Y561729D01*
G01X1966730Y511130D02*
X1969329Y513729D01*
G01X1966730Y507310D02*
Y511130D01*
G01X1960932Y475691D02*
Y470260D01*
G01X1959302Y477321D02*
X1960932Y475691D01*
G01X1969329Y561729D02*
X1972800Y565200D01*
G01X1972100Y597200D02*
X1969300Y594400D01*
G01X1973000Y597200D02*
X1972100D01*
G54D14*
G01X85550Y-47300D02*
X80500Y-42250D01*
G01X144200Y-47300D02*
X85550D01*
G01X145585Y-45915D02*
X144200Y-47300D01*
G01X443146Y-45915D02*
X145585D01*
G01X146299Y-42355D02*
X443146D01*
G01X163902Y31700D02*
X165478Y33276D01*
G01X162678Y31700D02*
X163902D01*
G01X160431Y29453D02*
X162678Y31700D01*
G01X160431Y27899D02*
Y29453D01*
G01X169003Y31900D02*
X170403D01*
G01X167124Y30021D02*
X169003Y31900D01*
G01X167124Y27899D02*
Y30021D01*
G01X157285Y31700D02*
X159085Y33500D01*
G01X156285Y31700D02*
X157285D01*
G01X154985Y30400D02*
X156285Y31700D01*
G01X154985Y29146D02*
Y30400D01*
G01X153738Y27899D02*
X154985Y29146D01*
G01X127091Y31700D02*
X128667Y33276D01*
G01X125867Y31700D02*
X127091D01*
G01X123620Y29453D02*
X125867Y31700D01*
G01X123620Y27899D02*
Y29453D01*
G01X130313Y30021D02*
Y27899D01*
G01X132192Y31900D02*
X130313Y30021D01*
G01X133592Y31900D02*
X132192D01*
G01X135048Y33356D02*
X133592Y31900D01*
G01X148292Y29146D02*
X147045Y27899D01*
G01X148292Y30400D02*
Y29146D01*
G01X149592Y31700D02*
X148292Y30400D01*
G01X150592Y31700D02*
X149592D01*
G01X152392Y33500D02*
X150592Y31700D01*
G01X148917Y35574D02*
X150391Y34100D01*
G01X148917Y36668D02*
Y35574D01*
G01X147484Y38101D02*
X148917Y36668D01*
G01X147484Y39324D02*
Y38101D01*
G01X148984Y40824D02*
X147484Y39324D01*
G01X148984Y42176D02*
Y40824D01*
G01X147484Y43676D02*
X148984Y42176D01*
G01X147484Y44799D02*
Y43676D01*
G01X149159Y46474D02*
X147484Y44799D01*
G01X149159Y47859D02*
Y46474D01*
G01X146117Y50901D02*
X149159Y47859D01*
G01X146117Y54029D02*
Y50901D01*
G01X147045Y54957D02*
X146117Y54029D01*
G01X148880Y91618D02*
Y111738D01*
G01X148480Y91218D02*
X148880Y91618D01*
G01X148480Y86518D02*
Y91218D01*
G01X149280Y85718D02*
X148480Y86518D01*
G01X149280Y73287D02*
Y85718D01*
G01X148480Y72487D02*
X149280Y73287D01*
G01X148480Y66903D02*
Y72487D01*
G01X149080Y66303D02*
X148480Y66903D01*
G01X149080Y59218D02*
Y66303D01*
G01X147045Y57183D02*
X149080Y59218D01*
G01X147045Y54957D02*
Y57183D01*
G01X165277Y93272D02*
X167648Y97488D01*
G01X165277Y86404D02*
Y93272D01*
G01X165174Y86301D02*
X165277Y86404D01*
G01X165174Y73020D02*
Y86301D01*
G01X165191Y73003D02*
X165174Y73020D01*
G01X165191Y64199D02*
Y73003D01*
G01X163432Y55259D02*
X165191Y64199D01*
G01X161627Y53454D02*
X163432Y55259D01*
G01X161627Y51764D02*
Y53454D01*
G01X163477Y49914D02*
X161627Y51764D01*
G01X164703Y48688D02*
X163477Y49914D01*
G01X164703Y35675D02*
Y48688D01*
G01X165478Y34900D02*
X164703Y35675D01*
G01X165478Y33276D02*
Y34900D01*
G01X169191Y60766D02*
X171691Y63266D01*
G01X169191Y54498D02*
Y60766D01*
G01X167892Y53199D02*
X169191Y54498D01*
G01X167892Y51792D02*
Y53199D01*
G01X169770Y49914D02*
X167892Y51792D01*
G01X125492Y34788D02*
X126580Y33700D01*
G01X125492Y36668D02*
Y34788D01*
G01X124059Y38101D02*
X125492Y36668D01*
G01X124059Y39300D02*
Y38101D01*
G01X125559Y40800D02*
X124059Y39300D01*
G01X125559Y42000D02*
Y40800D01*
G01X124109Y43450D02*
X125559Y42000D01*
G01X124109Y44849D02*
Y43450D01*
G01X125492Y46232D02*
X124109Y44849D01*
G01X125492Y48101D02*
Y46232D01*
G01X122692Y50901D02*
X125492Y48101D01*
G01X122692Y54029D02*
Y50901D01*
G01X123620Y54957D02*
X122692Y54029D01*
G01X125492Y91900D02*
Y146500D01*
G01X124792Y91200D02*
X125492Y91900D01*
G01X124792Y86400D02*
Y91200D01*
G01X125492Y85700D02*
X124792Y86400D01*
G01X125492Y73000D02*
Y85700D01*
G01X124592Y72100D02*
X125492Y73000D01*
G01X124592Y67200D02*
Y72100D01*
G01X125492Y66300D02*
X124592Y67200D01*
G01X125492Y61000D02*
Y66300D01*
G01X123620Y59128D02*
X125492Y61000D01*
G01X123620Y54957D02*
Y59128D01*
G01X156030Y93463D02*
X153892Y95601D01*
G01X156030Y92068D02*
Y93463D01*
G01X155080Y91118D02*
X156030Y92068D01*
G01X155080Y86418D02*
Y91118D01*
G01X155680Y85818D02*
X155080Y86418D01*
G01X155680Y73087D02*
Y85818D01*
G01X155180Y72587D02*
X155680Y73087D01*
G01X155180Y66803D02*
Y72587D01*
G01X155980Y66003D02*
X155180Y66803D01*
G01X155980Y57819D02*
Y66003D01*
G01X153738Y55577D02*
X155980Y57819D01*
G01X153738Y54957D02*
Y55577D01*
G01X152617Y53836D02*
X153738Y54957D01*
G01X152617Y50900D02*
Y53836D01*
G01X155959Y47558D02*
X152617Y50900D01*
G01X155959Y46500D02*
Y47558D01*
G01X154159Y44700D02*
X155959Y46500D01*
G01X154159Y43125D02*
Y44700D01*
G01X155359Y41925D02*
X154159Y43125D01*
G01X155359Y40799D02*
Y41925D01*
G01X154159Y39599D02*
X155359Y40799D01*
G01X154159Y38226D02*
Y39599D01*
G01X155517Y36868D02*
X154159Y38226D01*
G01X155517Y35667D02*
Y36868D01*
G01X157084Y34100D02*
X155517Y35667D01*
G01X158530Y91668D02*
Y96089D01*
G01X159180Y91018D02*
X158530Y91668D01*
G01X159180Y86618D02*
Y91018D01*
G01X158480Y85918D02*
X159180Y86618D01*
G01X158480Y73111D02*
Y85918D01*
G01X159080Y72511D02*
X158480Y73111D01*
G01X159080Y67053D02*
Y72511D01*
G01X158530Y66503D02*
X159080Y67053D01*
G01X158530Y56768D02*
Y66503D01*
G01X155180Y53418D02*
X158530Y56768D01*
G01X155180Y51818D02*
Y53418D01*
G01X157084Y49914D02*
X155180Y51818D01*
G01X158473Y48525D02*
X157084Y49914D01*
G01X158473Y35512D02*
Y48525D01*
G01X159085Y34900D02*
X158473Y35512D01*
G01X159085Y33500D02*
Y34900D01*
G01X128492Y86400D02*
Y146550D01*
G01X128292Y86200D02*
X128492Y86400D01*
G01X128292Y72400D02*
Y86200D01*
G01X128392Y72300D02*
X128292Y72400D01*
G01X128392Y67000D02*
Y72300D01*
G01X127892Y66500D02*
X128392Y67000D01*
G01X127892Y56530D02*
Y66500D01*
G01X124680Y53318D02*
X127892Y56530D01*
G01X124680Y51900D02*
Y53318D01*
G01X126666Y49914D02*
X124680Y51900D01*
G01X127892Y48688D02*
X126666Y49914D01*
G01X127892Y35675D02*
Y48688D01*
G01X128667Y34900D02*
X127892Y35675D01*
G01X128667Y33276D02*
Y34900D01*
G01X132092Y34567D02*
X132959Y33700D01*
G01X132092Y36868D02*
Y34567D01*
G01X130459Y38501D02*
X132092Y36868D01*
G01X130459Y39800D02*
Y38501D01*
G01X131809Y41150D02*
X130459Y39800D01*
G01X131809Y42050D02*
Y41150D01*
G01X130559Y43300D02*
X131809Y42050D01*
G01X130559Y44499D02*
Y43300D01*
G01X132092Y46032D02*
X130559Y44499D01*
G01X132092Y48000D02*
Y46032D01*
G01X129192Y50900D02*
X132092Y48000D01*
G01X129192Y53836D02*
Y50900D01*
G01X130313Y54957D02*
X129192Y53836D01*
G01X132380Y94212D02*
X130992Y95600D01*
G01X132380Y92288D02*
Y94212D01*
G01X131092Y91000D02*
X132380Y92288D01*
G01X131092Y86400D02*
Y91000D01*
G01X132192Y85300D02*
X131092Y86400D01*
G01X132192Y73200D02*
Y85300D01*
G01X130992Y72000D02*
X132192Y73200D01*
G01X130992Y67450D02*
Y72000D01*
G01X132292Y66150D02*
X130992Y67450D01*
G01X132292Y64800D02*
Y66150D01*
G01X130313Y62821D02*
X132292Y64800D01*
G01X130313Y54957D02*
Y62821D01*
G01X135048Y34700D02*
Y33356D01*
G01X134432Y35316D02*
X135048Y34700D01*
G01X134432Y48441D02*
Y35316D01*
G01X132959Y49914D02*
X134432Y48441D01*
G01X134880Y93688D02*
X135992Y94800D01*
G01X134880Y63988D02*
Y93688D01*
G01X132380Y61488D02*
X134880Y63988D01*
G01X132380Y54588D02*
Y61488D01*
G01X130886Y53094D02*
X132380Y54588D01*
G01X130886Y51987D02*
Y53094D01*
G01X132959Y49914D02*
X130886Y51987D01*
G01X168903Y34567D02*
X169770Y33700D01*
G01X168903Y36868D02*
Y34567D01*
G01X167270Y38501D02*
X168903Y36868D01*
G01X167270Y39800D02*
Y38501D01*
G01X168620Y41150D02*
X167270Y39800D01*
G01X168620Y42050D02*
Y41150D01*
G01X167370Y43300D02*
X168620Y42050D01*
G01X167370Y44499D02*
Y43300D01*
G01X168903Y46032D02*
X167370Y44499D01*
G01X168903Y48000D02*
Y46032D01*
G01X166003Y50900D02*
X168903Y48000D01*
G01X166003Y53836D02*
Y50900D01*
G01X167124Y54957D02*
X166003Y53836D01*
G01X169182Y92339D02*
Y94990D01*
G01X167841Y90998D02*
X169182Y92339D01*
G01X167841Y86718D02*
Y90998D01*
G01X169191Y85368D02*
X167841Y86718D01*
G01X169191Y73499D02*
Y85368D01*
G01X167841Y72149D02*
X169191Y73499D01*
G01X167841Y67401D02*
Y72149D01*
G01X168991Y66251D02*
X167841Y67401D01*
G01X168991Y64698D02*
Y66251D01*
G01X167124Y62831D02*
X168991Y64698D01*
G01X167124Y54957D02*
Y62831D01*
G01X159503Y54029D02*
X160431Y54957D01*
G01X159503Y50901D02*
Y54029D01*
G01X162303Y48101D02*
X159503Y50901D01*
G01X162303Y46232D02*
Y48101D01*
G01X160920Y44849D02*
X162303Y46232D01*
G01X160920Y43450D02*
Y44849D01*
G01X162370Y42000D02*
X160920Y43450D01*
G01X162370Y40800D02*
Y42000D01*
G01X160870Y39300D02*
X162370Y40800D01*
G01X160870Y38101D02*
Y39300D01*
G01X162303Y36668D02*
X160870Y38101D01*
G01X162303Y34788D02*
Y36668D01*
G01X163391Y33700D02*
X162303Y34788D01*
G01X162391Y92118D02*
Y95074D01*
G01X161491Y91218D02*
X162391Y92118D01*
G01X161491Y86418D02*
Y91218D01*
G01X162491Y85418D02*
X161491Y86418D01*
G01X162491Y73103D02*
Y85418D01*
G01X161491Y72103D02*
X162491Y73103D01*
G01X161491Y67201D02*
Y72103D01*
G01X162391Y66301D02*
X161491Y67201D01*
G01X162391Y64998D02*
Y66301D01*
G01X161492Y64099D02*
X162391Y64998D01*
G01X161492Y57319D02*
Y64099D01*
G01X160431Y56258D02*
X161492Y57319D01*
G01X160431Y54957D02*
Y56258D01*
G01X152392Y34900D02*
Y33500D01*
G01X151780Y35512D02*
X152392Y34900D01*
G01X151780Y48525D02*
Y35512D01*
G01X150391Y49914D02*
X151780Y48525D01*
G01X151392Y92206D02*
Y110250D01*
G01X152580Y91018D02*
X151392Y92206D01*
G01X152580Y86518D02*
Y91018D01*
G01X151780Y85718D02*
X152580Y86518D01*
G01X151780Y73011D02*
Y85718D01*
G01X152680Y72111D02*
X151780Y73011D01*
G01X152680Y67253D02*
Y72111D01*
G01X151580Y66153D02*
X152680Y67253D01*
G01X151580Y58182D02*
Y66153D01*
G01X150030Y56632D02*
X151580Y58182D01*
G01X150030Y55008D02*
Y56632D01*
G01X148580Y53558D02*
X150030Y55008D01*
G01X148580Y51725D02*
Y53558D01*
G01X150391Y49914D02*
X148580Y51725D01*
G01X150792Y142774D02*
X167747Y159729D01*
G01X150792Y138831D02*
Y142774D01*
G01X150182Y138221D02*
X150792Y138831D01*
G01X148052Y138221D02*
X150182D01*
G01X147442Y137611D02*
X148052Y138221D01*
G01X147442Y136221D02*
Y137611D01*
G01X148052Y135611D02*
X147442Y136221D01*
G01X150182Y135611D02*
X148052D01*
G01X150792Y135001D02*
X150182Y135611D01*
G01X150792Y133611D02*
Y135001D01*
G01X150182Y133001D02*
X150792Y133611D01*
G01X147952Y133001D02*
X150182D01*
G01X147342Y132391D02*
X147952Y133001D01*
G01X147342Y131001D02*
Y132391D01*
G01X147952Y130391D02*
X147342Y131001D01*
G01X150182Y130391D02*
X147952D01*
G01X150792Y129781D02*
X150182Y130391D01*
G01X150792Y128391D02*
Y129781D01*
G01X150182Y127781D02*
X150792Y128391D01*
G01X147952Y127781D02*
X150182D01*
G01X147342Y127171D02*
X147952Y127781D01*
G01X147342Y125781D02*
Y127171D01*
G01X147952Y125171D02*
X147342Y125781D01*
G01X150182Y125171D02*
X147952D01*
G01X150792Y124561D02*
X150182Y125171D01*
G01X150792Y123171D02*
Y124561D01*
G01X150182Y122561D02*
X150792Y123171D01*
G01X147952Y122561D02*
X150182D01*
G01X147342Y121951D02*
X147952Y122561D01*
G01X147342Y120561D02*
Y121951D01*
G01X147952Y119951D02*
X147342Y120561D01*
G01X150182Y119951D02*
X147952D01*
G01X150792Y119341D02*
X150182Y119951D01*
G01X150792Y113650D02*
Y119341D01*
G01X148880Y111738D02*
X150792Y113650D01*
G01X167648Y107406D02*
X170392Y110150D01*
G01X167648Y97488D02*
Y107406D01*
G01X125492Y146500D02*
X210992Y232000D01*
G01X161792Y145950D02*
X205660Y189818D01*
G01X161792Y137231D02*
Y145950D01*
G01X161182Y136621D02*
X161792Y137231D01*
G01X157352Y136621D02*
X161182D01*
G01X156742Y136011D02*
X157352Y136621D01*
G01X156742Y134621D02*
Y136011D01*
G01X157352Y134011D02*
X156742Y134621D01*
G01X161182Y134011D02*
X157352D01*
G01X161792Y133401D02*
X161182Y134011D01*
G01X161792Y131650D02*
Y133401D01*
G01X160992Y130850D02*
X161792Y131650D01*
G01X156042Y130850D02*
X160992D01*
G01X155542Y130350D02*
X156042Y130850D01*
G01X155542Y110350D02*
Y130350D01*
G01X153892Y108700D02*
X155542Y110350D01*
G01X153892Y95601D02*
Y108700D01*
G01X164642Y145100D02*
X242092Y222550D01*
G01X164642Y129368D02*
Y145100D01*
G01X164032Y128758D02*
X164642Y129368D01*
G01X159652Y128758D02*
X164032D01*
G01X159042Y128148D02*
X159652Y128758D01*
G01X159042Y126758D02*
Y128148D01*
G01X159652Y126148D02*
X159042Y126758D01*
G01X164032Y126148D02*
X159652D01*
G01X164642Y125538D02*
X164032Y126148D01*
G01X164642Y124148D02*
Y125538D01*
G01X164032Y123538D02*
X164642Y124148D01*
G01X159652Y123538D02*
X164032D01*
G01X159042Y122928D02*
X159652Y123538D01*
G01X159042Y121538D02*
Y122928D01*
G01X159652Y120928D02*
X159042Y121538D01*
G01X164032Y120928D02*
X159652D01*
G01X164642Y120318D02*
X164032Y120928D01*
G01X164642Y118928D02*
Y120318D01*
G01X164032Y118318D02*
X164642Y118928D01*
G01X159652Y118318D02*
X164032D01*
G01X159042Y117708D02*
X159652Y118318D01*
G01X159042Y116318D02*
Y117708D01*
G01X159652Y115708D02*
X159042Y116318D01*
G01X164032Y115708D02*
X159652D01*
G01X164642Y115098D02*
X164032Y115708D01*
G01X164642Y112899D02*
Y115098D01*
G01X163518Y111775D02*
X164642Y112899D01*
G01X161392Y111775D02*
X163518D01*
G01X160892Y111275D02*
X161392Y111775D01*
G01X160892Y108376D02*
Y111275D01*
G01X160282Y107766D02*
X160892Y108376D01*
G01X157102Y107766D02*
X160282D01*
G01X156492Y107156D02*
X157102Y107766D01*
G01X156492Y105766D02*
Y107156D01*
G01X157102Y105156D02*
X156492Y105766D01*
G01X160282Y105156D02*
X157102D01*
G01X160892Y104546D02*
X160282Y105156D01*
G01X160892Y103156D02*
Y104546D01*
G01X160282Y102546D02*
X160892Y103156D01*
G01X157102Y102546D02*
X160282D01*
G01X156492Y101936D02*
X157102Y102546D01*
G01X156492Y100546D02*
Y101936D01*
G01X157102Y99936D02*
X156492Y100546D01*
G01X159532Y99936D02*
X157102D01*
G01X160142Y99326D02*
X159532Y99936D01*
G01X160142Y97701D02*
Y99326D01*
G01X158530Y96089D02*
X160142Y97701D01*
G01X128492Y146550D02*
X211392Y229450D01*
G01X131892Y147150D02*
X144692Y159950D01*
G01X131892Y144822D02*
Y147150D01*
G01X130742Y143672D02*
X131892Y144822D01*
G01X130742Y142212D02*
Y143672D01*
G01X131892Y141062D02*
X130742Y142212D01*
G01X131892Y139602D02*
Y141062D01*
G01X130742Y138452D02*
X131892Y139602D01*
G01X130742Y136992D02*
Y138452D01*
G01X131892Y135842D02*
X130742Y136992D01*
G01X131892Y134382D02*
Y135842D01*
G01X130742Y133232D02*
X131892Y134382D01*
G01X130742Y131772D02*
Y133232D01*
G01X131892Y130622D02*
X130742Y131772D01*
G01X131892Y129162D02*
Y130622D01*
G01X130742Y128012D02*
X131892Y129162D01*
G01X130742Y126552D02*
Y128012D01*
G01X131892Y125402D02*
X130742Y126552D01*
G01X131892Y107874D02*
Y125402D01*
G01X132392Y107374D02*
X131892Y107874D01*
G01X133182Y107374D02*
X132392D01*
G01X133792Y106764D02*
X133182Y107374D01*
G01X133792Y105374D02*
Y106764D01*
G01X133182Y104764D02*
X133792Y105374D01*
G01X131602Y104764D02*
X133182D01*
G01X130992Y104154D02*
X131602Y104764D01*
G01X130992Y102764D02*
Y104154D01*
G01X131602Y102154D02*
X130992Y102764D01*
G01X133182Y102154D02*
X131602D01*
G01X133792Y101544D02*
X133182Y102154D01*
G01X133792Y100154D02*
Y101544D01*
G01X133182Y99544D02*
X133792Y100154D01*
G01X131602Y99544D02*
X133182D01*
G01X130992Y98934D02*
X131602Y99544D01*
G01X130992Y95600D02*
Y98934D01*
G01X133942Y146350D02*
X145067Y157475D01*
G01X133942Y109650D02*
Y146350D01*
G01X135992Y107600D02*
X133942Y109650D01*
G01X135992Y94800D02*
Y107600D01*
G01X169182Y94990D02*
X170392Y96200D01*
G01X167892Y143608D02*
X245342Y221058D01*
G01X167892Y110950D02*
Y143608D01*
G01X164939Y107997D02*
X167892Y110950D01*
G01X164939Y97622D02*
Y107997D01*
G01X162391Y95074D02*
X164939Y97622D01*
G01X152942Y141388D02*
X180392Y168838D01*
G01X152942Y111800D02*
Y141388D01*
G01X151392Y110250D02*
X152942Y111800D01*
G01X168886Y167544D02*
X170024Y168682D01*
G01X168886Y166836D02*
Y167544D01*
G01X171439Y164283D02*
X168886Y166836D01*
G01X169593Y162437D02*
X170455D01*
G01X167065Y164965D02*
X169593Y162437D01*
G01X166357Y164965D02*
X167065D01*
G01X165219Y163827D02*
X166357Y164965D01*
G01X165219Y163119D02*
Y163827D01*
G01X167747Y160591D02*
X165219Y163119D01*
G01X167747Y159729D02*
Y160591D01*
G01X151067Y166325D02*
X212142Y227400D01*
G01X151067Y163075D02*
Y166325D01*
G01X147942Y159950D02*
X151067Y163075D01*
G01X144692Y159950D02*
X147942D01*
G01X153067Y165475D02*
X213042Y225450D01*
G01X153067Y162275D02*
Y165475D01*
G01X148267Y157475D02*
X153067Y162275D01*
G01X145067Y157475D02*
X148267D01*
G01X125778Y455569D02*
Y510417D01*
G01X160647Y420700D02*
X125778Y455569D01*
G01X174208Y415083D02*
X160647Y420700D01*
G01X149692Y460135D02*
Y501044D01*
G01X157339Y452488D02*
X149692Y460135D01*
G01X157339Y451356D02*
Y452488D01*
G01X156703Y450720D02*
X157339Y451356D01*
G01X156703Y449588D02*
Y450720D01*
G01X157834Y448457D02*
X156703Y449588D01*
G01X158966Y448457D02*
X157834D01*
G01X159602Y449093D02*
X158966Y448457D01*
G01X160734Y449093D02*
X159602D01*
G01X161865Y447962D02*
X160734Y449093D01*
G01X161865Y446830D02*
Y447962D01*
G01X161229Y446194D02*
X161865Y446830D01*
G01X161229Y445062D02*
Y446194D01*
G01X162360Y443931D02*
X161229Y445062D01*
G01X163492Y443931D02*
X162360D01*
G01X164128Y444567D02*
X163492Y443931D01*
G01X165260Y444567D02*
X164128D01*
G01X166391Y443436D02*
X165260Y444567D01*
G01X166391Y442304D02*
Y443436D01*
G01X165755Y441668D02*
X166391Y442304D01*
G01X165755Y440536D02*
Y441668D01*
G01X166886Y439405D02*
X165755Y440536D01*
G01X168018Y439405D02*
X166886D01*
G01X168654Y440041D02*
X168018Y439405D01*
G01X169786Y440041D02*
X168654D01*
G01X166291Y426700D02*
X170791D01*
G01X142392Y450599D02*
X166291Y426700D01*
G01X142392Y453798D02*
Y450599D01*
G01X141413Y454777D02*
X142392Y453798D01*
G01X140621Y454777D02*
X141413D01*
G01X138063Y452219D02*
X140621Y454777D01*
G01X137273Y452218D02*
X138063Y452219D01*
G01X136253Y453238D02*
X137273Y452218D01*
G01X136253Y454030D02*
Y453238D01*
G01X138811Y456588D02*
X136253Y454030D01*
G01X138810Y457380D02*
X138811Y456588D01*
G01X137791Y458399D02*
X138810Y457380D01*
G01X136999Y458399D02*
X137791D01*
G01X134441Y455841D02*
X136999Y458399D01*
G01X133651Y455840D02*
X134441Y455841D01*
G01X132992Y456499D02*
X133651Y455840D01*
G01X132992Y507296D02*
Y456499D01*
G01X165791Y424600D02*
X170191D01*
G01X143791Y446600D02*
X165791Y424600D01*
G01X140191Y446600D02*
X143791D01*
G01X130466Y456325D02*
X140191Y446600D01*
G01X130466Y507775D02*
Y456325D01*
G01X167492Y449407D02*
X180159Y436740D01*
G01X167492Y464100D02*
Y449407D01*
G01X166692Y464900D02*
X167492Y464100D01*
G01X164292D02*
X165092Y464900D01*
G01X164292Y456100D02*
Y464100D01*
G01X163492Y455300D02*
X164292Y456100D01*
G01X161892Y455300D02*
X163492D01*
G01X161092Y456100D02*
X161892Y455300D01*
G01X161092Y493400D02*
Y456100D01*
G01X164992Y448371D02*
X177659Y435704D01*
G01X164992Y451100D02*
Y448371D01*
G01X163356Y452736D02*
X164992Y451100D01*
G01X160627Y452736D02*
X163356D01*
G01X158492Y454871D02*
X160627Y452736D01*
G01X158492Y457399D02*
Y454871D01*
G01X155556Y460335D02*
X158492Y457399D01*
G01X153028Y460335D02*
X155556D01*
G01X152192Y461171D02*
X153028Y460335D01*
G01X152192Y463450D02*
Y461171D01*
G01X152752Y464010D02*
X152192Y463450D01*
G01X158632Y464010D02*
X152752D01*
G01X159192Y464570D02*
X158632Y464010D01*
G01X159192Y466010D02*
Y464570D01*
G01X127966Y456025D02*
Y510952D01*
G01X139728Y444263D02*
X127966Y456025D01*
G01X140520Y444263D02*
X139728D01*
G01X140978Y444721D02*
X140520Y444263D01*
G01X141870Y444720D02*
X140978Y444721D01*
G01X142881Y443709D02*
X141870Y444720D01*
G01X142881Y443001D02*
Y443709D01*
G01X142331Y442451D02*
X142881Y443001D01*
G01X142330Y441661D02*
X142331Y442451D01*
G01X143350Y440641D02*
X142330Y441661D01*
G01X144142Y440641D02*
X143350D01*
G01X145200Y441699D02*
X144142Y440641D01*
G01X145992Y441698D02*
X145200Y441699D01*
G01X147011Y440679D02*
X145992Y441698D01*
G01X147011Y439887D02*
Y440679D01*
G01X145953Y438829D02*
X147011Y439887D01*
G01X145952Y438039D02*
X145953Y438829D01*
G01X146972Y437019D02*
X145952Y438039D01*
G01X147764Y437019D02*
X146972D01*
G01X148822Y438077D02*
X147764Y437019D01*
G01X149613Y438077D02*
X148822D01*
G01X165090Y422600D02*
X149613Y438077D01*
G01X169491Y422600D02*
X165090D01*
G01X212258Y379833D02*
X169491Y422600D01*
G01X125420Y517709D02*
Y529124D01*
G01X124766Y516130D02*
X125420Y517709D01*
G01X124766Y512861D02*
Y516130D01*
G01X125371Y511400D02*
X124766Y512861D01*
G01X125537Y511000D02*
X125371Y511400D01*
G01X125778Y510417D02*
X125537Y511000D01*
G01X148692Y519388D02*
Y527600D01*
G01X149080Y519000D02*
X148692Y519388D01*
G01X149080Y517557D02*
Y519000D01*
G01X148480Y516957D02*
X149080Y517557D01*
G01X148480Y512057D02*
Y516957D01*
G01X148845Y511692D02*
X148480Y512057D01*
G01X148845Y507952D02*
Y511692D01*
G01X143292Y502399D02*
X148845Y507952D01*
G01X143292Y496700D02*
Y502399D01*
G01X144092Y495900D02*
X143292Y496700D01*
G01X145692Y495900D02*
X144092D01*
G01X146492Y496700D02*
X145692Y495900D01*
G01X146492Y501044D02*
Y496700D01*
G01X147292Y501844D02*
X146492Y501044D01*
G01X148892Y501844D02*
X147292D01*
G01X149692Y501044D02*
X148892Y501844D01*
G01X167841Y511851D02*
X169836Y509856D01*
G01X167841Y516307D02*
Y511851D01*
G01X168992Y517458D02*
X167841Y516307D01*
G01X168992Y519399D02*
Y517458D01*
G01X168792Y519599D02*
X168992Y519399D01*
G01X168792Y527900D02*
Y519599D01*
G01X134866Y509170D02*
X132992Y507296D01*
G01X134866Y518674D02*
Y509170D01*
G01X136592Y520400D02*
X134866Y518674D01*
G01X136592Y521328D02*
Y520400D01*
G01X135982Y521938D02*
X136592Y521328D01*
G01X134002Y521938D02*
X135982D01*
G01X133492Y522448D02*
X134002Y521938D01*
G01X133492Y524428D02*
Y522448D01*
G01X134202Y525138D02*
X133492Y524428D01*
G01X135982Y525138D02*
X134202D01*
G01X136592Y525748D02*
X135982Y525138D01*
G01X136592Y526900D02*
Y525748D01*
G01X162598Y501194D02*
X173992Y489800D01*
G01X162598Y510650D02*
Y501194D01*
G01X161669Y511579D02*
X162598Y510650D01*
G01X161669Y516729D02*
Y511579D01*
G01X162391Y517451D02*
X161669Y516729D01*
G01X162391Y529401D02*
Y517451D01*
G01X164992Y502700D02*
X176592Y491100D01*
G01X164992Y504195D02*
Y502700D01*
G01X165602Y504805D02*
X164992Y504195D01*
G01X167105Y504805D02*
X165602D01*
G01X167715Y505415D02*
X167105Y504805D01*
G01X167715Y506805D02*
Y505415D01*
G01X167105Y507415D02*
X167715Y506805D01*
G01X165602Y507415D02*
X167105D01*
G01X164992Y508025D02*
X165602Y507415D01*
G01X164992Y511100D02*
Y508025D01*
G01X165292Y511400D02*
X164992Y511100D01*
G01X165292Y517256D02*
Y511400D01*
G01X164693Y517855D02*
X165292Y517256D01*
G01X164693Y521883D02*
Y517855D01*
G01X165303Y522493D02*
X164693Y521883D01*
G01X166470Y522493D02*
X165303D01*
G01X167080Y523103D02*
X166470Y522493D01*
G01X167080Y524493D02*
Y523103D01*
G01X166470Y525103D02*
X167080Y524493D01*
G01X165303Y525103D02*
X166470D01*
G01X164693Y525713D02*
X165303Y525103D01*
G01X164693Y529799D02*
Y525713D01*
G01X131963Y509272D02*
X130466Y507775D01*
G01X131963Y511055D02*
Y509272D01*
G01X131066Y511952D02*
X131963Y511055D01*
G01X131066Y516474D02*
Y511952D01*
G01X132366Y517774D02*
X131066Y516474D01*
G01X132366Y519500D02*
Y517774D01*
G01X131192Y520674D02*
X132366Y519500D01*
G01X131192Y527100D02*
Y520674D01*
G01X165092Y464900D02*
X166692D01*
G01X160292Y494200D02*
X161092Y493400D01*
G01X158692Y494200D02*
X160292D01*
G01X157892Y493400D02*
X158692Y494200D01*
G01X157892Y485300D02*
Y493400D01*
G01X157092Y484500D02*
X157892Y485300D01*
G01X155492Y484500D02*
X157092D01*
G01X154692Y485300D02*
X155492Y484500D01*
G01X154692Y507612D02*
Y485300D01*
G01X155680Y508600D02*
X154692Y507612D01*
G01X155680Y511157D02*
Y508600D01*
G01X155180Y511657D02*
X155680Y511157D01*
G01X155180Y517057D02*
Y511657D01*
G01X155980Y517857D02*
X155180Y517057D01*
G01X155980Y519000D02*
Y517857D01*
G01X155414Y519566D02*
X155980Y519000D01*
G01X155414Y527322D02*
Y519566D01*
G01X158792Y520300D02*
Y527700D01*
G01X158192Y519700D02*
X158792Y520300D01*
G01X158192Y517399D02*
Y519700D01*
G01X159492Y516099D02*
X158192Y517399D01*
G01X159492Y512001D02*
Y516099D01*
G01X158592Y511101D02*
X159492Y512001D01*
G01X158592Y499543D02*
Y511101D01*
G01X163592Y494543D02*
X158592Y499543D01*
G01X163592Y468200D02*
Y494543D01*
G01X164392Y467400D02*
X163592Y468200D01*
G01X165992Y467400D02*
X164392D01*
G01X166792Y468200D02*
X165992Y467400D01*
G01X166792Y487900D02*
Y468200D01*
G01X167592Y488700D02*
X166792Y487900D01*
G01X169192Y488700D02*
X167592D01*
G01X169992Y487900D02*
X169192Y488700D01*
G01X158632Y466570D02*
X159192Y466010D01*
G01X152752Y466570D02*
X158632D01*
G01X152192Y467130D02*
X152752Y466570D01*
G01X152192Y468570D02*
Y467130D01*
G01X152752Y469130D02*
X152192Y468570D01*
G01X158632Y469130D02*
X152752D01*
G01X159192Y469690D02*
X158632Y469130D01*
G01X159192Y471130D02*
Y469690D01*
G01X158632Y471690D02*
X159192Y471130D01*
G01X152752Y471690D02*
X158632D01*
G01X152192Y472250D02*
X152752Y471690D01*
G01X152192Y473690D02*
Y472250D01*
G01X152752Y474250D02*
X152192Y473690D01*
G01X158632Y474250D02*
X152752D01*
G01X159192Y474810D02*
X158632Y474250D01*
G01X159192Y476250D02*
Y474810D01*
G01X158632Y476810D02*
X159192Y476250D01*
G01X152752Y476810D02*
X158632D01*
G01X152192Y477370D02*
X152752Y476810D01*
G01X152192Y478810D02*
Y477370D01*
G01X152752Y479370D02*
X152192Y478810D01*
G01X158632Y479370D02*
X152752D01*
G01X159192Y479930D02*
X158632Y479370D01*
G01X159192Y481370D02*
Y479930D01*
G01X158632Y481930D02*
X159192Y481370D01*
G01X152752Y481930D02*
X158632D01*
G01X152192Y482490D02*
X152752Y481930D01*
G01X152192Y508788D02*
Y482490D01*
G01X151780Y509200D02*
X152192Y508788D01*
G01X151780Y511257D02*
Y509200D01*
G01X152680Y512157D02*
X151780Y511257D01*
G01X152680Y516557D02*
Y512157D01*
G01X151580Y517657D02*
X152680Y516557D01*
G01X151580Y519100D02*
Y517657D01*
G01X152092Y519612D02*
X151580Y519100D01*
G01X152092Y527700D02*
Y519612D01*
G01X127692Y517326D02*
Y529193D01*
G01X128666Y516352D02*
X127692Y517326D01*
G01X128666Y511652D02*
Y516352D01*
G01X127966Y510952D02*
X128666Y511652D01*
G01X121915Y567835D02*
X126580Y572500D01*
G01X121915Y557662D02*
Y567835D01*
G01X123620Y555957D02*
X121915Y557662D01*
G01X123191Y555528D02*
X123620Y555957D01*
G01X123191Y551833D02*
Y555528D01*
G01X124516Y550508D02*
X123191Y551833D01*
G01X125499Y548134D02*
X124516Y550508D01*
G01X125499Y536902D02*
Y548134D01*
G01X124666Y534890D02*
X125499Y536902D01*
G01X124666Y530946D02*
Y534890D01*
G01X125420Y529124D02*
X124666Y530946D01*
G01X167996Y552600D02*
X169682Y550914D01*
G01X167996Y554292D02*
Y552600D01*
G01X168903Y555199D02*
X167996Y554292D01*
G01X168903Y556792D02*
Y555199D01*
G01X167759Y557936D02*
X168903Y556792D01*
G01X167759Y559356D02*
Y557936D01*
G01X168603Y560200D02*
X167759Y559356D01*
G01X168603Y561900D02*
Y560200D01*
G01X167759Y562744D02*
X168603Y561900D01*
G01X167759Y563956D02*
Y562744D01*
G01X168703Y564900D02*
X167759Y563956D01*
G01X168703Y566100D02*
Y564900D01*
G01X168104Y566699D02*
X168703Y566100D01*
G01X167124Y566699D02*
X168104D01*
G01X145340Y557662D02*
X147045Y555957D01*
G01X145340Y567849D02*
Y557662D01*
G01X150391Y572900D02*
X145340Y567849D01*
G01X146380Y555292D02*
X147045Y555957D01*
G01X146380Y551457D02*
Y555292D01*
G01X149280Y548557D02*
X146380Y551457D01*
G01X149280Y547388D02*
Y548557D01*
G01X148714Y546822D02*
X149280Y547388D01*
G01X148714Y538166D02*
Y546822D01*
G01X149280Y537600D02*
X148714Y538166D01*
G01X149280Y536442D02*
Y537600D01*
G01X148007Y535169D02*
X149280Y536442D01*
G01X148007Y530548D02*
Y535169D01*
G01X149080Y529475D02*
X148007Y530548D01*
G01X149080Y527988D02*
Y529475D01*
G01X148692Y527600D02*
X149080Y527988D01*
G01X165419Y557662D02*
X167124Y555957D01*
G01X165419Y569315D02*
Y557662D01*
G01X168604Y572500D02*
X165419Y569315D01*
G01X169770Y572500D02*
X168604D01*
G01X168991Y528099D02*
X168792Y527900D01*
G01X168991Y529467D02*
Y528099D01*
G01X167822Y530636D02*
X168991Y529467D01*
G01X167822Y535230D02*
Y530636D01*
G01X169041Y536449D02*
X167822Y535230D01*
G01X169041Y538000D02*
Y536449D01*
G01X168792Y538249D02*
X169041Y538000D01*
G01X168792Y546900D02*
Y538249D01*
G01X169041Y547149D02*
X168792Y546900D01*
G01X169041Y548657D02*
Y547149D01*
G01X165691Y552007D02*
X169041Y548657D01*
G01X165691Y554524D02*
Y552007D01*
G01X167124Y555957D02*
X165691Y554524D01*
G01X131293Y566699D02*
X130313D01*
G01X131892Y566100D02*
X131293Y566699D01*
G01X131892Y564900D02*
Y566100D01*
G01X130948Y563956D02*
X131892Y564900D01*
G01X130948Y562744D02*
Y563956D01*
G01X131792Y561900D02*
X130948Y562744D01*
G01X131792Y560200D02*
Y561900D01*
G01X130948Y559356D02*
X131792Y560200D01*
G01X130948Y557936D02*
Y559356D01*
G01X132092Y556792D02*
X130948Y557936D01*
G01X132092Y555199D02*
Y556792D01*
G01X131185Y554292D02*
X132092Y555199D01*
G01X131185Y552600D02*
Y554292D01*
G01X132871Y550914D02*
X131185Y552600D01*
G01X132959Y550914D02*
X132871D01*
G01X134866Y528626D02*
X136592Y526900D01*
G01X134866Y537700D02*
Y528626D01*
G01X135392Y538226D02*
X134866Y537700D01*
G01X135392Y546300D02*
Y538226D01*
G01X134866Y546826D02*
X135392Y546300D01*
G01X134866Y548657D02*
Y546826D01*
G01X132959Y550564D02*
X134866Y548657D01*
G01X132959Y550914D02*
Y550564D01*
G01X158726Y557662D02*
X160431Y555957D01*
G01X158726Y567635D02*
Y557662D01*
G01X159348Y568257D02*
X158726Y567635D01*
G01X159348Y569445D02*
Y568257D01*
G01X162403Y572500D02*
X159348Y569445D01*
G01X163391Y572500D02*
X162403D01*
G01X161642Y530150D02*
X162391Y529401D01*
G01X161642Y535443D02*
Y530150D01*
G01X162341Y536142D02*
X161642Y535443D01*
G01X162341Y548657D02*
Y536142D01*
G01X160051Y550947D02*
X162341Y548657D01*
G01X160051Y555577D02*
Y550947D01*
G01X160431Y555957D02*
X160051Y555577D01*
G01X161503Y566699D02*
X160431D01*
G01X162103Y566099D02*
X161503Y566699D01*
G01X162103Y565201D02*
Y566099D01*
G01X161066Y564164D02*
X162103Y565201D01*
G01X161066Y562936D02*
Y564164D01*
G01X162003Y561999D02*
X161066Y562936D01*
G01X162003Y560601D02*
Y561999D01*
G01X161066Y559664D02*
X162003Y560601D01*
G01X161066Y558336D02*
Y559664D01*
G01X162203Y557199D02*
X161066Y558336D01*
G01X162203Y555300D02*
Y557199D01*
G01X161703Y554800D02*
X162203Y555300D01*
G01X161703Y552600D02*
Y554800D01*
G01X163389Y550914D02*
X161703Y552600D01*
G01X163477Y550914D02*
X163389D01*
G01X165591Y530697D02*
X164693Y529799D01*
G01X165591Y534856D02*
Y530697D01*
G01X164991Y535456D02*
X165591Y534856D01*
G01X164991Y537500D02*
Y535456D01*
G01X166492Y539001D02*
X164991Y537500D01*
G01X166492Y545500D02*
Y539001D01*
G01X164991Y547001D02*
X166492Y545500D01*
G01X164991Y549400D02*
Y547001D01*
G01X163477Y550914D02*
X164991Y549400D01*
G01X131793Y572500D02*
X132959D01*
G01X128608Y569315D02*
X131793Y572500D01*
G01X128608Y557662D02*
Y569315D01*
G01X130313Y555957D02*
X128608Y557662D01*
G01X132366Y528274D02*
X131192Y527100D01*
G01X132366Y529281D02*
Y528274D01*
G01X131066Y530581D02*
X132366Y529281D01*
G01X131066Y535375D02*
Y530581D01*
G01X132166Y536475D02*
X131066Y535375D01*
G01X132166Y537900D02*
Y536475D01*
G01X131992Y538074D02*
X132166Y537900D01*
G01X131992Y546800D02*
Y538074D01*
G01X132166Y546974D02*
X131992Y546800D01*
G01X132166Y548582D02*
Y546974D01*
G01X129350Y551398D02*
X132166Y548582D01*
G01X129350Y554928D02*
Y551398D01*
G01X130313Y555891D02*
X129350Y554928D01*
G01X130313Y555957D02*
Y555891D01*
G01X152033Y567849D02*
X157084Y572900D01*
G01X152033Y557662D02*
Y567849D01*
G01X153738Y555957D02*
X152033Y557662D01*
G01X155980Y527888D02*
X155414Y527322D01*
G01X155980Y529219D02*
Y527888D01*
G01X154880Y530319D02*
X155980Y529219D01*
G01X154880Y535342D02*
Y530319D01*
G01X155780Y536242D02*
X154880Y535342D01*
G01X155780Y537802D02*
Y536242D01*
G01X155392Y538190D02*
X155780Y537802D01*
G01X155392Y547000D02*
Y538190D01*
G01X155780Y547388D02*
X155392Y547000D01*
G01X155780Y548707D02*
Y547388D01*
G01X152380Y552107D02*
X155780Y548707D01*
G01X152380Y554599D02*
Y552107D01*
G01X153738Y555957D02*
X152380Y554599D01*
G01X156996Y550914D02*
X157084D01*
G01X155310Y552600D02*
X156996Y550914D01*
G01X155310Y554292D02*
Y552600D01*
G01X155485Y554467D02*
X155310Y554292D01*
G01X155485Y557100D02*
Y554467D01*
G01X154373Y558212D02*
X155485Y557100D01*
G01X154373Y559288D02*
Y558212D01*
G01X155385Y560300D02*
X154373Y559288D01*
G01X155385Y561500D02*
Y560300D01*
G01X154373Y562512D02*
X155385Y561500D01*
G01X154373Y563588D02*
Y562512D01*
G01X155510Y564725D02*
X154373Y563588D01*
G01X155510Y565999D02*
Y564725D01*
G01X154810Y566699D02*
X155510Y565999D01*
G01X153738Y566699D02*
X154810D01*
G01X157084Y550966D02*
Y550914D01*
G01X158292Y549758D02*
X157084Y550966D01*
G01X158292Y546800D02*
Y549758D01*
G01X158792Y546300D02*
X158292Y546800D01*
G01X158792Y539100D02*
Y546300D01*
G01X158008Y538316D02*
X158792Y539100D01*
G01X158008Y536984D02*
Y538316D01*
G01X159380Y535612D02*
X158008Y536984D01*
G01X159380Y530697D02*
Y535612D01*
G01X158154Y529471D02*
X159380Y530697D01*
G01X158154Y528338D02*
Y529471D01*
G01X158792Y527700D02*
X158154Y528338D01*
G01X150303Y550914D02*
X150391D01*
G01X148617Y552600D02*
X150303Y550914D01*
G01X148617Y554292D02*
Y552600D01*
G01X148792Y554467D02*
X148617Y554292D01*
G01X148792Y557100D02*
Y554467D01*
G01X147680Y558212D02*
X148792Y557100D01*
G01X147680Y559288D02*
Y558212D01*
G01X148692Y560300D02*
X147680Y559288D01*
G01X148692Y561500D02*
Y560300D01*
G01X147680Y562512D02*
X148692Y561500D01*
G01X147680Y563588D02*
Y562512D01*
G01X148817Y564725D02*
X147680Y563588D01*
G01X148817Y565999D02*
Y564725D01*
G01X148117Y566699D02*
X148817Y565999D01*
G01X147045Y566699D02*
X148117D01*
G01X151880Y527912D02*
X152092Y527700D01*
G01X151880Y529683D02*
Y527912D01*
G01X152446Y530249D02*
X151880Y529683D01*
G01X152446Y535745D02*
Y530249D01*
G01X151780Y536411D02*
X152446Y535745D01*
G01X151780Y537688D02*
Y536411D01*
G01X152092Y538000D02*
X151780Y537688D01*
G01X152092Y546700D02*
Y538000D01*
G01X151780Y547012D02*
X152092Y546700D01*
G01X151780Y549568D02*
Y547012D01*
G01X151737Y549568D02*
X151780D01*
G01X150391Y550914D02*
X151737Y549568D01*
G01X124692Y566699D02*
X123620D01*
G01X125292Y566099D02*
X124692Y566699D01*
G01X125292Y565201D02*
Y566099D01*
G01X124255Y564164D02*
X125292Y565201D01*
G01X124255Y562936D02*
Y564164D01*
G01X125192Y561999D02*
X124255Y562936D01*
G01X125192Y560601D02*
Y561999D01*
G01X124255Y559664D02*
X125192Y560601D01*
G01X124255Y558336D02*
Y559664D01*
G01X125392Y557199D02*
X124255Y558336D01*
G01X125392Y555300D02*
Y557199D01*
G01X124892Y554800D02*
X125392Y555300D01*
G01X124892Y552600D02*
Y554800D01*
G01X126578Y550914D02*
X124892Y552600D01*
G01X126666Y550914D02*
X126578D01*
G01X128166Y549414D02*
X126666Y550914D01*
G01X128166Y546726D02*
Y549414D01*
G01X128692Y546200D02*
X128166Y546726D01*
G01X128692Y538026D02*
Y546200D01*
G01X128166Y537500D02*
X128692Y538026D01*
G01X128166Y535867D02*
Y537500D01*
G01X128732Y535301D02*
X128166Y535867D01*
G01X128732Y530233D02*
Y535301D01*
G01X127692Y529193D02*
X128732Y530233D01*
G01X230907Y31700D02*
X232707Y33500D01*
G01X229907Y31700D02*
X230907D01*
G01X228607Y30400D02*
X229907Y31700D01*
G01X228607Y29146D02*
Y30400D01*
G01X227360Y27899D02*
X228607Y29146D01*
G01X207214Y31900D02*
X208670Y33356D01*
G01X205814Y31900D02*
X207214D01*
G01X203935Y30021D02*
X205814Y31900D01*
G01X203935Y27899D02*
Y30021D01*
G01X170403Y31900D02*
X171859Y33356D01*
G01X224214Y31700D02*
X226014Y33500D01*
G01X223214Y31700D02*
X224214D01*
G01X221914Y30400D02*
X223214Y31700D01*
G01X221914Y29146D02*
Y30400D01*
G01X220667Y27899D02*
X221914Y29146D01*
G01X200713Y31700D02*
X202289Y33276D01*
G01X199489Y31700D02*
X200713D01*
G01X197242Y29453D02*
X199489Y31700D01*
G01X197242Y27899D02*
Y29453D01*
G01X194096Y31700D02*
X195896Y33500D01*
G01X193096Y31700D02*
X194096D01*
G01X191796Y30400D02*
X193096Y31700D01*
G01X191796Y29146D02*
Y30400D01*
G01X190549Y27899D02*
X191796Y29146D01*
G01X185103D02*
X183856Y27899D01*
G01X185103Y30400D02*
Y29146D01*
G01X186403Y31700D02*
X185103Y30400D01*
G01X187403Y31700D02*
X186403D01*
G01X189203Y33500D02*
X187403Y31700D01*
G01X228802Y53418D02*
X232152Y56768D01*
G01X228802Y51818D02*
Y53418D01*
G01X230706Y49914D02*
X228802Y51818D01*
G01X232095Y48525D02*
X230706Y49914D01*
G01X208054Y48441D02*
X206581Y49914D01*
G01X208054Y35316D02*
Y48441D01*
G01X208670Y34700D02*
X208054Y35316D01*
G01X208670Y33356D02*
Y34700D01*
G01X208502Y64110D02*
Y95744D01*
G01X206002Y61610D02*
X208502Y64110D01*
G01X206002Y54610D02*
Y61610D01*
G01X204508Y53116D02*
X206002Y54610D01*
G01X204508Y51987D02*
Y53116D01*
G01X206581Y49914D02*
X204508Y51987D01*
G01X171243Y48441D02*
X169770Y49914D01*
G01X171243Y35316D02*
Y48441D01*
G01X171859Y34700D02*
X171243Y35316D01*
G01X171859Y33356D02*
Y34700D01*
G01X171691Y92964D02*
X172892Y96164D01*
G01X171691Y63266D02*
Y92964D01*
G01X197242Y56249D02*
Y54957D01*
G01X198276Y57283D02*
X197242Y56249D01*
G01X198276Y58416D02*
Y57283D01*
G01X197242Y59450D02*
X198276Y58416D01*
G01X197242Y61750D02*
Y59450D01*
G01X199202Y63710D02*
X197242Y61750D01*
G01X199202Y66291D02*
Y63710D01*
G01X198302Y67191D02*
X199202Y66291D01*
G01X198302Y72103D02*
Y67191D01*
G01X199302Y73103D02*
X198302Y72103D01*
G01X199302Y75900D02*
Y73103D01*
G01X200592Y77190D02*
X199302Y75900D01*
G01X200592Y81200D02*
Y77190D01*
G01X199302Y82490D02*
X200592Y81200D01*
G01X199302Y85418D02*
Y82490D01*
G01X198302Y86418D02*
X199302Y85418D01*
G01X198302Y91218D02*
Y86418D01*
G01X199202Y92118D02*
X198302Y91218D01*
G01X199202Y93590D02*
Y92118D01*
G01X198892Y93900D02*
X199202Y93590D01*
G01X198892Y105264D02*
Y93900D01*
G01X199114Y34788D02*
X200202Y33700D01*
G01X199114Y36668D02*
Y34788D01*
G01X197681Y38101D02*
X199114Y36668D01*
G01X197681Y39300D02*
Y38101D01*
G01X199181Y40800D02*
X197681Y39300D01*
G01X199181Y42000D02*
Y40800D01*
G01X197731Y43450D02*
X199181Y42000D01*
G01X197731Y44849D02*
Y43450D01*
G01X199114Y46232D02*
X197731Y44849D01*
G01X199114Y48101D02*
Y46232D01*
G01X196314Y50901D02*
X199114Y48101D01*
G01X196314Y54029D02*
Y50901D01*
G01X197242Y54957D02*
X196314Y54029D01*
G01X225502Y93610D02*
X227092Y95200D01*
G01X225502Y91718D02*
Y93610D01*
G01X226202Y91018D02*
X225502Y91718D01*
G01X226202Y86518D02*
Y91018D01*
G01X225402Y85718D02*
X226202Y86518D01*
G01X225402Y83990D02*
Y85718D01*
G01X226892Y82500D02*
X225402Y83990D01*
G01X226892Y76190D02*
Y82500D01*
G01X225402Y74700D02*
X226892Y76190D01*
G01X225402Y73191D02*
Y74700D01*
G01X226302Y72291D02*
X225402Y73191D01*
G01X226302Y67253D02*
Y72291D01*
G01X225492Y66443D02*
X226302Y67253D01*
G01X225492Y64700D02*
Y66443D01*
G01X226692Y63500D02*
X225492Y64700D01*
G01X226692Y59200D02*
Y63500D01*
G01X223652Y56160D02*
X226692Y59200D01*
G01X223652Y55030D02*
Y56160D01*
G01X222202Y53580D02*
X223652Y55030D01*
G01X222202Y51725D02*
Y53580D01*
G01X224013Y49914D02*
X222202Y51725D01*
G01X225402Y48525D02*
X224013Y49914D01*
G01X225402Y35512D02*
Y48525D01*
G01X226014Y34900D02*
X225402Y35512D01*
G01X226014Y33500D02*
Y34900D01*
G01X201514Y48688D02*
X200288Y49914D01*
G01X201514Y35675D02*
Y48688D01*
G01X202289Y34900D02*
X201514Y35675D01*
G01X202289Y33276D02*
Y34900D01*
G01X201902Y94590D02*
X201492Y95000D01*
G01X201902Y91668D02*
Y94590D01*
G01X202152Y91418D02*
X201902Y91668D01*
G01X202152Y86468D02*
Y91418D01*
G01X201802Y86118D02*
X202152Y86468D01*
G01X201802Y83691D02*
Y86118D01*
G01X203192Y82301D02*
X201802Y83691D01*
G01X203192Y76099D02*
Y82301D01*
G01X201802Y74709D02*
X203192Y76099D01*
G01X201802Y73203D02*
Y74709D01*
G01X202152Y72853D02*
X201802Y73203D01*
G01X202152Y66653D02*
Y72853D01*
G01X201902Y66403D02*
X202152Y66653D01*
G01X201902Y63266D02*
Y66403D01*
G01X199992Y61356D02*
X201902Y63266D01*
G01X199992Y60100D02*
Y61356D01*
G01X200922Y59170D02*
X199992Y60100D01*
G01X200922Y55938D02*
Y59170D01*
G01X198302Y53318D02*
X200922Y55938D01*
G01X198302Y51900D02*
Y53318D01*
G01X200288Y49914D02*
X198302Y51900D01*
G01X195284Y48525D02*
X193895Y49914D01*
G01X195284Y35512D02*
Y48525D01*
G01X195896Y34900D02*
X195284Y35512D01*
G01X195896Y33500D02*
Y34900D01*
G01X195341Y91668D02*
Y99920D01*
G01X195991Y91018D02*
X195341Y91668D01*
G01X195991Y86618D02*
Y91018D01*
G01X195291Y85918D02*
X195991Y86618D01*
G01X195291Y73001D02*
Y85918D01*
G01X195891Y72401D02*
X195291Y73001D01*
G01X195891Y67053D02*
Y72401D01*
G01X195341Y66503D02*
X195891Y67053D01*
G01X195341Y64100D02*
Y66503D01*
G01X193482Y62241D02*
X195341Y64100D01*
G01X193482Y54909D02*
Y62241D01*
G01X191991Y53418D02*
X193482Y54909D01*
G01X191991Y51818D02*
Y53418D01*
G01X193895Y49914D02*
X191991Y51818D01*
G01X190549Y62957D02*
Y54957D01*
G01X192392Y64800D02*
X190549Y62957D01*
G01X192392Y66402D02*
Y64800D01*
G01X191991Y66803D02*
X192392Y66402D01*
G01X191991Y72599D02*
Y66803D01*
G01X192491Y73099D02*
X191991Y72599D01*
G01X192491Y85818D02*
Y73099D01*
G01X191891Y86418D02*
X192491Y85818D01*
G01X191891Y91118D02*
Y86418D01*
G01X192366Y91593D02*
X191891Y91118D01*
G01X192366Y93674D02*
Y91593D01*
G01X190492Y95548D02*
X192366Y93674D01*
G01X192328Y35667D02*
X193895Y34100D01*
G01X192328Y36868D02*
Y35667D01*
G01X190970Y38226D02*
X192328Y36868D01*
G01X190970Y39599D02*
Y38226D01*
G01X192170Y40799D02*
X190970Y39599D01*
G01X192170Y41925D02*
Y40799D01*
G01X190970Y43125D02*
X192170Y41925D01*
G01X190970Y44700D02*
Y43125D01*
G01X192770Y46500D02*
X190970Y44700D01*
G01X192770Y47558D02*
Y46500D01*
G01X189428Y50900D02*
X192770Y47558D01*
G01X189428Y53836D02*
Y50900D01*
G01X190549Y54957D02*
X189428Y53836D01*
G01X183856Y57183D02*
Y54957D01*
G01X185891Y59218D02*
X183856Y57183D01*
G01X185891Y66303D02*
Y59218D01*
G01X185291Y66903D02*
X185891Y66303D01*
G01X185291Y72699D02*
Y66903D01*
G01X186091Y73499D02*
X185291Y72699D01*
G01X186091Y85718D02*
Y73499D01*
G01X185291Y86518D02*
X186091Y85718D01*
G01X185291Y91218D02*
Y86518D01*
G01X185691Y91618D02*
X185291Y91218D01*
G01X185691Y93800D02*
Y91618D01*
G01X185492Y93999D02*
X185691Y93800D01*
G01X185492Y123050D02*
Y93999D01*
G01X185728Y35574D02*
X187202Y34100D01*
G01X185728Y36668D02*
Y35574D01*
G01X184295Y38101D02*
X185728Y36668D01*
G01X184295Y39324D02*
Y38101D01*
G01X185795Y40824D02*
X184295Y39324D01*
G01X185795Y42176D02*
Y40824D01*
G01X184295Y43676D02*
X185795Y42176D01*
G01X184295Y44799D02*
Y43676D01*
G01X185970Y46474D02*
X184295Y44799D01*
G01X185970Y47859D02*
Y46474D01*
G01X182928Y50901D02*
X185970Y47859D01*
G01X182928Y54029D02*
Y50901D01*
G01X183856Y54957D02*
X182928Y54029D01*
G01X219574Y56050D02*
X220667Y54957D01*
G01X219574Y57182D02*
Y56050D01*
G01X220342Y57950D02*
X219574Y57182D01*
G01X221842Y57950D02*
X220342D01*
G01X223792Y59900D02*
X221842Y57950D01*
G01X223792Y61600D02*
Y59900D01*
G01X222702Y62690D02*
X223792Y61600D01*
G01X222702Y66303D02*
Y62690D01*
G01X222102Y66903D02*
X222702Y66303D01*
G01X222102Y72611D02*
Y66903D01*
G01X222492Y73001D02*
X222102Y72611D01*
G01X222492Y76304D02*
Y73001D01*
G01X223292Y77104D02*
X222492Y76304D01*
G01X223792Y77104D02*
X223292D01*
G01X224592Y77904D02*
X223792Y77104D01*
G01X224592Y79504D02*
Y77904D01*
G01X223792Y80304D02*
X224592Y79504D01*
G01X223292Y80304D02*
X223792D01*
G01X222492Y81104D02*
X223292Y80304D01*
G01X222492Y86128D02*
Y81104D01*
G01X222102Y86518D02*
X222492Y86128D01*
G01X222102Y91218D02*
Y86518D01*
G01X222502Y91618D02*
X222102Y91218D01*
G01X222502Y93890D02*
Y91618D01*
G01X222124Y94268D02*
X222502Y93890D01*
G01X222124Y95400D02*
Y94268D01*
G01X222539Y35574D02*
X224013Y34100D01*
G01X222539Y36668D02*
Y35574D01*
G01X221106Y38101D02*
X222539Y36668D01*
G01X221106Y39324D02*
Y38101D01*
G01X222606Y40824D02*
X221106Y39324D01*
G01X222606Y42176D02*
Y40824D01*
G01X221106Y43676D02*
X222606Y42176D01*
G01X221106Y44799D02*
Y43676D01*
G01X222781Y46474D02*
X221106Y44799D01*
G01X222781Y47859D02*
Y46474D01*
G01X219739Y50901D02*
X222781Y47859D01*
G01X219739Y54029D02*
Y50901D01*
G01X220667Y54957D02*
X219739Y54029D01*
G01X189203Y34900D02*
Y33500D01*
G01X188591Y35512D02*
X189203Y34900D01*
G01X188591Y48525D02*
Y35512D01*
G01X187202Y49914D02*
X188591Y48525D01*
G01X185391Y51725D02*
X187202Y49914D01*
G01X185391Y53670D02*
Y51725D01*
G01X185866Y54145D02*
X185391Y53670D01*
G01X185866Y55657D02*
Y54145D01*
G01X188391Y58182D02*
X185866Y55657D01*
G01X188391Y66153D02*
Y58182D01*
G01X189491Y67253D02*
X188391Y66153D01*
G01X189491Y72201D02*
Y67253D01*
G01X188591Y73101D02*
X189491Y72201D01*
G01X188591Y85718D02*
Y73101D01*
G01X189391Y86518D02*
X188591Y85718D01*
G01X189391Y91018D02*
Y86518D01*
G01X188691Y91718D02*
X189391Y91018D01*
G01X188691Y92800D02*
Y91718D01*
G01X187992Y93499D02*
X188691Y92800D01*
G01X187992Y121350D02*
Y93499D01*
G01X203935Y62843D02*
Y54957D01*
G01X205802Y64710D02*
X203935Y62843D01*
G01X205802Y66267D02*
Y64710D01*
G01X204652Y67417D02*
X205802Y66267D01*
G01X204652Y72059D02*
Y67417D01*
G01X206002Y73409D02*
X204652Y72059D01*
G01X206002Y85368D02*
Y73409D01*
G01X204652Y86718D02*
X206002Y85368D01*
G01X204652Y90960D02*
Y86718D01*
G01X205892Y92200D02*
X204652Y90960D01*
G01X205892Y93900D02*
Y92200D01*
G01X203702Y96090D02*
X205892Y93900D01*
G01X205714Y34567D02*
X206581Y33700D01*
G01X205714Y36868D02*
Y34567D01*
G01X204081Y38501D02*
X205714Y36868D01*
G01X204081Y39800D02*
Y38501D01*
G01X205431Y41150D02*
X204081Y39800D01*
G01X205431Y42050D02*
Y41150D01*
G01X204181Y43300D02*
X205431Y42050D01*
G01X204181Y44499D02*
Y43300D01*
G01X205714Y46032D02*
X204181Y44499D01*
G01X205714Y48000D02*
Y46032D01*
G01X202814Y50900D02*
X205714Y48000D01*
G01X202814Y53836D02*
Y50900D01*
G01X203935Y54957D02*
X202814Y53836D01*
G01X227360Y56169D02*
Y54957D01*
G01X229602Y58411D02*
X227360Y56169D01*
G01X229602Y66003D02*
Y58411D01*
G01X228802Y66803D02*
X229602Y66003D01*
G01X228802Y72611D02*
Y66803D01*
G01X229302Y73111D02*
X228802Y72611D01*
G01X229302Y85818D02*
Y73111D01*
G01X228702Y86418D02*
X229302Y85818D01*
G01X228702Y91118D02*
Y86418D01*
G01X229652Y92068D02*
X228702Y91118D01*
G01X229652Y115436D02*
Y92068D01*
G01X229139Y35667D02*
X230706Y34100D01*
G01X229139Y36868D02*
Y35667D01*
G01X227781Y38226D02*
X229139Y36868D01*
G01X227781Y39599D02*
Y38226D01*
G01X228981Y40799D02*
X227781Y39599D01*
G01X228981Y41925D02*
Y40799D01*
G01X227781Y43125D02*
X228981Y41925D01*
G01X227781Y44700D02*
Y43125D01*
G01X229581Y46500D02*
X227781Y44700D01*
G01X229581Y47558D02*
Y46500D01*
G01X226239Y50900D02*
X229581Y47558D01*
G01X226239Y53836D02*
Y50900D01*
G01X227360Y54957D02*
X226239Y53836D01*
G01X231116Y141425D02*
X249992Y160301D01*
G01X231116Y137473D02*
Y141425D01*
G01X209592Y115949D02*
X231116Y137473D01*
G01X209592Y102754D02*
Y115949D01*
G01X206642Y99804D02*
X209592Y102754D01*
G01X206642Y97604D02*
Y99804D01*
G01X208502Y95744D02*
X206642Y97604D01*
G01X170392Y142572D02*
X247842Y220022D01*
G01X170392Y110150D02*
Y142572D01*
G01X183042Y148150D02*
X252842Y217950D01*
G01X183042Y134501D02*
Y148150D01*
G01X182070Y133529D02*
X183042Y134501D01*
G01X181208Y133529D02*
X182070D01*
G01X180122Y134616D02*
X181208Y133529D01*
G01X179260Y134616D02*
X180122D01*
G01X178276Y133632D02*
X179260Y134616D01*
G01X178276Y132770D02*
Y133632D01*
G01X179362Y131683D02*
X178276Y132770D01*
G01X179362Y130821D02*
Y131683D01*
G01X175392Y126851D02*
X179362Y130821D01*
G01X175392Y107100D02*
Y126851D01*
G01X172892Y104600D02*
X175392Y107100D01*
G01X172892Y96164D02*
Y104600D01*
G01X202392Y108764D02*
X198892Y105264D01*
G01X202392Y110215D02*
Y108764D01*
G01X201782Y110825D02*
X202392Y110215D01*
G01X200602Y110825D02*
X201782D01*
G01X200042Y111385D02*
X200602Y110825D01*
G01X200042Y112875D02*
Y111385D01*
G01X200602Y113435D02*
X200042Y112875D01*
G01X201782Y113435D02*
X200602D01*
G01X202392Y114045D02*
X201782Y113435D01*
G01X202392Y115435D02*
Y114045D01*
G01X201782Y116045D02*
X202392Y115435D01*
G01X200252Y116045D02*
X201782D01*
G01X199642Y116655D02*
X200252Y116045D01*
G01X199642Y118045D02*
Y116655D01*
G01X200252Y118655D02*
X199642Y118045D01*
G01X201782Y118655D02*
X200252D01*
G01X208192Y125065D02*
X201782Y118655D01*
G01X208192Y129109D02*
Y125065D01*
G01X242492Y163409D02*
X208192Y129109D01*
G01X227092Y116413D02*
X237529Y126850D01*
G01X227092Y95200D02*
Y116413D01*
G01X211342Y128723D02*
X244992Y162373D01*
G01X211342Y123950D02*
Y128723D01*
G01X205042Y117650D02*
X211342Y123950D01*
G01X205042Y108000D02*
Y117650D01*
G01X201492Y104450D02*
X205042Y108000D01*
G01X201492Y95000D02*
Y104450D01*
G01X203501Y129359D02*
X238542Y164400D01*
G01X203501Y128497D02*
Y129359D01*
G01X204764Y127234D02*
X203501Y128497D01*
G01X204764Y126372D02*
Y127234D01*
G01X203780Y125388D02*
X204764Y126372D01*
G01X202918Y125388D02*
X203780D01*
G01X201655Y126651D02*
X202918Y125388D01*
G01X200793Y126651D02*
X201655D01*
G01X199809Y125667D02*
X200793Y126651D01*
G01X199809Y124805D02*
Y125667D01*
G01X201072Y123542D02*
X199809Y124805D01*
G01X201072Y122680D02*
Y123542D01*
G01X200088Y121696D02*
X201072Y122680D01*
G01X199226Y121696D02*
X200088D01*
G01X197963Y122959D02*
X199226Y121696D01*
G01X197101Y122959D02*
X197963D01*
G01X192992Y118850D02*
X197101Y122959D01*
G01X192992Y116690D02*
Y118850D01*
G01X193602Y116080D02*
X192992Y116690D01*
G01X195792Y116080D02*
X193602D01*
G01X196292Y115580D02*
X195792Y116080D01*
G01X196292Y113970D02*
Y115580D01*
G01X195792Y113470D02*
X196292Y113970D01*
G01X193602Y113470D02*
X195792D01*
G01X192992Y112860D02*
X193602Y113470D01*
G01X192992Y111470D02*
Y112860D01*
G01X193602Y110860D02*
X192992Y111470D01*
G01X196082Y110860D02*
X193602D01*
G01X196692Y110250D02*
X196082Y110860D01*
G01X196692Y108860D02*
Y110250D01*
G01X196082Y108250D02*
X196692Y108860D01*
G01X193602Y108250D02*
X196082D01*
G01X192992Y107640D02*
X193602Y108250D01*
G01X192992Y106250D02*
Y107640D01*
G01X193602Y105640D02*
X192992Y106250D01*
G01X195232Y105640D02*
X193602D01*
G01X195842Y105030D02*
X195232Y105640D01*
G01X195842Y103640D02*
Y105030D01*
G01X195232Y103030D02*
X195842Y103640D01*
G01X193602Y103030D02*
X195232D01*
G01X192992Y102420D02*
X193602Y103030D01*
G01X192992Y101030D02*
Y102420D01*
G01X193602Y100420D02*
X192992Y101030D01*
G01X194841Y100420D02*
X193602D01*
G01X195341Y99920D02*
X194841Y100420D01*
G01X190492Y119400D02*
Y95548D01*
G01X215984Y144892D02*
X190492Y119400D01*
G01X215984Y145754D02*
Y144892D01*
G01X213797Y147941D02*
X215984Y145754D01*
G01X213797Y148803D02*
Y147941D01*
G01X214781Y149787D02*
X213797Y148803D01*
G01X215643Y149787D02*
X214781D01*
G01X217830Y147600D02*
X215643Y149787D01*
G01X218692Y147600D02*
X217830D01*
G01X219676Y148584D02*
X218692Y147600D01*
G01X219676Y149446D02*
Y148584D01*
G01X217489Y151633D02*
X219676Y149446D01*
G01X217489Y152495D02*
Y151633D01*
G01X218473Y153479D02*
X217489Y152495D01*
G01X219335Y153479D02*
X218473D01*
G01X221522Y151292D02*
X219335Y153479D01*
G01X222384Y151292D02*
X221522D01*
G01X223368Y152276D02*
X222384Y151292D01*
G01X223368Y153138D02*
Y152276D01*
G01X221181Y155325D02*
X223368Y153138D01*
G01X221181Y156187D02*
Y155325D01*
G01X222165Y157171D02*
X221181Y156187D01*
G01X225214Y154984D02*
X223027Y157171D01*
G01X226076Y154984D02*
X225214D01*
G01X227060Y155968D02*
X226076Y154984D01*
G01X227060Y156830D02*
Y155968D01*
G01X207199Y144757D02*
X185492Y123050D01*
G01X207199Y150443D02*
Y144757D01*
G01X204492Y153150D02*
X207199Y150443D01*
G01X204492Y155090D02*
Y153150D01*
G01X206145Y156743D02*
X204492Y155090D01*
G01X210340Y153410D02*
X207007Y156743D01*
G01X211202Y153410D02*
X210340D01*
G01X212186Y154394D02*
X211202Y153410D01*
G01X212186Y155256D02*
Y154394D01*
G01X208853Y158589D02*
X212186Y155256D01*
G01X222924Y96200D02*
X222124Y95400D01*
G01X223503Y96200D02*
X222924D01*
G01X224492Y97189D02*
X223503Y96200D01*
G01X224492Y98789D02*
Y97189D01*
G01X223692Y99589D02*
X224492Y98789D01*
G01X222192Y99589D02*
X223692D01*
G01X221392Y100389D02*
X222192Y99589D01*
G01X221392Y101989D02*
Y100389D01*
G01X222192Y102789D02*
X221392Y101989D01*
G01X223692Y102789D02*
X222192D01*
G01X224492Y103589D02*
X223692Y102789D01*
G01X224492Y105189D02*
Y103589D01*
G01X223692Y105989D02*
X224492Y105189D01*
G01X222192Y105989D02*
X223692D01*
G01X221392Y106789D02*
X222192Y105989D01*
G01X221392Y108389D02*
Y106789D01*
G01X222192Y109189D02*
X221392Y108389D01*
G01X223692Y109189D02*
X222192D01*
G01X224492Y109989D02*
X223692Y109189D01*
G01X224492Y111589D02*
Y109989D01*
G01X223692Y112389D02*
X224492Y111589D01*
G01X222652Y112389D02*
X223692D01*
G01X222092Y112949D02*
X222652Y112389D01*
G01X222092Y114948D02*
Y112949D01*
G01X239158Y132014D02*
X222092Y114948D01*
G01X211756Y145114D02*
X187992Y121350D01*
G01X211756Y150236D02*
Y145114D01*
G01X223015Y161495D02*
X211756Y150236D01*
G01X203702Y101346D02*
Y96090D01*
G01X207392Y105036D02*
X203702Y101346D01*
G01X207392Y117101D02*
Y105036D01*
G01X216098Y125807D02*
X207392Y117101D01*
G01X216098Y126668D02*
Y125807D01*
G01X215133Y127633D02*
X216098Y126668D01*
G01X215133Y128341D02*
Y127633D01*
G01X216271Y129479D02*
X215133Y128341D01*
G01X216979Y129479D02*
X216271D01*
G01X217943Y128515D02*
X216979Y129479D01*
G01X218806Y128515D02*
X217943D01*
G01X219790Y129499D02*
X218806Y128515D01*
G01X219790Y130361D02*
Y129499D01*
G01X218378Y131772D02*
X219790Y130361D01*
G01X218378Y132634D02*
Y131772D01*
G01X219362Y133618D02*
X218378Y132634D01*
G01X220224Y133618D02*
X219362D01*
G01X221636Y132207D02*
X220224Y133618D01*
G01X222498Y132207D02*
X221636D01*
G01X223482Y133191D02*
X222498Y132207D01*
G01X223482Y134052D02*
Y133191D01*
G01X222534Y135000D02*
X223482Y134052D01*
G01X222534Y135792D02*
Y135000D01*
G01X223588Y136846D02*
X222534Y135792D01*
G01X224380Y136846D02*
X223588D01*
G01X225327Y135899D02*
X224380Y136846D01*
G01X226190Y135899D02*
X225327D01*
G01X228048Y137757D02*
X226190Y135899D01*
G01X228048Y141893D02*
Y137757D01*
G01X247492Y161337D02*
X228048Y141893D01*
G01X180992Y149636D02*
X250342Y218986D01*
G01X180992Y143110D02*
Y149636D01*
G01X180382Y142500D02*
X180992Y143110D01*
G01X176052Y142500D02*
X180382D01*
G01X175442Y141890D02*
X176052Y142500D01*
G01X175442Y140260D02*
Y141890D01*
G01X176052Y139650D02*
X175442Y140260D01*
G01X180382Y139650D02*
X176052D01*
G01X180992Y139040D02*
X180382Y139650D01*
G01X180992Y137700D02*
Y139040D01*
G01X180392Y137100D02*
X180992Y137700D01*
G01X176092Y137100D02*
X180392D01*
G01X175042Y136050D02*
X176092Y137100D01*
G01X175042Y130801D02*
Y136050D01*
G01X172892Y128651D02*
X175042Y130801D01*
G01X172892Y108900D02*
Y128651D01*
G01X170392Y106400D02*
X172892Y108900D01*
G01X170392Y96200D02*
Y106400D01*
G01X237816Y123600D02*
X229652Y115436D01*
G01X220010Y215900D02*
X224076Y219966D01*
G01X217692Y215900D02*
X220010D01*
G01X172896Y171104D02*
X217692Y215900D01*
G01X172896Y170396D02*
Y171104D01*
G01X175301Y167991D02*
X172896Y170396D01*
G01X175301Y167283D02*
Y167991D01*
G01X174147Y166129D02*
X175301Y167283D01*
G01X173285Y166129D02*
X174147D01*
G01X170732Y168682D02*
X173285Y166129D01*
G01X170024Y168682D02*
X170732D01*
G01X171439Y163421D02*
Y164283D01*
G01X170455Y162437D02*
X171439Y163421D01*
G01X223027Y157171D02*
X222165D01*
G01X224873Y159017D02*
X227060Y156830D01*
G01X224873Y159879D02*
Y159017D01*
G01X225857Y160863D02*
X224873Y159879D01*
G01X226719Y160863D02*
X225857D01*
G01X228906Y158676D02*
X226719Y160863D01*
G01X229768Y158676D02*
X228906D01*
G01X230752Y159660D02*
X229768Y158676D01*
G01X230752Y160522D02*
Y159660D01*
G01X227514Y163760D02*
X230752Y160522D01*
G01X227514Y164622D02*
Y163760D01*
G01X228498Y165606D02*
X227514Y164622D01*
G01X229360Y165606D02*
X228498D01*
G01X232598Y162368D02*
X229360Y165606D01*
G01X207007Y156743D02*
X206145D01*
G01X208853Y159451D02*
Y158589D01*
G01X209837Y160435D02*
X208853Y159451D01*
G01X210699Y160435D02*
X209837D01*
G01X214032Y157102D02*
X210699Y160435D01*
G01X214894Y157102D02*
X214032D01*
G01X215878Y158086D02*
X214894Y157102D01*
G01X215878Y158948D02*
Y158086D01*
G01X212545Y162281D02*
X215878Y158948D01*
G01X212545Y163143D02*
Y162281D01*
G01X213529Y164127D02*
X212545Y163143D01*
G01X214391Y164127D02*
X213529D01*
G01X217724Y160794D02*
X214391Y164127D01*
G01X218586Y160794D02*
X217724D01*
G01X219570Y161778D02*
X218586Y160794D01*
G01X219570Y162640D02*
Y161778D01*
G01X216237Y165973D02*
X219570Y162640D01*
G01X216237Y166835D02*
Y165973D01*
G01X269513Y220111D02*
X216237Y166835D01*
G01X223136Y207294D02*
X238792Y222950D01*
G01X222274Y207294D02*
X223136D01*
G01X220011Y209557D02*
X222274Y207294D01*
G01X219149Y209557D02*
X220011D01*
G01X218165Y208573D02*
X219149Y209557D01*
G01X218165Y207711D02*
Y208573D01*
G01X220428Y205448D02*
X218165Y207711D01*
G01X220428Y204586D02*
Y205448D01*
G01X219444Y203602D02*
X220428Y204586D01*
G01X218582Y203602D02*
X219444D01*
G01X216319Y205865D02*
X218582Y203602D01*
G01X215457Y205865D02*
X216319D01*
G01X214473Y204881D02*
X215457Y205865D01*
G01X214473Y204019D02*
Y204881D01*
G01X216736Y201756D02*
X214473Y204019D01*
G01X216736Y200894D02*
Y201756D01*
G01X215752Y199910D02*
X216736Y200894D01*
G01X214890Y199910D02*
X215752D01*
G01X212627Y202173D02*
X214890Y199910D01*
G01X211765Y202173D02*
X212627D01*
G01X210781Y201189D02*
X211765Y202173D01*
G01X210781Y200327D02*
Y201189D01*
G01X213044Y198064D02*
X210781Y200327D01*
G01X213044Y197202D02*
Y198064D01*
G01X212060Y196218D02*
X213044Y197202D01*
G01X211198Y196218D02*
X212060D01*
G01X208935Y198481D02*
X211198Y196218D01*
G01X208073Y198481D02*
X208935D01*
G01X207089Y197497D02*
X208073Y198481D01*
G01X207089Y196635D02*
Y197497D01*
G01X209352Y194372D02*
X207089Y196635D01*
G01X209352Y193510D02*
Y194372D01*
G01X208368Y192526D02*
X209352Y193510D01*
G01X207506Y192526D02*
X208368D01*
G01X205243Y194789D02*
X207506Y192526D01*
G01X204381Y194789D02*
X205243D01*
G01X203397Y193805D02*
X204381Y194789D01*
G01X203397Y192943D02*
Y193805D01*
G01X205660Y190680D02*
X203397Y192943D01*
G01X205660Y189818D02*
Y190680D01*
G01X223015Y162627D02*
Y161495D01*
G01X219983Y165659D02*
X223015Y162627D01*
G01X219983Y166892D02*
Y165659D01*
G01X221657Y168566D02*
X219983Y166892D01*
G01X222519Y168566D02*
X221657D01*
G01X224582Y166504D02*
X222519Y168566D01*
G01X225444Y166504D02*
X224582D01*
G01X226428Y167488D02*
X225444Y166504D01*
G01X226428Y168350D02*
Y167488D01*
G01X224365Y170412D02*
X226428Y168350D01*
G01X224365Y171274D02*
Y170412D01*
G01X225349Y172258D02*
X224365Y171274D01*
G01X226211Y172258D02*
X225349D01*
G01X228274Y170196D02*
X226211Y172258D01*
G01X229136Y170196D02*
X228274D01*
G01X230120Y171180D02*
X229136Y170196D01*
G01X230120Y172042D02*
Y171180D01*
G01X228057Y174104D02*
X230120Y172042D01*
G01X228057Y174966D02*
Y174104D01*
G01X229041Y175950D02*
X228057Y174966D01*
G01X229903Y175950D02*
X229041D01*
G01X230353Y175500D02*
X229903Y175950D01*
G01X231966Y173888D02*
X230353Y175500D01*
G01X224992Y212050D02*
X235529Y222587D01*
G01X217442Y212050D02*
X224992D01*
G01X197721Y192329D02*
X217442Y212050D01*
G01X197721Y191621D02*
Y192329D01*
G01X199532Y189810D02*
X197721Y191621D01*
G01X199532Y187978D02*
Y189810D01*
G01X197868Y186314D02*
X199532Y187978D01*
G01X197006Y186314D02*
X197868D01*
G01X195562Y187758D02*
X197006Y186314D01*
G01X194700Y187758D02*
X195562D01*
G01X193716Y186774D02*
X194700Y187758D01*
G01X193716Y185912D02*
Y186774D01*
G01X195160Y184468D02*
X193716Y185912D01*
G01X195160Y183606D02*
Y184468D01*
G01X194176Y182622D02*
X195160Y183606D01*
G01X193314Y182622D02*
X194176D01*
G01X191870Y184066D02*
X193314Y182622D01*
G01X191008Y184066D02*
X191870D01*
G01X190024Y183082D02*
X191008Y184066D01*
G01X190024Y182220D02*
Y183082D01*
G01X191468Y180776D02*
X190024Y182220D01*
G01X191468Y179914D02*
Y180776D01*
G01X190484Y178930D02*
X191468Y179914D01*
G01X189622Y178930D02*
X190484D01*
G01X188178Y180374D02*
X189622Y178930D01*
G01X187316Y180374D02*
X188178D01*
G01X186332Y179390D02*
X187316Y180374D01*
G01X186332Y178528D02*
Y179390D01*
G01X187776Y177084D02*
X186332Y178528D01*
G01X187776Y176222D02*
Y177084D01*
G01X186792Y175238D02*
X187776Y176222D01*
G01X185930Y175238D02*
X186792D01*
G01X184486Y176682D02*
X185930Y175238D01*
G01X183624Y176682D02*
X184486D01*
G01X182640Y175698D02*
X183624Y176682D01*
G01X182640Y174836D02*
Y175698D01*
G01X184084Y173392D02*
X182640Y174836D01*
G01X184084Y172530D02*
Y173392D01*
G01X183100Y171546D02*
X184084Y172530D01*
G01X182238Y171546D02*
X183100D01*
G01X180794Y172990D02*
X182238Y171546D01*
G01X179932Y172990D02*
X180794D01*
G01X178948Y172006D02*
X179932Y172990D01*
G01X178948Y171144D02*
Y172006D01*
G01X180392Y169700D02*
X178948Y171144D01*
G01X180392Y168838D02*
Y169700D01*
G01X229676Y225566D02*
X253695Y249585D01*
G01X229676Y222684D02*
Y225566D01*
G01X226958Y219966D02*
X229676Y222684D01*
G01X224076Y219966D02*
X226958D01*
G01X212042Y232000D02*
X255442Y275400D01*
G01X210992Y232000D02*
X212042D01*
G01X212492Y229450D02*
X254692Y271650D01*
G01X211392Y229450D02*
X212492D01*
G01X213442Y227400D02*
X255363Y269321D01*
G01X212142Y227400D02*
X213442D01*
G01X214392Y225450D02*
X255763Y266821D01*
G01X213042Y225450D02*
X214392D01*
G01X248141Y321780D02*
X210373Y359548D01*
G01X207466Y381825D02*
X174208Y415083D01*
G01X209406Y377142D02*
X207466Y381825D01*
G01X210373Y374807D02*
X209406Y377142D01*
G01X210373Y359548D02*
Y374807D01*
G01X214947Y414183D02*
X239147Y389983D01*
G01X223803Y384788D02*
X175159Y433432D01*
G01X223803Y370890D02*
Y384788D01*
G01X253752Y340941D02*
X223803Y370890D01*
G01X213062Y413402D02*
X237262Y389202D01*
G01X216028Y364501D02*
X250649Y329880D01*
G01X216028Y381463D02*
Y364501D01*
G01X170791Y426700D02*
X216028Y381463D01*
G01X209292Y411840D02*
X233492Y387640D01*
G01X211177Y412621D02*
X235377Y388421D01*
G01X214143Y362850D02*
X249613Y327380D01*
G01X214143Y380648D02*
Y362850D01*
G01X170191Y424600D02*
X214143Y380648D01*
G01X227573Y372885D02*
X252358Y348100D01*
G01X227573Y386518D02*
Y372885D01*
G01X180159Y433932D02*
X227573Y386518D01*
G01X229458Y387417D02*
X196394Y420481D01*
G01X229458Y373667D02*
Y387417D01*
G01X253108Y350017D02*
X229458Y373667D01*
G01X225688Y372105D02*
X254352Y343441D01*
G01X225688Y385603D02*
Y372105D01*
G01X177659Y433632D02*
X225688Y385603D01*
G01X212258Y361199D02*
Y379833D01*
G01X249177Y324280D02*
X212258Y361199D01*
G01X246192Y445569D02*
X207992Y483769D01*
G01X214947Y416200D02*
Y414183D01*
G01X215447Y416700D02*
X214947Y416200D01*
G01X218492Y416700D02*
X215447D01*
G01X219192Y417400D02*
X218492Y416700D01*
G01X219192Y418600D02*
Y417400D01*
G01X218292Y419500D02*
X219192Y418600D01*
G01X215892Y419500D02*
X218292D01*
G01X214947Y420445D02*
X215892Y419500D01*
G01X214947Y423745D02*
Y420445D01*
G01X181592Y457100D02*
X214947Y423745D01*
G01X181592Y459104D02*
Y457100D01*
G01X182392Y459904D02*
X181592Y459104D01*
G01X184692Y459904D02*
X182392D01*
G01X185492Y460704D02*
X184692Y459904D01*
G01X185492Y462304D02*
Y460704D01*
G01X184692Y463104D02*
X185492Y462304D01*
G01X182392Y463104D02*
X184692D01*
G01X181592Y463904D02*
X182392Y463104D01*
G01X181592Y493500D02*
Y463904D01*
G01X170917Y438910D02*
X169786Y440041D01*
G01X170917Y437778D02*
Y438910D01*
G01X170281Y437142D02*
X170917Y437778D01*
G01X170281Y436010D02*
Y437142D01*
G01X171412Y434879D02*
X170281Y436010D01*
G01X172544Y434879D02*
X171412D01*
G01X173180Y435515D02*
X172544Y434879D01*
G01X174312Y435515D02*
X173180D01*
G01X175159Y434668D02*
X174312Y435515D01*
G01X175159Y433432D02*
Y434668D01*
G01X215820Y458760D02*
X205943Y468637D01*
G01X215820Y457628D02*
Y458760D01*
G01X214689Y456497D02*
X215820Y457628D01*
G01X213557Y456497D02*
X214689D01*
G01X205755Y464299D02*
X213557Y456497D01*
G01X204623Y464299D02*
X205755D01*
G01X203492Y463168D02*
X204623Y464299D01*
G01X203492Y462036D02*
Y463168D01*
G01X230792Y434736D02*
X203492Y462036D01*
G01X230792Y432476D02*
Y434736D01*
G01X230182Y431866D02*
X230792Y432476D01*
G01X227539Y431866D02*
X230182D01*
G01X226929Y431256D02*
X227539Y431866D01*
G01X226929Y429866D02*
Y431256D01*
G01X227539Y429256D02*
X226929Y429866D01*
G01X230182Y429256D02*
X227539D01*
G01X230792Y428646D02*
X230182Y429256D01*
G01X230792Y412966D02*
Y428646D01*
G01X250477Y393281D02*
X230792Y412966D01*
G01X213062Y418430D02*
Y413402D01*
G01X179092Y452400D02*
X213062Y418430D01*
G01X179092Y460140D02*
Y452400D01*
G01X179976Y461024D02*
X179092Y460140D01*
G01X179976Y461984D02*
Y461024D01*
G01X179092Y462868D02*
X179976Y461984D01*
G01X179092Y492500D02*
Y462868D01*
G01X209292Y416800D02*
Y411840D01*
G01X173992Y452100D02*
X209292Y416800D01*
G01X173992Y489800D02*
Y452100D01*
G01X243692Y444533D02*
X205492Y482733D01*
G01X248692Y446605D02*
X210492Y484805D01*
G01X211177Y417615D02*
Y412621D01*
G01X176592Y452200D02*
X211177Y417615D01*
G01X176592Y491100D02*
Y452200D01*
G01X240001Y442490D02*
X201492Y480999D01*
G01X231074Y446891D02*
X237738Y440227D01*
G01X229942Y446891D02*
X231074D01*
G01X228811Y445760D02*
X229942Y446891D01*
G01X228811Y444628D02*
Y445760D01*
G01X239692Y433747D02*
X228811Y444628D01*
G01X180159Y436740D02*
Y433932D01*
G01X227538Y450578D02*
X196692Y481424D01*
G01X227538Y449446D02*
Y450578D01*
G01X226407Y448315D02*
X227538Y449446D01*
G01X225275Y448315D02*
X226407D01*
G01X218507Y455083D02*
X225275Y448315D01*
G01X217375Y455083D02*
X218507D01*
G01X216697Y454405D02*
X217375Y455083D01*
G01X216697Y453697D02*
Y454405D01*
G01X236795Y433599D02*
X216697Y453697D01*
G01X169992Y450443D02*
Y487900D01*
G01X182692Y437743D02*
X169992Y450443D01*
G01X182692Y434183D02*
Y437743D01*
G01X184217Y432658D02*
X182692Y434183D01*
G01X185079Y432658D02*
X184217D01*
G01X186026Y433605D02*
X185079Y432658D01*
G01X186888Y433605D02*
X186026D01*
G01X188289Y432204D02*
X186888Y433605D01*
G01X188289Y431342D02*
Y432204D01*
G01X187342Y430395D02*
X188289Y431342D01*
G01X187342Y429533D02*
Y430395D01*
G01X188743Y428132D02*
X187342Y429533D01*
G01X189605Y428132D02*
X188743D01*
G01X190552Y429079D02*
X189605Y428132D01*
G01X191414Y429079D02*
X190552D01*
G01X192815Y427678D02*
X191414Y429079D01*
G01X192815Y426816D02*
Y427678D01*
G01X191868Y425869D02*
X192815Y426816D01*
G01X191868Y425007D02*
Y425869D01*
G01X193269Y423606D02*
X191868Y425007D01*
G01X194131Y423606D02*
X193269D01*
G01X195078Y424553D02*
X194131Y423606D01*
G01X195940Y424553D02*
X195078D01*
G01X197341Y423152D02*
X195940Y424553D01*
G01X197341Y422290D02*
Y423152D01*
G01X196394Y421343D02*
X197341Y422290D01*
G01X196394Y420481D02*
Y421343D01*
G01X177659Y435704D02*
Y433632D01*
G01X200992Y463236D02*
X197931Y466297D01*
G01X200992Y461000D02*
Y463236D01*
G01X225238Y436754D02*
X200992Y461000D01*
G01X225238Y434949D02*
Y436754D01*
G01X224107Y433818D02*
X225238Y434949D01*
G01X222975Y433818D02*
X224107D01*
G01X214636Y442157D02*
X222975Y433818D01*
G01X213604Y442157D02*
X214636D01*
G01X212473Y441026D02*
X213604Y442157D01*
G01X212473Y439794D02*
Y441026D01*
G01X228092Y424175D02*
X212473Y439794D01*
G01X228092Y413000D02*
Y424175D01*
G01X248592Y392500D02*
X228092Y413000D01*
G01X202292Y519590D02*
Y527600D01*
G01X201597Y518895D02*
X202292Y519590D01*
G01X201597Y517194D02*
Y518895D01*
G01X202692Y516099D02*
X201597Y517194D01*
G01X202692Y511799D02*
Y516099D01*
G01X201692Y510799D02*
X202692Y511799D01*
G01X201692Y508700D02*
Y510799D01*
G01X207992Y502400D02*
X201692Y508700D01*
G01X207992Y483769D02*
Y502400D01*
G01X209992Y525885D02*
Y527100D01*
G01X209382Y525275D02*
X209992Y525885D01*
G01X207902Y525275D02*
X209382D01*
G01X207292Y524665D02*
X207902Y525275D01*
G01X207292Y522685D02*
Y524665D01*
G01X207902Y522075D02*
X207292Y522685D01*
G01X209382Y522075D02*
X207902D01*
G01X209992Y521465D02*
X209382Y522075D01*
G01X209992Y520400D02*
Y521465D01*
G01X208502Y518910D02*
X209992Y520400D01*
G01X208502Y508790D02*
Y518910D01*
G01X214492Y502800D02*
X208502Y508790D01*
G01X214492Y500941D02*
Y502800D01*
G01X212992Y499441D02*
X214492Y500941D01*
G01X212992Y497741D02*
Y499441D01*
G01X214492Y496241D02*
X212992Y497741D01*
G01X214492Y495101D02*
Y496241D01*
G01X212992Y493601D02*
X214492Y495101D01*
G01X212992Y492301D02*
Y493601D01*
G01X214492Y490801D02*
X212992Y492301D01*
G01X214492Y490101D02*
Y490801D01*
G01X212992Y488601D02*
X214492Y490101D01*
G01X212992Y485841D02*
Y488601D01*
G01X251192Y447641D02*
X212992Y485841D01*
G01X171691Y503401D02*
X181592Y493500D01*
G01X171691Y504480D02*
Y503401D01*
G01X172301Y505090D02*
X171691Y504480D01*
G01X173592Y505090D02*
X172301D01*
G01X174092Y505590D02*
X173592Y505090D01*
G01X174092Y507790D02*
Y505590D01*
G01X173592Y508290D02*
X174092Y507790D01*
G01X172301Y508290D02*
X173592D01*
G01X171691Y508900D02*
X172301Y508290D01*
G01X171691Y518800D02*
Y508900D01*
G01X172492Y519601D02*
X171691Y518800D01*
G01X172492Y521825D02*
Y519601D01*
G01X171882Y522435D02*
X172492Y521825D01*
G01X171102Y522435D02*
X171882D01*
G01X170492Y523045D02*
X171102Y522435D01*
G01X170492Y525025D02*
Y523045D01*
G01X171102Y525635D02*
X170492Y525025D01*
G01X171882Y525635D02*
X171102D01*
G01X172492Y526245D02*
X171882Y525635D01*
G01X172492Y527400D02*
Y526245D01*
G01X225692Y519990D02*
Y527900D01*
G01X225202Y519500D02*
X225692Y519990D01*
G01X225202Y517589D02*
Y519500D01*
G01X226302Y516489D02*
X225202Y517589D01*
G01X226302Y512157D02*
Y516489D01*
G01X225402Y511257D02*
X226302Y512157D01*
G01X225402Y509190D02*
Y511257D01*
G01X227092Y507500D02*
X225402Y509190D01*
G01X227092Y490677D02*
Y507500D01*
G01X234380Y483389D02*
X227092Y490677D01*
G01X188892Y520001D02*
Y528000D01*
G01X188391Y519500D02*
X188892Y520001D01*
G01X188391Y517401D02*
Y519500D01*
G01X189491Y516301D02*
X188391Y517401D01*
G01X189491Y512157D02*
Y516301D01*
G01X188591Y511257D02*
X189491Y512157D01*
G01X188591Y505729D02*
Y511257D01*
G01X194192Y500128D02*
X188591Y505729D01*
G01X194192Y480388D02*
Y500128D01*
G01X196027Y478553D02*
X194192Y480388D01*
G01X196027Y477691D02*
Y478553D01*
G01X193795Y475459D02*
X196027Y477691D01*
G01X193795Y474597D02*
Y475459D01*
G01X195196Y473196D02*
X193795Y474597D01*
G01X196058Y473196D02*
X195196D01*
G01X198290Y475428D02*
X196058Y473196D01*
G01X199152Y475428D02*
X198290D01*
G01X202818Y471762D02*
X199152Y475428D01*
G01X202818Y470900D02*
Y471762D01*
G01X201286Y469368D02*
X202818Y470900D01*
G01X201286Y468506D02*
Y469368D01*
G01X202687Y467105D02*
X201286Y468506D01*
G01X203549Y467105D02*
X202687D01*
G01X205081Y468637D02*
X203549Y467105D01*
G01X205943Y468637D02*
X205081D01*
G01X169836Y501756D02*
X179092Y492500D01*
G01X169836Y509856D02*
Y501756D01*
G01X229036Y519966D02*
Y527844D01*
G01X229602Y519400D02*
X229036Y519966D01*
G01X229602Y517809D02*
Y519400D01*
G01X228802Y517009D02*
X229602Y517809D01*
G01X228802Y511657D02*
Y517009D01*
G01X229592Y510867D02*
X228802Y511657D01*
G01X229592Y491977D02*
Y510867D01*
G01X235680Y485889D02*
X229592Y491977D01*
G01X199202Y517389D02*
Y529489D01*
G01X198370Y516557D02*
X199202Y517389D01*
G01X198370Y511689D02*
Y516557D01*
G01X199166Y510893D02*
X198370Y511689D01*
G01X199166Y508226D02*
Y510893D01*
G01X205492Y501900D02*
X199166Y508226D01*
G01X205492Y482733D02*
Y501900D01*
G01X205291Y520011D02*
Y527499D01*
G01X205768Y519534D02*
X205291Y520011D01*
G01X205768Y517575D02*
Y519534D01*
G01X204492Y516299D02*
X205768Y517575D01*
G01X204492Y512217D02*
Y516299D01*
G01X205984Y510725D02*
X204492Y512217D01*
G01X205984Y508008D02*
Y510725D01*
G01X210492Y503500D02*
X205984Y508008D01*
G01X210492Y484805D02*
Y503500D01*
G01X222292Y520010D02*
Y527800D01*
G01X222702Y519600D02*
X222292Y520010D01*
G01X222702Y517557D02*
Y519600D01*
G01X222102Y516957D02*
X222702Y517557D01*
G01X222102Y512057D02*
Y516957D01*
G01X222902Y511257D02*
X222102Y512057D01*
G01X222902Y508591D02*
Y511257D01*
G01X224592Y506901D02*
X222902Y508591D01*
G01X224592Y489377D02*
Y506901D01*
G01X233080Y480889D02*
X224592Y489377D01*
G01X195592Y519551D02*
Y527800D01*
G01X195341Y519300D02*
X195592Y519551D01*
G01X195341Y516951D02*
Y519300D01*
G01X195891Y516401D02*
X195341Y516951D01*
G01X195891Y512257D02*
Y516401D01*
G01X195192Y511558D02*
X195891Y512257D01*
G01X195192Y506200D02*
Y511558D01*
G01X201062Y500330D02*
X195192Y506200D01*
G01X201062Y498969D02*
Y500330D01*
G01X200519Y498426D02*
X201062Y498969D01*
G01X199022Y498426D02*
X200519D01*
G01X198317Y497721D02*
X199022Y498426D01*
G01X198317Y496121D02*
Y497721D01*
G01X198945Y495493D02*
X198317Y496121D01*
G01X200692Y495493D02*
X198945D01*
G01X201492Y494693D02*
X200692Y495493D01*
G01X201492Y493093D02*
Y494693D01*
G01X200692Y492293D02*
X201492Y493093D01*
G01X199514Y492293D02*
X200692D01*
G01X198714Y491493D02*
X199514Y492293D01*
G01X198714Y489893D02*
Y491493D01*
G01X199514Y489093D02*
X198714Y489893D01*
G01X200692Y489093D02*
X199514D01*
G01X201492Y488293D02*
X200692Y489093D01*
G01X201492Y486693D02*
Y488293D01*
G01X200692Y485893D02*
X201492Y486693D01*
G01X199409Y485893D02*
X200692D01*
G01X198635Y485119D02*
X199409Y485893D01*
G01X198635Y483519D02*
Y485119D01*
G01X199461Y482693D02*
X198635Y483519D01*
G01X200692Y482693D02*
X199461D01*
G01X201492Y481893D02*
X200692Y482693D01*
G01X201492Y480999D02*
Y481893D01*
G01X192224Y520067D02*
Y527832D01*
G01X193192Y519099D02*
X192224Y520067D01*
G01X193192Y517800D02*
Y519099D01*
G01X191292Y515900D02*
X193192Y517800D01*
G01X191292Y512356D02*
Y515900D01*
G01X192692Y510956D02*
X191292Y512356D01*
G01X192692Y505164D02*
Y510956D01*
G01X196692Y501164D02*
X192692Y505164D01*
G01X196692Y481424D02*
Y501164D01*
G01X185492Y519599D02*
Y527700D01*
G01X185891Y519200D02*
X185492Y519599D01*
G01X185891Y517557D02*
Y519200D01*
G01X184892Y516558D02*
X185891Y517557D01*
G01X184892Y512456D02*
Y516558D01*
G01X185792Y511556D02*
X184892Y512456D01*
G01X185792Y504992D02*
Y511556D01*
G01X191692Y499092D02*
X185792Y504992D01*
G01X191692Y472536D02*
Y499092D01*
G01X194636Y469592D02*
X191692Y472536D01*
G01X195668Y469592D02*
X194636D01*
G01X196918Y470842D02*
X195668Y469592D01*
G01X198050Y470842D02*
X196918D01*
G01X199181Y469711D02*
X198050Y470842D01*
G01X199181Y468579D02*
Y469711D01*
G01X197931Y467329D02*
X199181Y468579D01*
G01X197931Y466297D02*
Y467329D01*
G01X198314Y566699D02*
X197242D01*
G01X198914Y566099D02*
X198314Y566699D01*
G01X198914Y565201D02*
Y566099D01*
G01X197877Y564164D02*
X198914Y565201D01*
G01X197877Y562936D02*
Y564164D01*
G01X198814Y561999D02*
X197877Y562936D01*
G01X198814Y560601D02*
Y561999D01*
G01X197877Y559664D02*
X198814Y560601D01*
G01X197877Y558336D02*
Y559664D01*
G01X199014Y557199D02*
X197877Y558336D01*
G01X199014Y555300D02*
Y557199D01*
G01X198514Y554800D02*
X199014Y555300D01*
G01X198514Y552600D02*
Y554800D01*
G01X200200Y550914D02*
X198514Y552600D01*
G01X200288Y550914D02*
X200200D01*
G01X200992Y550210D02*
X200288Y550914D01*
G01X200992Y547600D02*
Y550210D01*
G01X202292Y546300D02*
X200992Y547600D01*
G01X202292Y537990D02*
Y546300D01*
G01X201802Y537500D02*
X202292Y537990D01*
G01X201802Y535456D02*
Y537500D01*
G01X202402Y534856D02*
X201802Y535456D01*
G01X202402Y530697D02*
Y534856D01*
G01X201902Y530197D02*
X202402Y530697D01*
G01X201902Y527990D02*
Y530197D01*
G01X202292Y527600D02*
X201902Y527990D01*
G01X204915Y566699D02*
X203935D01*
G01X205514Y566100D02*
X204915Y566699D01*
G01X205514Y564900D02*
Y566100D01*
G01X204570Y563956D02*
X205514Y564900D01*
G01X204570Y562744D02*
Y563956D01*
G01X205414Y561900D02*
X204570Y562744D01*
G01X205414Y560200D02*
Y561900D01*
G01X204570Y559356D02*
X205414Y560200D01*
G01X204570Y557936D02*
Y559356D01*
G01X205714Y556792D02*
X204570Y557936D01*
G01X205714Y555199D02*
Y556792D01*
G01X204807Y554292D02*
X205714Y555199D01*
G01X204807Y552600D02*
Y554292D01*
G01X206493Y550914D02*
X204807Y552600D01*
G01X206581Y550914D02*
X206493D01*
G01X208502Y548993D02*
X206581Y550914D01*
G01X208502Y546890D02*
Y548993D01*
G01X209292Y546100D02*
X208502Y546890D01*
G01X209292Y544747D02*
Y546100D01*
G01X208682Y544137D02*
X209292Y544747D01*
G01X207602Y544137D02*
X208682D01*
G01X206992Y543527D02*
X207602Y544137D01*
G01X206992Y541547D02*
Y543527D01*
G01X207602Y540937D02*
X206992Y541547D01*
G01X208682Y540937D02*
X207602D01*
G01X209292Y540327D02*
X208682Y540937D01*
G01X209292Y538600D02*
Y540327D01*
G01X208502Y537810D02*
X209292Y538600D01*
G01X208502Y528590D02*
Y537810D01*
G01X209992Y527100D02*
X208502Y528590D01*
G01X169682Y550914D02*
X169770D01*
G01X171691Y528201D02*
X172492Y527400D01*
G01X171691Y537700D02*
Y528201D01*
G01X172192Y538201D02*
X171691Y537700D01*
G01X172192Y540456D02*
Y538201D01*
G01X170892Y541756D02*
X172192Y540456D01*
G01X170892Y543356D02*
Y541756D01*
G01X172192Y544656D02*
X170892Y543356D01*
G01X172192Y546400D02*
Y544656D01*
G01X171691Y546901D02*
X172192Y546400D01*
G01X171691Y548643D02*
Y546901D01*
G01X169770Y550564D02*
X171691Y548643D01*
G01X169770Y550914D02*
Y550564D01*
G01X221739Y566699D02*
X220667D01*
G01X222439Y565999D02*
X221739Y566699D01*
G01X222439Y564725D02*
Y565999D01*
G01X221302Y563588D02*
X222439Y564725D01*
G01X221302Y562512D02*
Y563588D01*
G01X222314Y561500D02*
X221302Y562512D01*
G01X222314Y560300D02*
Y561500D01*
G01X221302Y559288D02*
X222314Y560300D01*
G01X221302Y558212D02*
Y559288D01*
G01X222414Y557100D02*
X221302Y558212D01*
G01X222414Y554467D02*
Y557100D01*
G01X222239Y554292D02*
X222414Y554467D01*
G01X222239Y552600D02*
Y554292D01*
G01X223925Y550914D02*
X222239Y552600D01*
G01X224013Y550914D02*
X223925D01*
G01X225359Y549568D02*
X224013Y550914D01*
G01X225402Y549568D02*
X225359D01*
G01X225402Y546890D02*
Y549568D01*
G01X225692Y546600D02*
X225402Y546890D01*
G01X225692Y538000D02*
Y546600D01*
G01X225402Y537710D02*
X225692Y538000D01*
G01X225402Y536091D02*
Y537710D01*
G01X226068Y535425D02*
X225402Y536091D01*
G01X226068Y530363D02*
Y535425D01*
G01X225502Y529797D02*
X226068Y530363D01*
G01X225502Y528090D02*
Y529797D01*
G01X225692Y527900D02*
X225502Y528090D01*
G01X184928Y566699D02*
X183856D01*
G01X185628Y565999D02*
X184928Y566699D01*
G01X185628Y564725D02*
Y565999D01*
G01X184491Y563588D02*
X185628Y564725D01*
G01X184491Y562512D02*
Y563588D01*
G01X185503Y561500D02*
X184491Y562512D01*
G01X185503Y560300D02*
Y561500D01*
G01X184491Y559288D02*
X185503Y560300D01*
G01X184491Y558212D02*
Y559288D01*
G01X185603Y557100D02*
X184491Y558212D01*
G01X185603Y554467D02*
Y557100D01*
G01X185428Y554292D02*
X185603Y554467D01*
G01X185428Y552600D02*
Y554292D01*
G01X187114Y550914D02*
X185428Y552600D01*
G01X187202Y550914D02*
X187114D01*
G01X188548Y549568D02*
X187202Y550914D01*
G01X188591Y549568D02*
X188548D01*
G01X188591Y546700D02*
Y549568D01*
G01X188892Y546399D02*
X188591Y546700D01*
G01X188892Y538000D02*
Y546399D01*
G01X188591Y537699D02*
X188892Y538000D01*
G01X188591Y536301D02*
Y537699D01*
G01X189257Y535635D02*
X188591Y536301D01*
G01X189257Y530263D02*
Y535635D01*
G01X188691Y529697D02*
X189257Y530263D01*
G01X188691Y528201D02*
Y529697D01*
G01X188892Y528000D02*
X188691Y528201D01*
G01X226002Y554599D02*
X227360Y555957D01*
G01X226002Y552107D02*
Y554599D01*
G01X229402Y548707D02*
X226002Y552107D01*
G01X229402Y547110D02*
Y548707D01*
G01X229092Y546800D02*
X229402Y547110D01*
G01X229092Y537910D02*
Y546800D01*
G01X229402Y537600D02*
X229092Y537910D01*
G01X229402Y536242D02*
Y537600D01*
G01X228502Y535342D02*
X229402Y536242D01*
G01X228502Y530369D02*
Y535342D01*
G01X229465Y529406D02*
X228502Y530369D01*
G01X229465Y528273D02*
Y529406D01*
G01X229036Y527844D02*
X229465Y528273D01*
G01X225655Y567849D02*
X230706Y572900D01*
G01X225655Y557662D02*
Y567849D01*
G01X227360Y555957D02*
X225655Y557662D01*
G01X199214Y572500D02*
X200202D01*
G01X196159Y569445D02*
X199214Y572500D01*
G01X196159Y568257D02*
Y569445D01*
G01X195537Y567635D02*
X196159Y568257D01*
G01X195537Y557662D02*
Y567635D01*
G01X197242Y555957D02*
X195537Y557662D01*
G01X196699Y555414D02*
X197242Y555957D01*
G01X196699Y550894D02*
Y555414D01*
G01X199152Y548441D02*
X196699Y550894D01*
G01X199152Y536142D02*
Y548441D01*
G01X198154Y535144D02*
X199152Y536142D01*
G01X198154Y530537D02*
Y535144D01*
G01X199202Y529489D02*
X198154Y530537D01*
G01X205415Y572500D02*
X206581D01*
G01X202230Y569315D02*
X205415Y572500D01*
G01X202230Y557662D02*
Y569315D01*
G01X203935Y555957D02*
X202230Y557662D01*
G01X203142Y555164D02*
X203935Y555957D01*
G01X203142Y551367D02*
Y555164D01*
G01X205635Y548874D02*
X203142Y551367D01*
G01X205635Y546043D02*
Y548874D01*
G01X205105Y545513D02*
X205635Y546043D01*
G01X205105Y538547D02*
Y545513D01*
G01X205847Y537805D02*
X205105Y538547D01*
G01X205847Y536549D02*
Y537805D01*
G01X204652Y535354D02*
X205847Y536549D01*
G01X204652Y530617D02*
Y535354D01*
G01X205802Y529467D02*
X204652Y530617D01*
G01X205802Y528010D02*
Y529467D01*
G01X205291Y527499D02*
X205802Y528010D01*
G01X230706Y550966D02*
Y550914D01*
G01X232002Y549670D02*
X230706Y550966D01*
G01X228432Y566699D02*
X227360D01*
G01X229132Y565999D02*
X228432Y566699D01*
G01X229132Y564725D02*
Y565999D01*
G01X227995Y563588D02*
X229132Y564725D01*
G01X227995Y562512D02*
Y563588D01*
G01X229007Y561500D02*
X227995Y562512D01*
G01X229007Y560300D02*
Y561500D01*
G01X227995Y559288D02*
X229007Y560300D01*
G01X227995Y558212D02*
Y559288D01*
G01X229107Y557100D02*
X227995Y558212D01*
G01X229107Y554467D02*
Y557100D01*
G01X228932Y554292D02*
X229107Y554467D01*
G01X228932Y552600D02*
Y554292D01*
G01X230618Y550914D02*
X228932Y552600D01*
G01X230706Y550914D02*
X230618D01*
G01X218962Y557662D02*
X220667Y555957D01*
G01X218962Y567849D02*
Y557662D01*
G01X224013Y572900D02*
X218962Y567849D01*
G01X220002Y555292D02*
X220667Y555957D01*
G01X220002Y551457D02*
Y555292D01*
G01X222902Y548557D02*
X220002Y551457D01*
G01X222902Y547410D02*
Y548557D01*
G01X222292Y546800D02*
X222902Y547410D01*
G01X222292Y538210D02*
Y546800D01*
G01X222902Y537600D02*
X222292Y538210D01*
G01X222902Y536442D02*
Y537600D01*
G01X221629Y535169D02*
X222902Y536442D01*
G01X221629Y530670D02*
Y535169D01*
G01X222702Y529597D02*
X221629Y530670D01*
G01X222702Y528210D02*
Y529597D01*
G01X222292Y527800D02*
X222702Y528210D01*
G01X220667Y555957D02*
Y555961D01*
G01X191621Y566699D02*
X190549D01*
G01X192321Y565999D02*
X191621Y566699D01*
G01X192321Y564725D02*
Y565999D01*
G01X191184Y563588D02*
X192321Y564725D01*
G01X191184Y562512D02*
Y563588D01*
G01X192196Y561500D02*
X191184Y562512D01*
G01X192196Y560300D02*
Y561500D01*
G01X191184Y559288D02*
X192196Y560300D01*
G01X191184Y558212D02*
Y559288D01*
G01X192296Y557100D02*
X191184Y558212D01*
G01X192296Y554467D02*
Y557100D01*
G01X192121Y554292D02*
X192296Y554467D01*
G01X192121Y552600D02*
Y554292D01*
G01X193807Y550914D02*
X192121Y552600D01*
G01X193895Y550914D02*
X193807D01*
G01X193895Y550966D02*
Y550914D01*
G01X195191Y549670D02*
X193895Y550966D01*
G01X195191Y546801D02*
Y549670D01*
G01X195592Y546400D02*
X195191Y546801D01*
G01X195592Y537901D02*
Y546400D01*
G01X195191Y537500D02*
X195592Y537901D01*
G01X195191Y536302D02*
Y537500D01*
G01X196191Y535302D02*
X195191Y536302D01*
G01X196191Y530547D02*
Y535302D01*
G01X195341Y529697D02*
X196191Y530547D01*
G01X195341Y528051D02*
Y529697D01*
G01X195592Y527800D02*
X195341Y528051D01*
G01X189191Y554599D02*
X190549Y555957D01*
G01X189191Y552107D02*
Y554599D01*
G01X192591Y548707D02*
X189191Y552107D01*
G01X192591Y547099D02*
Y548707D01*
G01X192192Y546700D02*
X192591Y547099D01*
G01X192192Y538099D02*
Y546700D01*
G01X192591Y537700D02*
X192192Y538099D01*
G01X192591Y536242D02*
Y537700D01*
G01X191691Y535342D02*
X192591Y536242D01*
G01X191691Y530447D02*
Y535342D01*
G01X192791Y529347D02*
X191691Y530447D01*
G01X192791Y528399D02*
Y529347D01*
G01X192224Y527832D02*
X192791Y528399D01*
G01X188844Y567849D02*
X193895Y572900D01*
G01X188844Y557662D02*
Y567849D01*
G01X190549Y555957D02*
X188844Y557662D01*
G01X182151Y567849D02*
X187202Y572900D01*
G01X182151Y557662D02*
Y567849D01*
G01X183856Y555957D02*
X182151Y557662D01*
G01X183191Y555292D02*
X183856Y555957D01*
G01X183191Y551457D02*
Y555292D01*
G01X186091Y548557D02*
X183191Y551457D01*
G01X186091Y547099D02*
Y548557D01*
G01X185492Y546500D02*
X186091Y547099D01*
G01X185492Y538099D02*
Y546500D01*
G01X186091Y537500D02*
X185492Y538099D01*
G01X186091Y536442D02*
Y537500D01*
G01X184818Y535169D02*
X186091Y536442D01*
G01X184818Y530570D02*
Y535169D01*
G01X185891Y529497D02*
X184818Y530570D01*
G01X185891Y528099D02*
Y529497D01*
G01X185492Y527700D02*
X185891Y528099D01*
G01X261025Y31700D02*
X262825Y33500D01*
G01X260025Y31700D02*
X261025D01*
G01X258725Y30400D02*
X260025Y31700D01*
G01X258725Y29146D02*
Y30400D01*
G01X257478Y27899D02*
X258725Y29146D01*
G01X234053Y29453D02*
Y27899D01*
G01X236300Y31700D02*
X234053Y29453D01*
G01X237524Y31700D02*
X236300D01*
G01X239100Y33276D02*
X237524Y31700D01*
G01X277124Y17590D02*
X277557Y17157D01*
G01X277124Y24333D02*
Y17590D01*
G01X279424Y26633D02*
X277124Y24333D01*
G01X279424Y28467D02*
Y26633D01*
G01X278274Y29617D02*
X279424Y28467D01*
G01X278274Y34183D02*
Y29617D01*
G01X270864Y25272D02*
Y17157D01*
G01X272692Y27100D02*
X270864Y25272D01*
G01X272692Y28499D02*
Y27100D01*
G01X271924Y29267D02*
X272692Y28499D01*
G01X271924Y34299D02*
Y29267D01*
G01X271992Y14032D02*
X273910Y12114D01*
G01X271992Y15600D02*
Y14032D01*
G01X274192Y17800D02*
X271992Y15600D01*
G01X274192Y24900D02*
Y17800D01*
G01X275524Y26232D02*
X274192Y24900D01*
G01X275524Y28599D02*
Y26232D01*
G01X275774Y28849D02*
X275524Y28599D01*
G01X275774Y35049D02*
Y28849D01*
G01X278130Y14187D02*
X280203Y12114D01*
G01X278130Y15238D02*
Y14187D01*
G01X279624Y16732D02*
X278130Y15238D01*
G01X279624Y23533D02*
Y16732D01*
G01X282124Y26033D02*
X279624Y23533D01*
G01X282124Y118832D02*
Y26033D01*
G01X267718Y31700D02*
X269518Y33500D01*
G01X266718Y31700D02*
X267718D01*
G01X265418Y30400D02*
X266718Y31700D01*
G01X265418Y29146D02*
Y30400D01*
G01X264171Y27899D02*
X265418Y29146D01*
G01X240746Y30021D02*
Y27899D01*
G01X242625Y31900D02*
X240746Y30021D01*
G01X244025Y31900D02*
X242625D01*
G01X245481Y33356D02*
X244025Y31900D01*
G01X232152Y91668D02*
Y114400D01*
G01X232802Y91018D02*
X232152Y91668D01*
G01X232802Y86618D02*
Y91018D01*
G01X232102Y85918D02*
X232802Y86618D01*
G01X232102Y73091D02*
Y85918D01*
G01X232702Y72491D02*
X232102Y73091D01*
G01X232702Y67053D02*
Y72491D01*
G01X232152Y66503D02*
X232702Y67053D01*
G01X232152Y56768D02*
Y66503D01*
G01X232095Y35512D02*
Y48525D01*
G01X232707Y34900D02*
X232095Y35512D01*
G01X232707Y33500D02*
Y34900D01*
G01X262255Y91712D02*
Y105853D01*
G01X262955Y91012D02*
X262255Y91712D01*
G01X262955Y86674D02*
Y91012D01*
G01X262266Y85985D02*
X262955Y86674D01*
G01X262266Y73126D02*
Y85985D01*
G01X262855Y72537D02*
X262266Y73126D01*
G01X262855Y66947D02*
Y72537D01*
G01X261655Y65747D02*
X262855Y66947D01*
G01X261655Y56332D02*
Y65747D01*
G01X259024Y53701D02*
X261655Y56332D01*
G01X259024Y51714D02*
Y53701D01*
G01X260824Y49914D02*
X259024Y51714D01*
G01X262213Y48525D02*
X260824Y49914D01*
G01X262213Y35512D02*
Y48525D01*
G01X262825Y34900D02*
X262213Y35512D01*
G01X262825Y33500D02*
Y34900D01*
G01X236595Y49914D02*
X237099D01*
G01X235066Y51443D02*
X236595Y49914D01*
G01X235066Y53244D02*
Y51443D01*
G01X238655Y56833D02*
X235066Y53244D01*
G01X238655Y67059D02*
Y56833D01*
G01X238955Y67359D02*
X238655Y67059D01*
G01X238955Y72659D02*
Y67359D01*
G01X238655Y72959D02*
X238955Y72659D01*
G01X238655Y86074D02*
Y72959D01*
G01X239055Y86474D02*
X238655Y86074D01*
G01X239055Y91174D02*
Y86474D01*
G01X238755Y91474D02*
X239055Y91174D01*
G01X238755Y105628D02*
Y91474D01*
G01X239100Y34900D02*
Y33276D01*
G01X238325Y35675D02*
X239100Y34900D01*
G01X238325Y48688D02*
Y35675D01*
G01X237099Y49914D02*
X238325Y48688D01*
G01X279624Y35533D02*
X278274Y34183D01*
G01X279624Y47564D02*
Y35533D01*
G01X278274Y48914D02*
X279624Y47564D01*
G01X278274Y53182D02*
Y48914D01*
G01X279624Y54532D02*
X278274Y53182D01*
G01X279624Y66067D02*
Y54532D01*
G01X278274Y67417D02*
X279624Y66067D01*
G01X278274Y72083D02*
Y67417D01*
G01X279624Y73433D02*
X278274Y72083D01*
G01X279624Y85364D02*
Y73433D01*
G01X278274Y86714D02*
X279624Y85364D01*
G01X278274Y90982D02*
Y86714D01*
G01X279624Y92332D02*
X278274Y90982D01*
G01X279624Y104816D02*
Y92332D01*
G01X240746Y62954D02*
Y54957D01*
G01X242655Y64863D02*
X240746Y62954D01*
G01X242655Y66225D02*
Y64863D01*
G01X241466Y67414D02*
X242655Y66225D01*
G01X241466Y72157D02*
Y67414D01*
G01X242666Y73357D02*
X241466Y72157D01*
G01X242666Y85363D02*
Y73357D01*
G01X241155Y86874D02*
X242666Y85363D01*
G01X241155Y90662D02*
Y86874D01*
G01X242555Y92062D02*
X241155Y90662D01*
G01X242555Y105024D02*
Y92062D01*
G01X242525Y34567D02*
X243392Y33700D01*
G01X242525Y36868D02*
Y34567D01*
G01X240892Y38501D02*
X242525Y36868D01*
G01X240892Y39800D02*
Y38501D01*
G01X242242Y41150D02*
X240892Y39800D01*
G01X242242Y42050D02*
Y41150D01*
G01X240992Y43300D02*
X242242Y42050D01*
G01X240992Y44499D02*
Y43300D01*
G01X242525Y46032D02*
X240992Y44499D01*
G01X242525Y48000D02*
Y46032D01*
G01X239625Y50900D02*
X242525Y48000D01*
G01X239625Y53836D02*
Y50900D01*
G01X240746Y54957D02*
X239625Y53836D01*
G01X272924Y35299D02*
X271924Y34299D01*
G01X272924Y40882D02*
Y35299D01*
G01X271992Y41814D02*
X272924Y40882D01*
G01X271992Y44082D02*
Y41814D01*
G01X272924Y45014D02*
X271992Y44082D01*
G01X272924Y47614D02*
Y45014D01*
G01X271924Y48614D02*
X272924Y47614D01*
G01X271924Y53414D02*
Y48614D01*
G01X272824Y54314D02*
X271924Y53414D01*
G01X272824Y59853D02*
Y54314D01*
G01X271992Y60685D02*
X272824Y59853D01*
G01X271992Y63053D02*
Y60685D01*
G01X272824Y63885D02*
X271992Y63053D01*
G01X272824Y66267D02*
Y63885D01*
G01X271924Y67167D02*
X272824Y66267D01*
G01X271924Y72099D02*
Y67167D01*
G01X272924Y73099D02*
X271924Y72099D01*
G01X272924Y78377D02*
Y73099D01*
G01X272092Y79209D02*
X272924Y78377D01*
G01X272092Y81577D02*
Y79209D01*
G01X272924Y82409D02*
X272092Y81577D01*
G01X272924Y85414D02*
Y82409D01*
G01X271924Y86414D02*
X272924Y85414D01*
G01X271924Y91214D02*
Y86414D01*
G01X272824Y92114D02*
X271924Y91214D01*
G01X272824Y98712D02*
Y92114D01*
G01X275424Y35399D02*
X275774Y35049D01*
G01X275424Y48314D02*
Y35399D01*
G01X275774Y48664D02*
X275424Y48314D01*
G01X275774Y53614D02*
Y48664D01*
G01X275524Y53864D02*
X275774Y53614D01*
G01X275524Y66399D02*
Y53864D01*
G01X275774Y66649D02*
X275524Y66399D01*
G01X275774Y72849D02*
Y66649D01*
G01X275424Y73199D02*
X275774Y72849D01*
G01X275424Y86114D02*
Y73199D01*
G01X275774Y86464D02*
X275424Y86114D01*
G01X275774Y91414D02*
Y86464D01*
G01X275424Y91764D02*
X275774Y91414D01*
G01X275424Y105332D02*
Y91764D01*
G01X259455Y56934D02*
X257478Y54957D01*
G01X259455Y66271D02*
Y56934D01*
G01X258655Y67071D02*
X259455Y66271D01*
G01X258655Y72363D02*
Y67071D01*
G01X259466Y73174D02*
X258655Y72363D01*
G01X259466Y85963D02*
Y73174D01*
G01X258655Y86774D02*
X259466Y85963D01*
G01X258655Y91074D02*
Y86774D01*
G01X259755Y92174D02*
X258655Y91074D01*
G01X259755Y104775D02*
Y92174D01*
G01X259350Y35574D02*
X260824Y34100D01*
G01X259350Y36668D02*
Y35574D01*
G01X257917Y38101D02*
X259350Y36668D01*
G01X257917Y39324D02*
Y38101D01*
G01X259417Y40824D02*
X257917Y39324D01*
G01X259417Y42176D02*
Y40824D01*
G01X257917Y43676D02*
X259417Y42176D01*
G01X257917Y44799D02*
Y43676D01*
G01X259592Y46474D02*
X257917Y44799D01*
G01X259592Y47859D02*
Y46474D01*
G01X256550Y50901D02*
X259592Y47859D01*
G01X256550Y54029D02*
Y50901D01*
G01X257478Y54957D02*
X256550Y54029D01*
G01X263050Y53836D02*
X264171Y54957D01*
G01X263050Y50900D02*
Y53836D01*
G01X266392Y47558D02*
X263050Y50900D01*
G01X266392Y46500D02*
Y47558D01*
G01X264592Y44700D02*
X266392Y46500D01*
G01X264592Y43125D02*
Y44700D01*
G01X265792Y41925D02*
X264592Y43125D01*
G01X265792Y40799D02*
Y41925D01*
G01X264592Y39599D02*
X265792Y40799D01*
G01X264592Y38226D02*
Y39599D01*
G01X265950Y36868D02*
X264592Y38226D01*
G01X265950Y35667D02*
Y36868D01*
G01X267517Y34100D02*
X265950Y35667D01*
G01X266155Y91874D02*
Y105286D01*
G01X265566Y91285D02*
X266155Y91874D01*
G01X265566Y86463D02*
Y91285D01*
G01X266255Y85774D02*
X265566Y86463D01*
G01X266255Y73263D02*
Y85774D01*
G01X265455Y72463D02*
X266255Y73263D01*
G01X265455Y67071D02*
Y72463D01*
G01X266066Y66460D02*
X265455Y67071D01*
G01X266066Y61274D02*
Y66460D01*
G01X264171Y59379D02*
X266066Y61274D01*
G01X264171Y54957D02*
Y59379D01*
G01X234053Y61457D02*
Y54957D01*
G01X235955Y63359D02*
X234053Y61457D01*
G01X235955Y66237D02*
Y63359D01*
G01X235066Y67126D02*
X235955Y66237D01*
G01X235066Y72070D02*
Y67126D01*
G01X235955Y72959D02*
X235066Y72070D01*
G01X235955Y85574D02*
Y72959D01*
G01X235066Y86463D02*
X235955Y85574D01*
G01X235066Y91173D02*
Y86463D01*
G01X235955Y92062D02*
X235066Y91173D01*
G01X235955Y105286D02*
Y92062D01*
G01X235925Y34788D02*
X237013Y33700D01*
G01X235925Y36668D02*
Y34788D01*
G01X234492Y38101D02*
X235925Y36668D01*
G01X234492Y39300D02*
Y38101D01*
G01X235992Y40800D02*
X234492Y39300D01*
G01X235992Y42000D02*
Y40800D01*
G01X234542Y43450D02*
X235992Y42000D01*
G01X234542Y44849D02*
Y43450D01*
G01X235925Y46232D02*
X234542Y44849D01*
G01X235925Y48101D02*
Y46232D01*
G01X233125Y50901D02*
X235925Y48101D01*
G01X233125Y54029D02*
Y50901D01*
G01X234053Y54957D02*
X233125Y54029D01*
G01X268906Y48525D02*
X267517Y49914D01*
G01X268906Y35512D02*
Y48525D01*
G01X269518Y34900D02*
X268906Y35512D01*
G01X269518Y33500D02*
Y34900D01*
G01X268755Y91986D02*
Y106046D01*
G01X269455Y91286D02*
X268755Y91986D01*
G01X269455Y86562D02*
Y91286D01*
G01X268755Y85862D02*
X269455Y86562D01*
G01X268755Y73237D02*
Y85862D01*
G01X269466Y72526D02*
X268755Y73237D01*
G01X269466Y66970D02*
Y72526D01*
G01X268855Y66359D02*
X269466Y66970D01*
G01X268855Y54144D02*
Y66359D01*
G01X269655Y53344D02*
X268855Y54144D01*
G01X269655Y52052D02*
Y53344D01*
G01X267517Y49914D02*
X269655Y52052D01*
G01X241366Y51940D02*
X243392Y49914D01*
G01X241366Y53074D02*
Y51940D01*
G01X242766Y54474D02*
X241366Y53074D01*
G01X242766Y61774D02*
Y54474D01*
G01X245305Y64313D02*
X242766Y61774D01*
G01X245305Y105021D02*
Y64313D01*
G01X245481Y34700D02*
Y33356D01*
G01X244865Y35316D02*
X245481Y34700D01*
G01X244865Y48441D02*
Y35316D01*
G01X243392Y49914D02*
X244865Y48441D01*
G01X272792Y142800D02*
Y168434D01*
G01X247771Y117779D02*
X272792Y142800D01*
G01X246103Y117779D02*
X247771D01*
G01X245493Y118389D02*
X246103Y117779D01*
G01X245493Y120690D02*
Y118389D01*
G01X244883Y121300D02*
X245493Y120690D01*
G01X243493Y121300D02*
X244883D01*
G01X242883Y120690D02*
X243493Y121300D01*
G01X242883Y118389D02*
Y120690D01*
G01X242273Y117779D02*
X242883Y118389D01*
G01X235531Y117779D02*
X242273D01*
G01X232152Y114400D02*
X235531Y117779D01*
G01X262255Y105853D02*
X260824Y107284D01*
G01X237099D02*
X238755Y105628D01*
G01X266142Y150600D02*
Y168856D01*
G01X263741Y148199D02*
X266142Y150600D01*
G01X263741Y147337D02*
Y148199D01*
G01X265104Y145974D02*
X263741Y147337D01*
G01X265104Y145112D02*
Y145974D01*
G01X264120Y144128D02*
X265104Y145112D01*
G01X263258Y144128D02*
X264120D01*
G01X261895Y145491D02*
X263258Y144128D01*
G01X261033Y145491D02*
X261895D01*
G01X242392Y126850D02*
X261033Y145491D01*
G01X237529Y126850D02*
X242392D01*
G01X278266Y106174D02*
X279624Y104816D01*
G01X278266Y110316D02*
Y106174D01*
G01X279592Y111642D02*
X278266Y110316D01*
G01X279592Y119801D02*
Y111642D01*
G01X286492Y126701D02*
X279592Y119801D01*
G01X286492Y138749D02*
Y126701D01*
G01X292242Y144499D02*
X286492Y138749D01*
G01X292242Y146425D02*
Y144499D01*
G01X291632Y147035D02*
X292242Y146425D01*
G01X289852Y147035D02*
X291632D01*
G01X289242Y147645D02*
X289852Y147035D01*
G01X289242Y149035D02*
Y147645D01*
G01X289852Y149645D02*
X289242Y149035D01*
G01X291632Y149645D02*
X289852D01*
G01X292242Y150255D02*
X291632Y149645D01*
G01X292242Y151645D02*
Y150255D01*
G01X291632Y152255D02*
X292242Y151645D01*
G01X289852Y152255D02*
X291632D01*
G01X289242Y152865D02*
X289852Y152255D01*
G01X289242Y154255D02*
Y152865D01*
G01X289852Y154865D02*
X289242Y154255D01*
G01X291632Y154865D02*
X289852D01*
G01X292242Y155475D02*
X291632Y154865D01*
G01X292242Y156865D02*
Y155475D01*
G01X241455Y106124D02*
X242555Y105024D01*
G01X241455Y111618D02*
Y106124D01*
G01X240746Y112327D02*
X241455Y111618D01*
G01X271992Y99544D02*
X272824Y98712D01*
G01X271992Y101912D02*
Y99544D01*
G01X272824Y102744D02*
X271992Y101912D01*
G01X272824Y105316D02*
Y102744D01*
G01X271866Y106274D02*
X272824Y105316D01*
G01X271866Y110716D02*
Y106274D01*
G01X272824Y111674D02*
X271866Y110716D01*
G01X272824Y114132D02*
Y111674D01*
G01X273392Y114700D02*
X272824Y114132D01*
G01X273392Y121849D02*
Y114700D01*
G01X281542Y129999D02*
X273392Y121849D01*
G01X281542Y143149D02*
Y129999D01*
G01X282192Y143799D02*
X281542Y143149D01*
G01X282192Y154171D02*
Y143799D01*
G01X282752Y154731D02*
X282192Y154171D01*
G01X284132Y154731D02*
X282752D01*
G01X284692Y155291D02*
X284132Y154731D01*
G01X284692Y156731D02*
Y155291D01*
G01X275766Y105674D02*
X275424Y105332D01*
G01X275766Y110732D02*
Y105674D01*
G01X275424Y111074D02*
X275766Y110732D01*
G01X275424Y113200D02*
Y111074D01*
G01X275892Y113668D02*
X275424Y113200D01*
G01X275892Y119901D02*
Y113668D01*
G01X284292Y128301D02*
X275892Y119901D01*
G01X284292Y141400D02*
Y128301D01*
G01X287092Y144200D02*
X284292Y141400D01*
G01X287092Y165974D02*
Y144200D01*
G01X258855Y105675D02*
X259755Y104775D01*
G01X258855Y110950D02*
Y105675D01*
G01X257478Y112327D02*
X258855Y110950D01*
G01X264171Y107270D02*
Y112327D01*
G01X266155Y105286D02*
X264171Y107270D01*
G01X240020Y132014D02*
X239158D01*
G01X240732Y131302D02*
X240020Y132014D01*
G01X241594Y131302D02*
X240732D01*
G01X242578Y132286D02*
X241594Y131302D01*
G01X242578Y133148D02*
Y132286D01*
G01X241866Y133860D02*
X242578Y133148D01*
G01X241866Y134722D02*
Y133860D01*
G01X263692Y156548D02*
X241866Y134722D01*
G01X235055Y106186D02*
X235955Y105286D01*
G01X235055Y111325D02*
Y106186D01*
G01X234053Y112327D02*
X235055Y111325D01*
G01X288892Y125600D02*
X282124Y118832D01*
G01X288892Y136649D02*
Y125600D01*
G01X294742Y142499D02*
X288892Y136649D01*
G01X268755Y106046D02*
X267517Y107284D01*
G01X250292Y123600D02*
X237816D01*
G01X252537Y125845D02*
X250292Y123600D01*
G01X252537Y126707D02*
Y125845D01*
G01X251864Y127380D02*
X252537Y126707D01*
G01X251864Y128172D02*
Y127380D01*
G01X252918Y129226D02*
X251864Y128172D01*
G01X253710Y129226D02*
X252918D01*
G01X254383Y128553D02*
X253710Y129226D01*
G01X255245Y128553D02*
X254383D01*
G01X256229Y129537D02*
X255245Y128553D01*
G01X256229Y130399D02*
Y129537D01*
G01X255241Y131387D02*
X256229Y130399D01*
G01X255241Y132249D02*
Y131387D01*
G01X256225Y133233D02*
X255241Y132249D01*
G01X257087Y133233D02*
X256225D01*
G01X258075Y132245D02*
X257087Y133233D01*
G01X258937Y132245D02*
X258075D01*
G01X259921Y133229D02*
X258937Y132245D01*
G01X259921Y134091D02*
Y133229D01*
G01X258933Y135079D02*
X259921Y134091D01*
G01X258933Y135941D02*
Y135079D01*
G01X259917Y136925D02*
X258933Y135941D01*
G01X260779Y136925D02*
X259917D01*
G01X261767Y135937D02*
X260779Y136925D01*
G01X262629Y135937D02*
X261767D01*
G01X269392Y142700D02*
X262629Y135937D01*
G01X269392Y168570D02*
Y142700D01*
G01X243392Y106934D02*
X245305Y105021D01*
G01X285119Y180761D02*
Y182551D01*
G01X272792Y168434D02*
X285119Y180761D01*
G01X262544Y183227D02*
Y186099D01*
G01X249992Y170675D02*
X262544Y183227D01*
G01X249992Y160301D02*
Y170675D01*
G01X242492Y173783D02*
Y163409D01*
G01X255292Y186583D02*
X242492Y173783D01*
G01X255292Y190501D02*
Y186583D01*
G01X279442Y183953D02*
X281634Y186145D01*
G01X279442Y182156D02*
Y183953D01*
G01X266142Y168856D02*
X279442Y182156D01*
G01X257342Y187500D02*
X258209Y188367D01*
G01X257342Y185097D02*
Y187500D01*
G01X244992Y172747D02*
X257342Y185097D01*
G01X244992Y162373D02*
Y172747D01*
G01X279792Y215365D02*
X279799Y215372D01*
G01X279792Y214200D02*
Y215365D01*
G01X278392Y212800D02*
X279792Y214200D01*
G01X277092Y212800D02*
X278392D01*
G01X275292Y211000D02*
X277092Y212800D01*
G01X273692Y211000D02*
X275292D01*
G01X271692Y209000D02*
X273692Y211000D01*
G01X270192Y209000D02*
X271692D01*
G01X253392Y192200D02*
X270192Y209000D01*
G01X252302Y192200D02*
X253392D01*
G01X251692Y191590D02*
X252302Y192200D01*
G01X251692Y191501D02*
Y191590D01*
G01X247546Y187355D02*
X251692Y191501D01*
G01X247546Y186493D02*
Y187355D01*
G01X248758Y185280D02*
X247546Y186493D01*
G01X248758Y184418D02*
Y185280D01*
G01X247774Y183434D02*
X248758Y184418D01*
G01X246912Y183434D02*
X247774D01*
G01X245700Y184647D02*
X246912Y183434D01*
G01X244838Y184647D02*
X245700D01*
G01X243854Y183663D02*
X244838Y184647D01*
G01X243854Y182801D02*
Y183663D01*
G01X245066Y181588D02*
X243854Y182801D01*
G01X245066Y180726D02*
Y181588D01*
G01X244082Y179742D02*
X245066Y180726D01*
G01X243220Y179742D02*
X244082D01*
G01X242008Y180955D02*
X243220Y179742D01*
G01X241146Y180955D02*
X242008D01*
G01X238542Y178351D02*
X241146Y180955D01*
G01X238542Y164400D02*
Y178351D01*
G01X291192Y157915D02*
X292242Y156865D01*
G01X291192Y159645D02*
Y157915D01*
G01X292242Y160695D02*
X291192Y159645D01*
G01X292242Y174800D02*
Y160695D01*
G01X308448Y191006D02*
X292242Y174800D01*
G01X233460Y162368D02*
X232598D01*
G01X235992Y164900D02*
X233460Y162368D01*
G01X235992Y179337D02*
Y164900D01*
G01X265692Y209037D02*
X235992Y179337D01*
G01X265692Y209600D02*
Y209037D01*
G01X271092Y215000D02*
X265692Y209600D01*
G01X275397Y215000D02*
X271092D01*
G01X284132Y157291D02*
X284692Y156731D01*
G01X282752Y157291D02*
X284132D01*
G01X282192Y157851D02*
X282752Y157291D01*
G01X282192Y159291D02*
Y157851D01*
G01X282752Y159851D02*
X282192Y159291D01*
G01X284132Y159851D02*
X282752D01*
G01X284692Y160411D02*
X284132Y159851D01*
G01X284692Y161851D02*
Y160411D01*
G01X284132Y162411D02*
X284692Y161851D01*
G01X282752Y162411D02*
X284132D01*
G01X282192Y162971D02*
X282752Y162411D01*
G01X282192Y171750D02*
Y162971D01*
G01X303542Y193100D02*
X282192Y171750D01*
G01X286532Y166534D02*
X287092Y165974D01*
G01X284852Y166534D02*
X286532D01*
G01X284292Y167094D02*
X284852Y166534D01*
G01X284292Y168534D02*
Y167094D01*
G01X284852Y169094D02*
X284292Y168534D01*
G01X286532Y169094D02*
X284852D01*
G01X287092Y169654D02*
X286532Y169094D01*
G01X287092Y173000D02*
Y169654D01*
G01X305948Y191856D02*
X287092Y173000D01*
G01X263692Y169942D02*
Y156548D01*
G01X276642Y182892D02*
X263692Y169942D01*
G01X276642Y184689D02*
Y182892D01*
G01X279911Y187958D02*
X276642Y184689D01*
G01X232828Y173888D02*
X231966D01*
G01X233812Y174872D02*
X232828Y173888D01*
G01X233812Y175734D02*
Y174872D01*
G01X231749Y177796D02*
X233812Y175734D01*
G01X231749Y178658D02*
Y177796D01*
G01X270702Y217611D02*
X231749Y178658D01*
G01X272608Y217611D02*
X270702D01*
G01X247492Y171711D02*
Y161337D01*
G01X259742Y183961D02*
X247492Y171711D01*
G01X259742Y186812D02*
Y183961D01*
G01X260786Y187856D02*
X259742Y186812D01*
G01X281942Y181120D02*
X269392Y168570D01*
G01X281942Y182917D02*
Y181120D01*
G01X283417Y184392D02*
X281942Y182917D01*
G01X260489Y236500D02*
X261473Y237484D01*
G01X259720Y236500D02*
X260489D01*
G01X247842Y224622D02*
X259720Y236500D01*
G01X247842Y220022D02*
Y224622D01*
G01X263364Y232275D02*
X264964Y233875D01*
G01X262567Y232275D02*
X263364D01*
G01X252842Y222550D02*
X262567Y232275D01*
G01X252842Y217950D02*
Y222550D01*
G01X265039Y275400D02*
X266178Y274261D01*
G01X255442Y275400D02*
X265039D01*
G01X272608Y220111D02*
X269513D01*
G01X238792Y227590D02*
X256241Y245039D01*
G01X238792Y222950D02*
Y227590D01*
G01X242092Y227354D02*
X258409Y243671D01*
G01X242092Y222550D02*
Y227354D01*
G01X265411Y271650D02*
X266290Y272529D01*
G01X254692Y271650D02*
X265411D01*
G01X255363Y269321D02*
X261898D01*
G01X255763Y266821D02*
X261898D01*
G01X262082Y234543D02*
X263924Y236385D01*
G01X261299Y234543D02*
X262082D01*
G01X250342Y223586D02*
X261299Y234543D01*
G01X250342Y218986D02*
Y223586D01*
G01X259525Y239841D02*
X260278D01*
G01X245342Y225658D02*
X259525Y239841D01*
G01X245342Y221058D02*
Y225658D01*
G01X235529Y227863D02*
X255673Y248007D01*
G01X235529Y222587D02*
Y227863D01*
G01X259818Y321780D02*
X248141D01*
G01X255448Y340941D02*
X253752D01*
G01X250649Y329880D02*
X259208D01*
G01X249613Y327380D02*
X259088D01*
G01X259818Y324280D02*
X249177D01*
G01X264218Y400312D02*
X254295Y410235D01*
G01X239147Y383489D02*
X260192Y362444D01*
G01X239147Y389983D02*
Y383489D01*
G01X250477Y390039D02*
Y393281D01*
G01X259048Y381468D02*
X250477Y390039D01*
G01X237262Y381838D02*
X258459Y360641D01*
G01X237262Y389202D02*
Y381838D01*
G01X252428Y359600D02*
X255287Y356741D01*
G01X251592Y359600D02*
X252428D01*
G01X233492Y377700D02*
X251592Y359600D01*
G01X233492Y387640D02*
Y377700D01*
G01X262350Y398644D02*
X251692Y409302D01*
G01X235377Y380187D02*
X256948Y358616D01*
G01X235377Y388421D02*
Y380187D01*
G01X261292Y389300D02*
X239692Y410900D01*
G01X261292Y386318D02*
Y389300D01*
G01X264958Y382652D02*
X261292Y386318D01*
G01X258792Y387632D02*
X233506Y412918D01*
G01X258792Y385260D02*
Y387632D01*
G01X263179Y380873D02*
X258792Y385260D01*
G01X254352Y343441D02*
X255448D01*
G01X248592Y388388D02*
Y392500D01*
G01X257339Y379641D02*
X248592Y388388D01*
G01X246192Y427699D02*
Y445569D01*
G01X248987Y424904D02*
X246192Y427699D01*
G01X248987Y424042D02*
Y424904D01*
G01X248550Y423605D02*
X248987Y424042D01*
G01X248550Y422744D02*
Y423605D01*
G01X249951Y421343D02*
X248550Y422744D01*
G01X250813Y421343D02*
X249951D01*
G01X251250Y421779D02*
X250813Y421343D01*
G01X252112Y421779D02*
X251250D01*
G01X253513Y420378D02*
X252112Y421779D01*
G01X253513Y419516D02*
Y420378D01*
G01X253075Y419078D02*
X253513Y419516D01*
G01X253075Y418216D02*
Y419078D01*
G01X254295Y416996D02*
X253075Y418216D01*
G01X254295Y415240D02*
Y416996D01*
G01X254905Y414630D02*
X254295Y415240D01*
G01X256496Y414630D02*
X254905D01*
G01X257106Y414020D02*
X256496Y414630D01*
G01X257106Y412630D02*
Y414020D01*
G01X256496Y412020D02*
X257106Y412630D01*
G01X254905Y412020D02*
X256496D01*
G01X254295Y411410D02*
X254905Y412020D01*
G01X254295Y410235D02*
Y411410D01*
G01X278692Y442328D02*
Y487900D01*
G01X280297Y440723D02*
X278692Y442328D01*
G01X281429Y440723D02*
X280297D01*
G01X282226Y441520D02*
X281429Y440723D01*
G01X283252Y441520D02*
X282226D01*
G01X284383Y440389D02*
X283252Y441520D01*
G01X284383Y439151D02*
Y440389D01*
G01X283692Y438460D02*
X284383Y439151D01*
G01X283692Y437328D02*
Y438460D01*
G01X309825Y411195D02*
X283692Y437328D01*
G01X251192Y429001D02*
Y447641D01*
G01X263789Y416404D02*
X251192Y429001D01*
G01X263789Y415080D02*
Y416404D01*
G01X263179Y414470D02*
X263789Y415080D01*
G01X261774Y414470D02*
X263179D01*
G01X261164Y413860D02*
X261774Y414470D01*
G01X261164Y412470D02*
Y413860D01*
G01X261774Y411860D02*
X261164Y412470D01*
G01X263073Y411860D02*
X261774D01*
G01X263683Y411250D02*
X263073Y411860D01*
G01X263683Y410013D02*
Y411250D01*
G01X268748Y404948D02*
X263683Y410013D01*
G01X259121Y464098D02*
X239830Y483389D01*
G01X259121Y463236D02*
Y464098D01*
G01X258137Y462252D02*
X259121Y463236D01*
G01X257275Y462252D02*
X258137D01*
G01X252939Y466588D02*
X257275Y462252D01*
G01X251093Y464742D02*
Y465604D01*
G01X263792Y452043D02*
X251093Y464742D01*
G01X263792Y434465D02*
Y452043D01*
G01X282953Y415304D02*
X263792Y434465D01*
G01X282953Y409796D02*
Y415304D01*
G01X273592Y440100D02*
Y465816D01*
G01X304525Y409167D02*
X273592Y440100D01*
G01X261244Y464825D02*
X240180Y485889D01*
G01X261244Y457509D02*
Y464825D01*
G01X266292Y452461D02*
X261244Y457509D01*
G01X266292Y435501D02*
Y452461D01*
G01X291192Y410601D02*
X266292Y435501D01*
G01X291192Y407897D02*
Y410601D01*
G01X293707Y405382D02*
X291192Y407897D01*
G01X243692Y424899D02*
Y444533D01*
G01X251692Y416899D02*
X243692Y424899D01*
G01X251692Y409302D02*
Y416899D01*
G01X248692Y427901D02*
Y446605D01*
G01X259016Y417577D02*
X248692Y427901D01*
G01X259016Y411144D02*
Y417577D01*
G01X266925Y403235D02*
X259016Y411144D01*
G01X263572Y457933D02*
Y465787D01*
G01X264182Y457323D02*
X263572Y457933D01*
G01X265572Y457323D02*
X264182D01*
G01X266182Y457933D02*
X265572Y457323D01*
G01X266182Y462679D02*
Y457933D01*
G01X266792Y463289D02*
X266182Y462679D01*
G01X268182Y463289D02*
X266792D01*
G01X268792Y462679D02*
X268182Y463289D01*
G01X268792Y436537D02*
Y462679D01*
G01X295173Y410156D02*
X268792Y436537D01*
G01X249046Y463766D02*
Y470623D01*
G01X261292Y451520D02*
X249046Y463766D01*
G01X261292Y433376D02*
Y451520D01*
G01X280192Y414476D02*
X261292Y433376D01*
G01X280192Y409007D02*
Y414476D01*
G01X280998Y408201D02*
X280192Y409007D01*
G01X240001Y441358D02*
Y442490D01*
G01X238870Y440227D02*
X240001Y441358D01*
G01X237738Y440227D02*
X238870D01*
G01X239692Y421922D02*
Y433747D01*
G01X239082Y421312D02*
X239692Y421922D01*
G01X236556Y421312D02*
X239082D01*
G01X235946Y420702D02*
X236556Y421312D01*
G01X235946Y419312D02*
Y420702D01*
G01X236556Y418702D02*
X235946Y419312D01*
G01X239082Y418702D02*
X236556D01*
G01X239692Y418092D02*
X239082Y418702D01*
G01X239692Y416702D02*
Y418092D01*
G01X239082Y416092D02*
X239692Y416702D01*
G01X236556Y416092D02*
X239082D01*
G01X235946Y415482D02*
X236556Y416092D01*
G01X235946Y414092D02*
Y415482D01*
G01X236556Y413482D02*
X235946Y414092D01*
G01X239082Y413482D02*
X236556D01*
G01X239692Y412872D02*
X239082Y413482D01*
G01X239692Y410900D02*
Y412872D01*
G01X236795Y431150D02*
Y433599D01*
G01X236185Y430540D02*
X236795Y431150D01*
G01X233479Y430540D02*
X236185D01*
G01X232869Y429930D02*
X233479Y430540D01*
G01X232869Y428540D02*
Y429930D01*
G01X233479Y427930D02*
X232869Y428540D01*
G01X236185Y427930D02*
X233479D01*
G01X236795Y427320D02*
X236185Y427930D01*
G01X236795Y424947D02*
Y427320D01*
G01X233506Y421658D02*
X236795Y424947D01*
G01X233506Y412918D02*
Y421658D01*
G01X276192Y441200D02*
Y469239D01*
G01X307025Y410367D02*
X276192Y441200D01*
G01X281192Y444577D02*
Y486800D01*
G01X282109Y443660D02*
X281192Y444577D01*
G01X283709Y443660D02*
X282109D01*
G01X284392Y444343D02*
X283709Y443660D01*
G01X284392Y449858D02*
Y444343D01*
G01X285074Y450540D02*
X284392Y449858D01*
G01X286674Y450540D02*
X285074D01*
G01X287592Y449622D02*
X286674Y450540D01*
G01X287592Y437101D02*
Y449622D01*
G01X312325Y412368D02*
X287592Y437101D01*
G01X279355Y517388D02*
Y529513D01*
G01X278274Y516307D02*
X279355Y517388D01*
G01X278274Y512057D02*
Y516307D01*
G01X279408Y510923D02*
X278274Y512057D01*
G01X279408Y494916D02*
Y510923D01*
G01X278366Y493874D02*
X279408Y494916D01*
G01X278366Y488226D02*
Y493874D01*
G01X278692Y487900D02*
X278366Y488226D01*
G01X266113Y500429D02*
X264171Y498487D01*
G01X266113Y511157D02*
Y500429D01*
G01X265613Y511657D02*
X266113Y511157D01*
G01X265613Y517057D02*
Y511657D01*
G01X266392Y517836D02*
X265613Y517057D01*
G01X266392Y519221D02*
Y517836D01*
G01X265892Y519721D02*
X266392Y519221D01*
G01X265892Y527800D02*
Y519721D01*
G01X257478Y500787D02*
Y498487D01*
G01X259713Y503022D02*
X257478Y500787D01*
G01X259713Y511257D02*
Y503022D01*
G01X258913Y512057D02*
X259713Y511257D01*
G01X258913Y516957D02*
Y512057D01*
G01X259513Y517557D02*
X258913Y516957D01*
G01X259513Y519200D02*
Y517557D01*
G01X259192Y519521D02*
X259513Y519200D01*
G01X259192Y527500D02*
Y519521D01*
G01X239830Y483389D02*
X234380D01*
G01X252077Y466588D02*
X252939D01*
G01X251093Y465604D02*
X252077Y466588D01*
G01X272824Y517405D02*
Y529468D01*
G01X271924Y516505D02*
X272824Y517405D01*
G01X271924Y511797D02*
Y516505D01*
G01X272666Y511055D02*
X271924Y511797D01*
G01X272666Y502726D02*
Y511055D01*
G01X272792Y502600D02*
X272666Y502726D01*
G01X272792Y495200D02*
Y502600D01*
G01X272036Y494444D02*
X272792Y495200D01*
G01X272036Y488443D02*
Y494444D01*
G01X269492Y485899D02*
X272036Y488443D01*
G01X269492Y478822D02*
Y485899D01*
G01X270292Y478022D02*
X269492Y478822D01*
G01X271068Y478022D02*
X270292D01*
G01X271868Y477222D02*
X271068Y478022D01*
G01X271868Y475622D02*
Y477222D01*
G01X271068Y474822D02*
X271868Y475622D01*
G01X270292Y474822D02*
X271068D01*
G01X269492Y474022D02*
X270292Y474822D01*
G01X269492Y469916D02*
Y474022D01*
G01X273592Y465816D02*
X269492Y469916D01*
G01X240180Y485889D02*
X235680D01*
G01X232392Y519540D02*
Y527600D01*
G01X232152Y519300D02*
X232392Y519540D01*
G01X232152Y517357D02*
Y519300D01*
G01X232702Y516807D02*
X232152Y517357D01*
G01X232702Y512257D02*
Y516807D01*
G01X231492Y511047D02*
X232702Y512257D01*
G01X231492Y492900D02*
Y511047D01*
G01X235892Y488500D02*
X231492Y492900D01*
G01X240859Y488500D02*
X235892D01*
G01X243769Y485590D02*
X240859Y488500D01*
G01X244631Y485590D02*
X243769D01*
G01X246288Y487247D02*
X244631Y485590D01*
G01X247150Y487247D02*
X246288D01*
G01X248134Y486263D02*
X247150Y487247D01*
G01X248134Y485401D02*
Y486263D01*
G01X246477Y483744D02*
X248134Y485401D01*
G01X246477Y482882D02*
Y483744D01*
G01X263572Y465787D02*
X246477Y482882D01*
G01X238780Y480889D02*
X233080D01*
G01X249046Y470623D02*
X238780Y480889D01*
G01X260037Y492957D02*
X260824Y493744D01*
G01X258635Y492957D02*
X260037D01*
G01X258238Y493354D02*
X258635Y492957D01*
G01X258238Y494146D02*
Y493354D01*
G01X259192Y495100D02*
X258238Y494146D01*
G01X259192Y499399D02*
Y495100D01*
G01X262213Y502420D02*
X259192Y499399D01*
G01X262213Y511257D02*
Y502420D01*
G01X263113Y512157D02*
X262213Y511257D01*
G01X263113Y516557D02*
Y512157D01*
G01X262013Y517657D02*
X263113Y516557D01*
G01X262013Y519300D02*
Y517657D01*
G01X263092Y520379D02*
X262013Y519300D01*
G01X263092Y522400D02*
Y520379D01*
G01X262192Y523300D02*
X263092Y522400D01*
G01X262192Y524900D02*
Y523300D01*
G01X263092Y525800D02*
X262192Y524900D01*
G01X263092Y527400D02*
Y525800D01*
G01X243392Y504078D02*
Y495694D01*
G01X245313Y505999D02*
X243392Y504078D01*
G01X245313Y519120D02*
Y505999D01*
G01X245792Y519599D02*
X245313Y519120D01*
G01X245792Y529300D02*
Y519599D01*
G01X291492Y482400D02*
X296524Y487432D01*
G01X291492Y471678D02*
Y482400D01*
G01X297944Y465226D02*
X291492Y471678D01*
G01X269192Y519429D02*
Y527800D01*
G01X268963Y519200D02*
X269192Y519429D01*
G01X268963Y517357D02*
Y519200D01*
G01X269513Y516807D02*
X268963Y517357D01*
G01X269513Y512257D02*
Y516807D01*
G01X268913Y511657D02*
X269513Y512257D01*
G01X268913Y495248D02*
Y511657D01*
G01X267584Y493919D02*
X268913Y495248D01*
G01X275892Y519468D02*
Y527600D01*
G01X275524Y519100D02*
X275892Y519468D01*
G01X275524Y517457D02*
Y519100D01*
G01X275774Y517207D02*
X275524Y517457D01*
G01X275774Y511747D02*
Y517207D01*
G01X275566Y511539D02*
X275774Y511747D01*
G01X275566Y506426D02*
Y511539D01*
G01X275792Y506200D02*
X275566Y506426D01*
G01X275792Y495200D02*
Y506200D01*
G01X276492Y494500D02*
X275792Y495200D01*
G01X276492Y484744D02*
Y494500D01*
G01X275880Y484132D02*
X276492Y484744D01*
G01X272235Y484132D02*
X275880D01*
G01X271382Y483279D02*
X272235Y484132D01*
G01X271382Y481679D02*
Y483279D01*
G01X272129Y480932D02*
X271382Y481679D01*
G01X275392Y480932D02*
X272129D01*
G01X276192Y480132D02*
X275392Y480932D01*
G01X276192Y473659D02*
Y480132D01*
G01X275582Y473049D02*
X276192Y473659D01*
G01X272913Y473049D02*
X275582D01*
G01X272303Y472439D02*
X272913Y473049D01*
G01X272303Y470459D02*
Y472439D01*
G01X272862Y469900D02*
X272303Y470459D01*
G01X275531Y469900D02*
X272862D01*
G01X276192Y469239D02*
X275531Y469900D01*
G01X241292Y497600D02*
X239592Y495900D01*
G01X241292Y506977D02*
Y497600D01*
G01X242813Y508498D02*
X241292Y506977D01*
G01X242813Y510707D02*
Y508498D01*
G01X241463Y512057D02*
X242813Y510707D01*
G01X241463Y516307D02*
Y512057D01*
G01X242613Y517457D02*
X241463Y516307D01*
G01X242613Y519100D02*
Y517457D01*
G01X242392Y519321D02*
X242613Y519100D01*
G01X242392Y527900D02*
Y519321D01*
G01X233292Y501600D02*
Y498500D01*
G01X236113Y504421D02*
X233292Y501600D01*
G01X236113Y510757D02*
Y504421D01*
G01X235113Y511757D02*
X236113Y510757D01*
G01X235113Y516457D02*
Y511757D01*
G01X235869Y517213D02*
X235113Y516457D01*
G01X235869Y529523D02*
Y517213D01*
G01X282592Y519900D02*
Y527900D01*
G01X282124Y519432D02*
X282592Y519900D01*
G01X282124Y487732D02*
Y519432D01*
G01X281192Y486800D02*
X282124Y487732D01*
G01X238613Y492521D02*
X236892Y490800D01*
G01X238613Y494080D02*
Y492521D01*
G01X236992Y495701D02*
X238613Y494080D01*
G01X236992Y502179D02*
Y495701D01*
G01X238613Y503800D02*
X236992Y502179D01*
G01X238613Y510657D02*
Y503800D01*
G01X238963Y511007D02*
X238613Y510657D01*
G01X238963Y517207D02*
Y511007D01*
G01X238713Y517457D02*
X238963Y517207D01*
G01X238713Y519200D02*
Y517457D01*
G01X239092Y519579D02*
X238713Y519200D01*
G01X239092Y527700D02*
Y519579D01*
G01X279474Y586457D02*
X277557Y588374D01*
G01X279474Y574183D02*
Y586457D01*
G01X278324Y573033D02*
X279474Y574183D01*
G01X278324Y568367D02*
Y573033D01*
G01X279424Y567267D02*
X278324Y568367D01*
G01X279424Y555257D02*
Y567267D01*
G01X278274Y554107D02*
X279424Y555257D01*
G01X278274Y549857D02*
Y554107D01*
G01X279624Y548507D02*
X278274Y549857D01*
G01X279624Y536632D02*
Y548507D01*
G01X278274Y535282D02*
X279624Y536632D01*
G01X278274Y530594D02*
Y535282D01*
G01X279355Y529513D02*
X278274Y530594D01*
G01X262466Y557662D02*
X264171Y555957D01*
G01X262466Y567849D02*
Y557662D01*
G01X267517Y572900D02*
X262466Y567849D01*
G01X266413Y528321D02*
X265892Y527800D01*
G01X266413Y529497D02*
Y528321D01*
G01X265313Y530597D02*
X266413Y529497D01*
G01X265313Y535342D02*
Y530597D01*
G01X266213Y536242D02*
X265313Y535342D01*
G01X266213Y537600D02*
Y536242D01*
G01X265892Y537921D02*
X266213Y537600D01*
G01X265892Y546800D02*
Y537921D01*
G01X266213Y547121D02*
X265892Y546800D01*
G01X266213Y548707D02*
Y547121D01*
G01X262813Y552107D02*
X266213Y548707D01*
G01X262813Y554599D02*
Y552107D01*
G01X264171Y555957D02*
X262813Y554599D01*
G01X255773Y557662D02*
X257478Y555957D01*
G01X255773Y567849D02*
Y557662D01*
G01X260824Y572900D02*
X255773Y567849D01*
G01X259513Y527821D02*
X259192Y527500D01*
G01X259513Y529597D02*
Y527821D01*
G01X258440Y530670D02*
X259513Y529597D01*
G01X258440Y535169D02*
Y530670D01*
G01X259713Y536442D02*
X258440Y535169D01*
G01X259713Y537600D02*
Y536442D01*
G01X259192Y538121D02*
X259713Y537600D01*
G01X259192Y546200D02*
Y538121D01*
G01X259713Y546721D02*
X259192Y546200D01*
G01X259713Y548557D02*
Y546721D01*
G01X256813Y551457D02*
X259713Y548557D01*
G01X256813Y555292D02*
Y551457D01*
G01X257478Y555957D02*
X256813Y555292D01*
G01X272774Y586457D02*
X270864Y588367D01*
G01X272774Y573942D02*
Y586457D01*
G01X271776Y572944D02*
X272774Y573942D01*
G01X271776Y568217D02*
Y572944D01*
G01X272824Y567169D02*
X271776Y568217D01*
G01X272824Y555209D02*
Y567169D01*
G01X271924Y554309D02*
X272824Y555209D01*
G01X271924Y549557D02*
Y554309D01*
G01X272924Y548557D02*
X271924Y549557D01*
G01X272924Y536242D02*
Y548557D01*
G01X271924Y535242D02*
X272924Y536242D01*
G01X271924Y530368D02*
Y535242D01*
G01X272824Y529468D02*
X271924Y530368D01*
G01X232002Y546790D02*
Y549670D01*
G01X232392Y546400D02*
X232002Y546790D01*
G01X232392Y537900D02*
Y546400D01*
G01X232002Y537510D02*
X232392Y537900D01*
G01X232002Y536390D02*
Y537510D01*
G01X233002Y535390D02*
X232002Y536390D01*
G01X233002Y530697D02*
Y535390D01*
G01X232152Y529847D02*
X233002Y530697D01*
G01X232152Y527840D02*
Y529847D01*
G01X232392Y527600D02*
X232152Y527840D01*
G01X260736Y550914D02*
X260824D01*
G01X259050Y552600D02*
X260736Y550914D01*
G01X259050Y554292D02*
Y552600D01*
G01X259225Y554467D02*
X259050Y554292D01*
G01X259225Y557100D02*
Y554467D01*
G01X258113Y558212D02*
X259225Y557100D01*
G01X258113Y559288D02*
Y558212D01*
G01X259125Y560300D02*
X258113Y559288D01*
G01X259125Y561500D02*
Y560300D01*
G01X258113Y562512D02*
X259125Y561500D01*
G01X258113Y563588D02*
Y562512D01*
G01X259250Y564725D02*
X258113Y563588D01*
G01X259250Y565999D02*
Y564725D01*
G01X258550Y566699D02*
X259250Y565999D01*
G01X257478Y566699D02*
X258550D01*
G01X262313Y528179D02*
X263092Y527400D01*
G01X262313Y529797D02*
Y528179D01*
G01X262879Y530363D02*
X262313Y529797D01*
G01X262879Y535513D02*
Y530363D01*
G01X262213Y536179D02*
X262879Y535513D01*
G01X262213Y537700D02*
Y536179D01*
G01X263292Y538779D02*
X262213Y537700D01*
G01X263292Y540800D02*
Y538779D01*
G01X261992Y542100D02*
X263292Y540800D01*
G01X261992Y543400D02*
Y542100D01*
G01X263292Y544700D02*
X261992Y543400D01*
G01X263292Y546100D02*
Y544700D01*
G01X262213Y547179D02*
X263292Y546100D01*
G01X262213Y549568D02*
Y547179D01*
G01X262170Y549568D02*
X262213D01*
G01X260824Y550914D02*
X262170Y549568D01*
G01X243304Y550914D02*
X243392D01*
G01X241618Y552600D02*
X243304Y550914D01*
G01X241618Y554292D02*
Y552600D01*
G01X242525Y555199D02*
X241618Y554292D01*
G01X242525Y556792D02*
Y555199D01*
G01X241381Y557936D02*
X242525Y556792D01*
G01X241381Y559356D02*
Y557936D01*
G01X242225Y560200D02*
X241381Y559356D01*
G01X242225Y561900D02*
Y560200D01*
G01X241381Y562744D02*
X242225Y561900D01*
G01X241381Y563956D02*
Y562744D01*
G01X242325Y564900D02*
X241381Y563956D01*
G01X242325Y566100D02*
Y564900D01*
G01X241726Y566699D02*
X242325Y566100D01*
G01X240746Y566699D02*
X241726D01*
G01X245313Y529779D02*
X245792Y529300D01*
G01X245313Y537700D02*
Y529779D01*
G01X245792Y538179D02*
X245313Y537700D01*
G01X245792Y546500D02*
Y538179D01*
G01X245313Y546979D02*
X245792Y546500D01*
G01X245313Y548643D02*
Y546979D01*
G01X243392Y550564D02*
X245313Y548643D01*
G01X243392Y550914D02*
Y550564D01*
G01X267517Y550966D02*
Y550914D01*
G01X268792Y549691D02*
X267517Y550966D01*
G01X268792Y546300D02*
Y549691D01*
G01X267896Y545404D02*
X268792Y546300D01*
G01X267896Y543896D02*
Y545404D01*
G01X268792Y543000D02*
X267896Y543896D01*
G01X268792Y541899D02*
Y543000D01*
G01X267692Y540799D02*
X268792Y541899D01*
G01X267692Y539401D02*
Y540799D01*
G01X268813Y538280D02*
X267692Y539401D01*
G01X268813Y536478D02*
Y538280D01*
G01X269813Y535478D02*
X268813Y536478D01*
G01X269813Y530697D02*
Y535478D01*
G01X268963Y529847D02*
X269813Y530697D01*
G01X268963Y528029D02*
Y529847D01*
G01X269192Y527800D02*
X268963Y528029D01*
G01X265243Y566699D02*
X264171D01*
G01X265943Y565999D02*
X265243Y566699D01*
G01X265943Y564725D02*
Y565999D01*
G01X264806Y563588D02*
X265943Y564725D01*
G01X264806Y562512D02*
Y563588D01*
G01X265818Y561500D02*
X264806Y562512D01*
G01X265818Y560300D02*
Y561500D01*
G01X264806Y559288D02*
X265818Y560300D01*
G01X264806Y558212D02*
Y559288D01*
G01X265918Y557100D02*
X264806Y558212D01*
G01X265918Y554467D02*
Y557100D01*
G01X265743Y554292D02*
X265918Y554467D01*
G01X265743Y552600D02*
Y554292D01*
G01X267429Y550914D02*
X265743Y552600D01*
G01X267517Y550914D02*
X267429D01*
G01X275424Y587200D02*
X273910Y588714D01*
G01X275424Y584868D02*
Y587200D01*
G01X275892Y584400D02*
X275424Y584868D01*
G01X275892Y576200D02*
Y584400D01*
G01X275424Y575732D02*
X275892Y576200D01*
G01X275424Y573256D02*
Y575732D01*
G01X276024Y572656D02*
X275424Y573256D01*
G01X276024Y568497D02*
Y572656D01*
G01X275524Y567997D02*
X276024Y568497D01*
G01X275524Y566068D02*
Y567997D01*
G01X275892Y565700D02*
X275524Y566068D01*
G01X275892Y557268D02*
Y565700D01*
G01X275524Y556900D02*
X275892Y557268D01*
G01X275524Y555257D02*
Y556900D01*
G01X275774Y555007D02*
X275524Y555257D01*
G01X275774Y549235D02*
Y555007D01*
G01X275424Y548885D02*
X275774Y549235D01*
G01X275424Y547068D02*
Y548885D01*
G01X275892Y546600D02*
X275424Y547068D01*
G01X275892Y537968D02*
Y546600D01*
G01X275424Y537500D02*
X275892Y537968D01*
G01X275424Y535542D02*
Y537500D01*
G01X275774Y535192D02*
X275424Y535542D01*
G01X275774Y530242D02*
Y535192D01*
G01X275524Y529992D02*
X275774Y530242D01*
G01X275524Y527968D02*
Y529992D01*
G01X275892Y527600D02*
X275524Y527968D01*
G01X239041Y557662D02*
X240746Y555957D01*
G01X239041Y569315D02*
Y557662D01*
G01X242226Y572500D02*
X239041Y569315D01*
G01X243392Y572500D02*
X242226D01*
G01X242613Y528121D02*
X242392Y527900D01*
G01X242613Y529467D02*
Y528121D01*
G01X241513Y530567D02*
X242613Y529467D01*
G01X241513Y535321D02*
Y530567D01*
G01X242663Y536471D02*
X241513Y535321D01*
G01X242663Y537800D02*
Y536471D01*
G01X242392Y538071D02*
X242663Y537800D01*
G01X242392Y546800D02*
Y538071D01*
G01X242663Y547071D02*
X242392Y546800D01*
G01X242663Y548657D02*
Y547071D01*
G01X239313Y552007D02*
X242663Y548657D01*
G01X239313Y554524D02*
Y552007D01*
G01X240746Y555957D02*
X239313Y554524D01*
G01X232348Y557662D02*
X234053Y555957D01*
G01X232348Y567635D02*
Y557662D01*
G01X232970Y568257D02*
X232348Y567635D01*
G01X232970Y569445D02*
Y568257D01*
G01X236025Y572500D02*
X232970Y569445D01*
G01X237013Y572500D02*
X236025D01*
G01X235087Y530305D02*
X235869Y529523D01*
G01X235087Y535266D02*
Y530305D01*
G01X235893Y536072D02*
X235087Y535266D01*
G01X235893Y548727D02*
Y536072D01*
G01X233549Y551071D02*
X235893Y548727D01*
G01X233549Y555453D02*
Y551071D01*
G01X234053Y555957D02*
X233549Y555453D01*
G01X282124Y586443D02*
X280203Y588364D01*
G01X282124Y584268D02*
Y586443D01*
G01X282592Y583800D02*
X282124Y584268D01*
G01X282592Y576068D02*
Y583800D01*
G01X282124Y575600D02*
X282592Y576068D01*
G01X282124Y563068D02*
Y575600D01*
G01X282592Y562600D02*
X282124Y563068D01*
G01X282592Y556968D02*
Y562600D01*
G01X282124Y556500D02*
X282592Y556968D01*
G01X282124Y546768D02*
Y556500D01*
G01X282592Y546300D02*
X282124Y546768D01*
G01X282592Y538168D02*
Y546300D01*
G01X282124Y537700D02*
X282592Y538168D01*
G01X282124Y528368D02*
Y537700D01*
G01X282592Y527900D02*
X282124Y528368D01*
G01X237011Y550914D02*
X237099D01*
G01X235325Y552600D02*
X237011Y550914D01*
G01X235325Y554800D02*
Y552600D01*
G01X235825Y555300D02*
X235325Y554800D01*
G01X235825Y557199D02*
Y555300D01*
G01X234688Y558336D02*
X235825Y557199D01*
G01X234688Y559664D02*
Y558336D01*
G01X235625Y560601D02*
X234688Y559664D01*
G01X235625Y561999D02*
Y560601D01*
G01X234688Y562936D02*
X235625Y561999D01*
G01X234688Y564164D02*
Y562936D01*
G01X235725Y565201D02*
X234688Y564164D01*
G01X235725Y566099D02*
Y565201D01*
G01X235125Y566699D02*
X235725Y566099D01*
G01X234053Y566699D02*
X235125D01*
G01X238713Y528079D02*
X239092Y527700D01*
G01X238713Y530197D02*
Y528079D01*
G01X239213Y530697D02*
X238713Y530197D01*
G01X239213Y534856D02*
Y530697D01*
G01X238613Y535456D02*
X239213Y534856D01*
G01X238613Y537400D02*
Y535456D01*
G01X239092Y537879D02*
X238613Y537400D01*
G01X239092Y546400D02*
Y537879D01*
G01X238613Y546879D02*
X239092Y546400D01*
G01X238613Y549400D02*
Y546879D01*
G01X237099Y550914D02*
X238613Y549400D01*
G01X277557Y588374D02*
Y593757D01*
G01X270864Y588367D02*
Y593757D01*
G01X280203Y588364D02*
Y588714D01*
G01X303224Y19399D02*
X300982Y17157D01*
G01X303224Y28199D02*
Y19399D01*
G01X302424Y28999D02*
X303224Y28199D01*
G01X302424Y34831D02*
Y28999D01*
G01Y14018D02*
X304328Y12114D01*
G01X302424Y15532D02*
Y14018D01*
G01X305774Y18882D02*
X302424Y15532D01*
G01X305774Y28699D02*
Y18882D01*
G01X306324Y29249D02*
X305774Y28699D01*
G01X306324Y34769D02*
Y29249D01*
G01X294289Y17897D02*
Y17157D01*
G01X296324Y19932D02*
X294289Y17897D01*
G01X296324Y28499D02*
Y19932D01*
G01X295724Y29099D02*
X296324Y28499D01*
G01X295724Y34731D02*
Y29099D01*
G01Y14025D02*
X297635Y12114D01*
G01X295724Y15672D02*
Y14025D01*
G01X299124Y19072D02*
X295724Y15672D01*
G01X299124Y25099D02*
Y19072D01*
G01X298824Y25399D02*
X299124Y25099D01*
G01X298824Y28399D02*
Y25399D01*
G01X299924Y29499D02*
X298824Y28399D01*
G01X299924Y34367D02*
Y29499D01*
G01X349459Y31612D02*
Y36958D01*
G01X351179Y29892D02*
X349459Y31612D01*
G01X351179Y28022D02*
Y29892D01*
G01X354526Y28023D02*
X354525Y28022D01*
G01X354526Y32865D02*
Y28023D01*
G01X352892Y34499D02*
X354526Y32865D01*
G01X341140Y30692D02*
Y28022D01*
G01X339992Y31840D02*
X341140Y30692D01*
G01X339992Y34401D02*
Y31840D01*
G01X329362Y32969D02*
X324407Y28014D01*
G01X343732Y31811D02*
X342879Y33870D01*
G01X343893Y31000D02*
X343732Y31811D01*
G01X344486Y28022D02*
X343893Y31000D01*
G01X319824D02*
X321061Y28014D01*
G01X319342Y32165D02*
X319824Y31000D01*
G01X319342Y39613D02*
Y32165D01*
G01X314368Y32554D02*
Y28014D01*
G01X316092Y34278D02*
X314368Y32554D01*
G01X344486Y50000D02*
Y46922D01*
G01X346116Y51630D02*
X344486Y50000D01*
G01X346116Y56675D02*
Y51630D01*
G01X342820Y59971D02*
X346116Y56675D01*
G01X342820Y72641D02*
Y59971D01*
G01X342873Y72694D02*
X342820Y72641D01*
G01X342873Y74820D02*
Y72694D01*
G01X342538Y75155D02*
X342873Y74820D01*
G01X342538Y85674D02*
Y75155D01*
G01X343138Y86274D02*
X342538Y85674D01*
G01X343138Y88174D02*
Y86274D01*
G01X342729Y88583D02*
X343138Y88174D01*
G01X342729Y91265D02*
Y88583D01*
G01X342940Y91476D02*
X342729Y91265D01*
G01X342940Y98237D02*
Y91476D01*
G01X345589Y35957D02*
X344486D01*
G01X346155Y36523D02*
X345589Y35957D01*
G01X346155Y37539D02*
Y36523D01*
G01X345556Y38138D02*
X346155Y37539D01*
G01X343673Y38138D02*
X345556D01*
G01X343063Y38748D02*
X343673Y38138D01*
G01X343063Y39738D02*
Y38748D01*
G01X343673Y40348D02*
X343063Y39738D01*
G01X346771Y40348D02*
X343673D01*
G01X347381Y40958D02*
X346771Y40348D01*
G01X347381Y41948D02*
Y40958D01*
G01X346771Y42558D02*
X347381Y41948D01*
G01X343620Y42558D02*
X346771D01*
G01X343062Y43116D02*
X343620Y42558D01*
G01X343062Y44106D02*
Y43116D01*
G01X343724Y44768D02*
X343062Y44106D01*
G01X345577Y44768D02*
X343724D01*
G01X346207Y45398D02*
X345577Y44768D01*
G01X346207Y46422D02*
Y45398D01*
G01X345707Y46922D02*
X346207Y46422D01*
G01X344486Y46922D02*
X345707D01*
G01X302924Y35331D02*
X302424Y34831D01*
G01X302924Y48014D02*
Y35331D01*
G01X302324Y48614D02*
X302924Y48014D01*
G01X302324Y53314D02*
Y48614D01*
G01X303274Y54264D02*
X302324Y53314D01*
G01X303274Y65949D02*
Y54264D01*
G01X302424Y66799D02*
X303274Y65949D01*
G01X302424Y72631D02*
Y66799D01*
G01X302924Y73131D02*
X302424Y72631D01*
G01X302924Y85814D02*
Y73131D01*
G01X302324Y86414D02*
X302924Y85814D01*
G01X302324Y91164D02*
Y86414D01*
G01X303324Y92164D02*
X302324Y91164D01*
G01X303324Y103168D02*
Y92164D01*
G01X354525Y42066D02*
Y46922D01*
G01X356199Y40392D02*
X354525Y42066D01*
G01X354526Y35957D02*
X356199Y37630D01*
G01X354525Y52233D02*
X356833Y54541D01*
G01X354525Y46922D02*
Y52233D01*
G01X335707Y49000D02*
X337793Y46914D01*
G01X333402Y49000D02*
X335707D01*
G01X332530Y49872D02*
X333402Y49000D01*
G01X332530Y52238D02*
Y49872D01*
G01X332792Y52500D02*
X332530Y52238D01*
G01X332792Y67219D02*
Y52500D01*
G01X332252Y67759D02*
X332792Y67219D01*
G01X332252Y71829D02*
Y67759D01*
G01X332817Y72394D02*
X332252Y71829D01*
G01X332817Y85809D02*
Y72394D01*
G01X332452Y86174D02*
X332817Y85809D01*
G01X332452Y88374D02*
Y86174D01*
G01X332896Y88818D02*
X332452Y88374D01*
G01X332896Y91130D02*
Y88818D01*
G01X332452Y91574D02*
X332896Y91130D01*
G01X332452Y96461D02*
Y91574D01*
G01X337793Y37001D02*
Y35957D01*
G01X337218Y37576D02*
X337793Y37001D01*
G01X334257Y37576D02*
X337218D01*
G01X333373Y38460D02*
X334257Y37576D01*
G01X333373Y44417D02*
Y38460D01*
G01X333962Y45006D02*
X333373Y44417D01*
G01X334952Y45006D02*
X333962D01*
G01X335583Y44375D02*
X334952Y45006D01*
G01X335583Y40308D02*
Y44375D01*
G01X336193Y39698D02*
X335583Y40308D01*
G01X337183Y39698D02*
X336193D01*
G01X337793Y40308D02*
X337183Y39698D01*
G01X337793Y46914D02*
Y40308D01*
G01X305724Y35369D02*
X306324Y34769D01*
G01X305724Y48064D02*
Y35369D01*
G01X306235Y48575D02*
X305724Y48064D01*
G01X306235Y53453D02*
Y48575D01*
G01X305774Y53914D02*
X306235Y53453D01*
G01X305774Y66499D02*
Y53914D01*
G01X306274Y66999D02*
X305774Y66499D01*
G01X306274Y72517D02*
Y66999D01*
G01X305724Y73067D02*
X306274Y72517D01*
G01X305724Y85914D02*
Y73067D01*
G01X306224Y86414D02*
X305724Y85914D01*
G01X306224Y91474D02*
Y86414D01*
G01X305824Y91874D02*
X306224Y91474D01*
G01X305824Y103332D02*
Y91874D01*
G01X314368Y56385D02*
Y54857D01*
G01X316366Y58383D02*
X314368Y56385D01*
G01X316366Y64527D02*
Y58383D01*
G01X316001Y64892D02*
X316366Y64527D01*
G01X316001Y67094D02*
Y64892D01*
G01X316366Y67459D02*
X316001Y67094D01*
G01X316366Y69459D02*
Y67459D01*
G01X315766Y70059D02*
X316366Y69459D01*
G01X315766Y72359D02*
Y70059D01*
G01X316091Y72684D02*
X315766Y72359D01*
G01X316091Y75034D02*
Y72684D01*
G01X315766Y75359D02*
X316091Y75034D01*
G01X315766Y85674D02*
Y75359D01*
G01X316366Y86274D02*
X315766Y85674D01*
G01X316366Y88174D02*
Y86274D01*
G01X315666Y88874D02*
X316366Y88174D01*
G01X315666Y90974D02*
Y88874D01*
G01X316366Y91674D02*
X315666Y90974D01*
G01X316366Y94546D02*
Y91674D01*
G01X320097Y98277D02*
X316366Y94546D01*
G01X309392Y37586D02*
X311021Y35957D01*
G01X309392Y49000D02*
Y37586D01*
G01X309992Y49600D02*
X309392Y49000D01*
G01X309992Y51610D02*
Y49600D01*
G01X309316Y52286D02*
X309992Y51610D01*
G01X309316Y66809D02*
Y52286D01*
G01X310066Y67559D02*
X309316Y66809D01*
G01X310066Y72051D02*
Y67559D01*
G01X309412Y72705D02*
X310066Y72051D01*
G01X309412Y74781D02*
Y72705D01*
G01X309066Y75127D02*
X309412Y74781D01*
G01X309066Y85474D02*
Y75127D01*
G01X310066Y86474D02*
X309066Y85474D01*
G01X310066Y88224D02*
Y86474D01*
G01X309066Y89224D02*
X310066Y88224D01*
G01X309066Y91274D02*
Y89224D01*
G01X310066Y92274D02*
X309066Y91274D01*
G01X310066Y93904D02*
Y92274D01*
G01X316021Y99859D02*
X310066Y93904D01*
G01X296524Y35531D02*
X295724Y34731D01*
G01X296524Y47914D02*
Y35531D01*
G01X295724Y48714D02*
X296524Y47914D01*
G01X295724Y53414D02*
Y48714D01*
G01X296124Y53814D02*
X295724Y53414D01*
G01X296124Y66499D02*
Y53814D01*
G01X295724Y66899D02*
X296124Y66499D01*
G01X295724Y72531D02*
Y66899D01*
G01X296524Y73331D02*
X295724Y72531D01*
G01X296524Y85714D02*
Y73331D01*
G01X295724Y86514D02*
X296524Y85714D01*
G01X295724Y91214D02*
Y86514D01*
G01X296266Y91756D02*
X295724Y91214D01*
G01X296266Y97347D02*
Y91756D01*
G01X345838Y93308D02*
X348474Y95944D01*
G01X345838Y91574D02*
Y93308D01*
G01X346438Y90974D02*
X345838Y91574D01*
G01X346438Y88974D02*
Y90974D01*
G01X345838Y88374D02*
X346438Y88974D01*
G01X345838Y86174D02*
Y88374D01*
G01X346438Y85574D02*
X345838Y86174D01*
G01X346438Y83700D02*
Y85574D01*
G01X346144Y83406D02*
X346438Y83700D01*
G01X346144Y72453D02*
Y83406D01*
G01X346438Y72159D02*
X346144Y72453D01*
G01X346438Y69959D02*
Y72159D01*
G01X345638Y69159D02*
X346438Y69959D01*
G01X345638Y67759D02*
Y69159D01*
G01X346114Y67283D02*
X345638Y67759D01*
G01X346114Y59378D02*
Y67283D01*
G01X349542Y55950D02*
X346114Y59378D01*
G01X349542Y54120D02*
Y55950D01*
G01X348592Y53170D02*
X349542Y54120D01*
G01X348592Y49770D02*
Y53170D01*
G01X347833Y49011D02*
X348592Y49770D01*
G01X347833Y46922D02*
Y49011D01*
G01Y45272D02*
Y46922D01*
G01X349023Y44082D02*
X347833Y45272D01*
G01X349023Y38926D02*
Y44082D01*
G01X347833Y37736D02*
X349023Y38926D01*
G01X347833Y35957D02*
Y37736D01*
G01X299024Y35267D02*
X299924Y34367D01*
G01X299024Y47914D02*
Y35267D01*
G01X299824Y48714D02*
X299024Y47914D01*
G01X299824Y53214D02*
Y48714D01*
G01X299124Y53914D02*
X299824Y53214D01*
G01X299124Y66499D02*
Y53914D01*
G01X299924Y67299D02*
X299124Y66499D01*
G01X299924Y72267D02*
Y67299D01*
G01X299024Y73167D02*
X299924Y72267D01*
G01X299024Y85714D02*
Y73167D01*
G01X299824Y86514D02*
X299024Y85714D01*
G01X299824Y91014D02*
Y86514D01*
G01X299066Y91772D02*
X299824Y91014D01*
G01X299066Y103774D02*
Y91772D01*
G01X312748Y48641D02*
X311021Y46914D01*
G01X312748Y55615D02*
Y48641D01*
G01X311832Y56531D02*
X312748Y55615D01*
G01X311832Y61020D02*
Y56531D01*
G01X312748Y61936D02*
X311832Y61020D01*
G01X312748Y66977D02*
Y61936D01*
G01X312366Y67359D02*
X312748Y66977D01*
G01X312366Y69359D02*
Y67359D01*
G01X312966Y69959D02*
X312366Y69359D01*
G01X312966Y72459D02*
Y69959D01*
G01X312645Y72780D02*
X312966Y72459D01*
G01X312645Y74753D02*
Y72780D01*
G01X312966Y75074D02*
X312645Y74753D01*
G01X312966Y85874D02*
Y75074D01*
G01X312466Y86374D02*
X312966Y85874D01*
G01X312466Y88274D02*
Y86374D01*
G01X313166Y88974D02*
X312466Y88274D01*
G01X313166Y91074D02*
Y88974D01*
G01X312435Y91805D02*
X313166Y91074D01*
G01X312435Y93444D02*
Y91805D01*
G01X318010Y99019D02*
X312435Y93444D01*
G01X350474Y92524D02*
Y100111D01*
G01X349379Y91429D02*
X350474Y92524D01*
G01X349379Y89069D02*
Y91429D01*
G01X349633Y88815D02*
X349379Y89069D01*
G01X349633Y85883D02*
Y88815D01*
G01X349379Y85629D02*
X349633Y85883D01*
G01X349379Y83512D02*
Y85629D01*
G01X349464Y83427D02*
X349379Y83512D01*
G01X349464Y72599D02*
Y83427D01*
G01X349379Y72514D02*
X349464Y72599D01*
G01X349379Y70104D02*
Y72514D01*
G01X349560Y69923D02*
X349379Y70104D01*
G01X349560Y58833D02*
Y69923D01*
G01X351792Y56601D02*
X349560Y58833D01*
G01X351792Y55470D02*
Y56601D01*
G01X351179Y54857D02*
X351792Y55470D01*
G01X351179Y52164D02*
Y54857D01*
G01X350692Y51677D02*
X351179Y52164D01*
G01X350692Y49142D02*
Y51677D01*
G01X349452Y47902D02*
X350692Y49142D01*
G01X349452Y45979D02*
Y47902D01*
G01X350692Y44739D02*
X349452Y45979D01*
G01X350692Y38191D02*
Y44739D01*
G01X349459Y36958D02*
X350692Y38191D01*
G01X352892Y48018D02*
Y34499D01*
G01X352692Y48218D02*
X352892Y48018D01*
G01X352692Y51600D02*
Y48218D01*
G01X352892Y51800D02*
X352692Y51600D01*
G01X352892Y53223D02*
Y51800D01*
G01X354526Y54857D02*
X352892Y53223D01*
G01X354526Y56766D02*
Y54857D01*
G01X352892Y58400D02*
X354526Y56766D01*
G01X352892Y66991D02*
Y58400D01*
G01X352524Y67359D02*
X352892Y66991D01*
G01X352524Y69359D02*
Y67359D01*
G01X352905Y69740D02*
X352524Y69359D01*
G01X352905Y83513D02*
Y69740D01*
G01X353124Y83732D02*
X352905Y83513D01*
G01X353124Y85268D02*
Y83732D01*
G01X351892Y86500D02*
X353124Y85268D01*
G01X351892Y87542D02*
Y86500D01*
G01X353324Y88974D02*
X351892Y87542D01*
G01X353324Y91074D02*
Y88974D01*
G01X352593Y91805D02*
X353324Y91074D01*
G01X352593Y96874D02*
Y91805D01*
G01X341140Y56017D02*
Y54857D01*
G01X340377Y56780D02*
X341140Y56017D01*
G01X335810Y56780D02*
X340377D01*
G01X335039Y57551D02*
X335810Y56780D01*
G01X335039Y63038D02*
Y57551D01*
G01X336067Y64066D02*
X335039Y63038D01*
G01X336067Y66788D02*
Y64066D01*
G01X337140Y67861D02*
X336067Y66788D01*
G01X337140Y71565D02*
Y67861D01*
G01X336092Y72613D02*
X337140Y71565D01*
G01X336092Y83046D02*
Y72613D01*
G01X335838Y83300D02*
X336092Y83046D01*
G01X335838Y85474D02*
Y83300D01*
G01X336838Y86474D02*
X335838Y85474D01*
G01X336838Y88224D02*
Y86474D01*
G01X335838Y89224D02*
X336838Y88224D01*
G01X335838Y91274D02*
Y89224D01*
G01X337292Y92728D02*
X335838Y91274D01*
G01X337292Y93600D02*
Y92728D01*
G01X335508Y95384D02*
X337292Y93600D01*
G01X339409Y34984D02*
X339992Y34401D01*
G01X339409Y53126D02*
Y34984D01*
G01X341140Y54857D02*
X339409Y53126D01*
G01X325821Y91805D02*
Y95488D01*
G01X326552Y91074D02*
X325821Y91805D01*
G01X326552Y88974D02*
Y91074D01*
G01X325852Y88274D02*
X326552Y88974D01*
G01X325852Y86374D02*
Y88274D01*
G01X326352Y85874D02*
X325852Y86374D01*
G01X326352Y83900D02*
Y85874D01*
G01X326138Y83686D02*
X326352Y83900D01*
G01X326138Y72673D02*
Y83686D01*
G01X326352Y72459D02*
X326138Y72673D01*
G01X326352Y69959D02*
Y72459D01*
G01X325752Y69359D02*
X326352Y69959D01*
G01X325752Y67359D02*
Y69359D01*
G01X326019Y67092D02*
X325752Y67359D01*
G01X326019Y60968D02*
Y67092D01*
G01X322792Y57741D02*
X326019Y60968D01*
G01X322792Y51876D02*
Y57741D01*
G01X327754Y46914D02*
X322792Y51876D01*
G01X326092Y45252D02*
X327754Y46914D01*
G01X326092Y36857D02*
Y45252D01*
G01X326992Y35957D02*
X326092Y36857D01*
G01X327754Y35957D02*
X326992D01*
G01X329362Y48531D02*
Y32969D01*
G01X324407Y53486D02*
X329362Y48531D01*
G01X324407Y54857D02*
Y53486D01*
G01Y55875D02*
Y54857D01*
G01X329487Y60955D02*
X324407Y55875D01*
G01X329487Y67194D02*
Y60955D01*
G01X329752Y67459D02*
X329487Y67194D01*
G01X329752Y69459D02*
Y67459D01*
G01X329152Y70059D02*
X329752Y69459D01*
G01X329152Y72359D02*
Y70059D01*
G01X329393Y72600D02*
X329152Y72359D01*
G01X329393Y83798D02*
Y72600D01*
G01X329152Y84039D02*
X329393Y83798D01*
G01X329152Y85674D02*
Y84039D01*
G01X329752Y86274D02*
X329152Y85674D01*
G01X329752Y88174D02*
Y86274D01*
G01X329052Y88874D02*
X329752Y88174D01*
G01X329052Y90974D02*
Y88874D01*
G01X330452Y92374D02*
X329052Y90974D01*
G01X330452Y97290D02*
Y92374D01*
G01X342862Y50936D02*
X344486Y54857D01*
G01X342862Y46232D02*
Y50936D01*
G01X341432Y44802D02*
X342862Y46232D01*
G01X341432Y38096D02*
Y44802D01*
G01X342879Y36649D02*
X341432Y38096D01*
G01X342879Y33870D02*
Y36649D01*
G01X339340Y91672D02*
Y97466D01*
G01X340392Y90620D02*
X339340Y91672D01*
G01X340392Y89428D02*
Y90620D01*
G01X339238Y88274D02*
X340392Y89428D01*
G01X339238Y86374D02*
Y88274D01*
G01X339738Y85874D02*
X339238Y86374D01*
G01X339738Y83330D02*
Y85874D01*
G01X339416Y83008D02*
X339738Y83330D01*
G01X339416Y72781D02*
Y83008D01*
G01X340401Y71796D02*
X339416Y72781D01*
G01X340401Y69462D02*
Y71796D01*
G01X339534Y68595D02*
X340401Y69462D01*
G01X339534Y65085D02*
Y68595D01*
G01X341022Y63597D02*
X339534Y65085D01*
G01X341022Y62549D02*
Y63597D01*
G01X340276Y61803D02*
X341022Y62549D01*
G01X338743Y61803D02*
X340276D01*
G01X338133Y61193D02*
X338743Y61803D01*
G01X338133Y60203D02*
Y61193D01*
G01X338743Y59593D02*
X338133Y60203D01*
G01X340850Y59593D02*
X338743D01*
G01X344486Y55957D02*
X340850Y59593D01*
G01X344486Y54857D02*
Y55957D01*
G01X321061Y58799D02*
Y54857D01*
G01X322792Y60530D02*
X321061Y58799D01*
G01X322792Y66899D02*
Y60530D01*
G01X323452Y67559D02*
X322792Y66899D01*
G01X323452Y72053D02*
Y67559D01*
G01X322799Y72706D02*
X323452Y72053D01*
G01X322799Y74892D02*
Y72706D01*
G01X322452Y75239D02*
X322799Y74892D01*
G01X322452Y85474D02*
Y75239D01*
G01X323452Y86474D02*
X322452Y85474D01*
G01X323452Y88224D02*
Y86474D01*
G01X322452Y89224D02*
X323452Y88224D01*
G01X322452Y91274D02*
Y89224D01*
G01X323452Y92274D02*
X322452Y91274D01*
G01X323452Y95948D02*
Y92274D01*
G01X319952Y40223D02*
X319342Y39613D01*
G01X320875Y40223D02*
X319952D01*
G01X321485Y40833D02*
X320875Y40223D01*
G01X321485Y42733D02*
Y40833D01*
G01X320875Y43343D02*
X321485Y42733D01*
G01X319952Y43343D02*
X320875D01*
G01X319342Y43953D02*
X319952Y43343D01*
G01X319342Y53238D02*
Y43953D01*
G01X320961Y54857D02*
X319342Y53238D01*
G01X321061Y54857D02*
X320961D01*
G01X316092Y49740D02*
Y34278D01*
G01X315992Y49840D02*
X316092Y49740D01*
G01X315992Y55660D02*
Y49840D01*
G01X318392Y58060D02*
X315992Y55660D01*
G01X318392Y63901D02*
Y58060D01*
G01X319448Y64957D02*
X318392Y63901D01*
G01X319448Y67277D02*
Y64957D01*
G01X318866Y67859D02*
X319448Y67277D01*
G01X318866Y69159D02*
Y67859D01*
G01X319342Y69635D02*
X318866Y69159D01*
G01X319342Y83450D02*
Y69635D01*
G01X319666Y83774D02*
X319342Y83450D01*
G01X319666Y85574D02*
Y83774D01*
G01X319066Y86174D02*
X319666Y85574D01*
G01X319066Y88374D02*
Y86174D01*
G01X319666Y88974D02*
X319066Y88374D01*
G01X319666Y90974D02*
Y88974D01*
G01X319066Y91574D02*
X319666Y90974D01*
G01X319066Y94417D02*
Y91574D01*
G01X322330Y97681D02*
X319066Y94417D01*
G01X360092Y115389D02*
X342940Y98237D01*
G01X302366Y104126D02*
X303324Y103168D01*
G01X302366Y108474D02*
Y104126D01*
G01X302892Y109000D02*
X302366Y108474D01*
G01X302892Y116100D02*
Y109000D01*
G01X312637Y125845D02*
X302892Y116100D01*
G01X312637Y129030D02*
Y125845D01*
G01X313197Y129590D02*
X312637Y129030D01*
G01X313932Y129590D02*
X313197D01*
G01X314492Y130150D02*
X313932Y129590D01*
G01X314492Y131590D02*
Y130150D01*
G01X313932Y132150D02*
X314492Y131590D01*
G01X313197Y132150D02*
X313932D01*
G01X312637Y132710D02*
X313197Y132150D01*
G01X312637Y134150D02*
Y132710D01*
G01X313197Y134710D02*
X312637Y134150D01*
G01X313932Y134710D02*
X313197D01*
G01X314492Y135270D02*
X313932Y134710D01*
G01X314492Y136710D02*
Y135270D01*
G01X313932Y137270D02*
X314492Y136710D01*
G01X313197Y137270D02*
X313932D01*
G01X312637Y137830D02*
X313197Y137270D01*
G01X312637Y139270D02*
Y137830D01*
G01X313197Y139830D02*
X312637Y139270D01*
G01X313932Y139830D02*
X313197D01*
G01X314492Y140390D02*
X313932Y139830D01*
G01X314492Y141830D02*
Y140390D01*
G01X313932Y142390D02*
X314492Y141830D01*
G01X313197Y142390D02*
X313932D01*
G01X312637Y142950D02*
X313197Y142390D01*
G01X312637Y144390D02*
Y142950D01*
G01X313197Y144950D02*
X312637Y144390D01*
G01X313932Y144950D02*
X313197D01*
G01X314492Y145510D02*
X313932Y144950D01*
G01X314492Y146950D02*
Y145510D01*
G01X313932Y147510D02*
X314492Y146950D01*
G01X313197Y147510D02*
X313932D01*
G01X312637Y148070D02*
X313197Y147510D01*
G01X312637Y149510D02*
Y148070D01*
G01X313197Y150070D02*
X312637Y149510D01*
G01X313932Y150070D02*
X313197D01*
G01X314492Y150630D02*
X313932Y150070D01*
G01X314492Y152070D02*
Y150630D01*
G01X313932Y152630D02*
X314492Y152070D01*
G01X313197Y152630D02*
X313932D01*
G01X312637Y153190D02*
X313197Y152630D01*
G01X312637Y169072D02*
Y153190D01*
G01X352188Y116197D02*
X332452Y96461D01*
G01X352188Y199049D02*
Y116197D01*
G01X306366Y103874D02*
X305824Y103332D01*
G01X306366Y112624D02*
Y103874D01*
G01X316592Y122850D02*
X306366Y112624D01*
G01X316592Y169414D02*
Y122850D01*
G01X320097Y107302D02*
Y98277D01*
G01X343486Y130691D02*
X320097Y107302D01*
G01X343486Y198703D02*
Y130691D01*
G01X316021Y109636D02*
Y99859D01*
G01X340101Y133716D02*
X316021Y109636D01*
G01X340101Y197885D02*
Y133716D01*
G01X295392Y98221D02*
X296266Y97347D01*
G01X295392Y100547D02*
Y98221D01*
G01X296266Y101421D02*
X295392Y100547D01*
G01X296266Y103526D02*
Y101421D01*
G01X295558Y104234D02*
X296266Y103526D01*
G01X295558Y108366D02*
Y104234D01*
G01X296692Y109500D02*
X295558Y108366D01*
G01X296692Y117416D02*
Y109500D01*
G01X305342Y126066D02*
X296692Y117416D01*
G01X305342Y136896D02*
Y126066D01*
G01X305952Y137506D02*
X305342Y136896D01*
G01X307273Y137506D02*
X305952D01*
G01X307883Y138116D02*
X307273Y137506D01*
G01X307883Y139336D02*
Y138116D01*
G01X307273Y139946D02*
X307883Y139336D01*
G01X305952Y139946D02*
X307273D01*
G01X305342Y140556D02*
X305952Y139946D01*
G01X305342Y141776D02*
Y140556D01*
G01X305952Y142386D02*
X305342Y141776D01*
G01X307273Y142386D02*
X305952D01*
G01X307883Y142996D02*
X307273Y142386D01*
G01X307883Y144216D02*
Y142996D01*
G01X307273Y144826D02*
X307883Y144216D01*
G01X305952Y144826D02*
X307273D01*
G01X305342Y145436D02*
X305952Y144826D01*
G01X305342Y146656D02*
Y145436D01*
G01X305952Y147266D02*
X305342Y146656D01*
G01X307273Y147266D02*
X305952D01*
G01X307883Y147876D02*
X307273Y147266D01*
G01X307883Y149096D02*
Y147876D01*
G01X307273Y149706D02*
X307883Y149096D01*
G01X305952Y149706D02*
X307273D01*
G01X305342Y150316D02*
X305952Y149706D01*
G01X305342Y169159D02*
Y150316D01*
G01X348474Y100941D02*
X362092Y114559D01*
G01X348474Y95944D02*
Y100941D01*
G01X299866Y104574D02*
X299066Y103774D01*
G01X299866Y108026D02*
Y104574D01*
G01X299124Y108768D02*
X299866Y108026D01*
G01X299124Y116432D02*
Y108768D01*
G01X307692Y125000D02*
X299124Y116432D01*
G01X307692Y133200D02*
Y125000D01*
G01X310442Y135950D02*
X307692Y133200D01*
G01X310442Y170723D02*
Y135950D01*
G01X318010Y108578D02*
Y99019D01*
G01X341660Y132228D02*
X318010Y108578D01*
G01X341660Y197909D02*
Y132228D01*
G01X294742Y172987D02*
Y142499D01*
G01X350474Y100111D02*
X364092Y113729D01*
G01X354913Y99194D02*
X352593Y96874D01*
G01X335508Y96516D02*
Y95384D01*
G01X356092Y117100D02*
X335508Y96516D01*
G01X348188Y121425D02*
Y198224D01*
G01X331600Y104837D02*
X348188Y121425D01*
G01X331600Y101267D02*
Y104837D01*
G01X325821Y95488D02*
X331600Y101267D01*
G01X334976Y101814D02*
X330452Y97290D01*
G01X334976Y103084D02*
Y101814D01*
G01X334222Y103838D02*
X334976Y103084D01*
G01X334222Y104546D02*
Y103838D01*
G01X335721Y106045D02*
X334222Y104546D01*
G01X336429Y106045D02*
X335721D01*
G01X337387Y105087D02*
X336429Y106045D01*
G01X338249Y105087D02*
X337387D01*
G01X339594Y106432D02*
X338249Y105087D01*
G01X339594Y107294D02*
Y106432D01*
G01X338497Y108391D02*
X339594Y107294D01*
G01X338497Y109253D02*
Y108391D01*
G01X339842Y110598D02*
X338497Y109253D01*
G01X340704Y110598D02*
X339842D01*
G01X341801Y109501D02*
X340704Y110598D01*
G01X342663Y109501D02*
X341801D01*
G01X344008Y110846D02*
X342663Y109501D01*
G01X344008Y111708D02*
Y110846D01*
G01X342911Y112805D02*
X344008Y111708D01*
G01X342911Y113667D02*
Y112805D01*
G01X344256Y115012D02*
X342911Y113667D01*
G01X345118Y115012D02*
X344256D01*
G01X345930Y114200D02*
X345118Y115012D01*
G01X346638Y114200D02*
X345930D01*
G01X350188Y117750D02*
X346638Y114200D01*
G01X350188Y198928D02*
Y117750D01*
G01X339340Y97466D02*
X358092Y116218D01*
G01X329492Y101988D02*
X323452Y95948D01*
G01X329492Y105558D02*
Y101988D01*
G01X346576Y122642D02*
X329492Y105558D01*
G01X346576Y198054D02*
Y122642D01*
G01X322330Y106338D02*
Y97681D01*
G01X345037Y129045D02*
X322330Y106338D01*
G01X345037Y198346D02*
Y129045D01*
G01X321003Y177438D02*
X312637Y169072D01*
G01X321730Y177438D02*
X321003D01*
G01X328148Y183856D02*
X321730Y177438D01*
G01X328148Y197291D02*
Y183856D01*
G01X322239Y175061D02*
X316592Y169414D01*
G01X322953Y175061D02*
X322239D01*
G01X330642Y182750D02*
X322953Y175061D01*
G01X330642Y197285D02*
Y182750D01*
G01X330648Y197291D02*
X330642Y197285D01*
G01X308448Y197341D02*
Y191006D01*
G01X303542Y197247D02*
Y193100D01*
G01X303448Y197341D02*
X303542Y197247D01*
G01X305948Y197341D02*
Y191856D01*
G01X317782Y181599D02*
X305342Y169159D01*
G01X319791Y181599D02*
X317782D01*
G01X323092Y184900D02*
X319791Y181599D01*
G01X323092Y196635D02*
Y184900D01*
G01X323148Y196691D02*
X323092Y196635D01*
G01X319123Y179404D02*
X310442Y170723D01*
G01X320596Y179404D02*
X319123D01*
G01X325867Y184675D02*
X320596Y179404D01*
G01X325867Y196432D02*
Y184675D01*
G01X325648Y196651D02*
X325867Y196432D01*
G01X310948Y189193D02*
X294742Y172987D01*
G01X310948Y197341D02*
Y189193D01*
G01X354188Y191809D02*
X356092Y189905D01*
G01X354188Y198734D02*
Y191809D01*
G01X348790Y397365D02*
Y482570D01*
G01X309825Y400464D02*
Y411195D01*
G01X304525Y400162D02*
Y409167D01*
G01X346790Y397118D02*
Y482150D01*
G01X342746Y475446D02*
Y400788D01*
G01X307025Y400312D02*
Y410367D01*
G01X344790Y476502D02*
Y396937D01*
G01X340746Y401003D02*
Y474546D01*
G01X338746Y473546D02*
Y400454D01*
G01X312325Y400312D02*
Y412368D01*
G01X307296Y442516D02*
Y477096D01*
G01X330904Y418908D02*
X307296Y442516D01*
G01X330904Y405921D02*
Y418908D01*
G01X350790Y407015D02*
Y482948D01*
G01X295173Y407266D02*
Y410156D01*
G01X297944Y441260D02*
Y465226D01*
G01X323104Y416100D02*
X297944Y441260D01*
G01X323104Y403924D02*
Y416100D01*
G01X352790Y407700D02*
Y485612D01*
G01X328608Y417668D02*
Y405717D01*
G01X304764Y441512D02*
X328608Y417668D01*
G01X304764Y469622D02*
Y441512D01*
G01X325604Y417136D02*
Y403862D01*
G01X300384Y442356D02*
X325604Y417136D01*
G01X300384Y445511D02*
Y442356D01*
G01X301302Y446429D02*
X300384Y445511D01*
G01X302165Y446429D02*
X301302D01*
G01X302775Y447039D02*
X302165Y446429D01*
G01X302775Y449019D02*
Y447039D01*
G01X302165Y449629D02*
X302775Y449019D01*
G01X301327Y449629D02*
X302165D01*
G01X300717Y450239D02*
X301327Y449629D01*
G01X300717Y452219D02*
Y450239D01*
G01X301327Y452829D02*
X300717Y452219D01*
G01X302165Y452829D02*
X301327D01*
G01X302775Y453439D02*
X302165Y452829D01*
G01X302775Y455419D02*
Y453439D01*
G01X302165Y456029D02*
X302775Y455419D01*
G01X300798Y456029D02*
X302165D01*
G01X300188Y456639D02*
X300798Y456029D01*
G01X300188Y458619D02*
Y456639D01*
G01X300798Y459229D02*
X300188Y458619D01*
G01X302006Y459229D02*
X300798D01*
G01X302616Y459839D02*
X302006Y459229D01*
G01X302616Y461819D02*
Y459839D01*
G01X302006Y462429D02*
X302616Y461819D01*
G01X300851Y462429D02*
X302006D01*
G01X300294Y462986D02*
X300851Y462429D01*
G01X300294Y464966D02*
Y462986D01*
G01X306292Y520300D02*
Y535800D01*
G01X305774Y519782D02*
X306292Y520300D01*
G01X305774Y517357D02*
Y519782D01*
G01X306240Y516891D02*
X305774Y517357D01*
G01X306240Y512173D02*
Y516891D01*
G01X305724Y511657D02*
X306240Y512173D01*
G01X305724Y507907D02*
Y511657D01*
G01X304924Y507107D02*
X305724Y507907D01*
G01X303692Y507107D02*
X304924D01*
G01X302892Y506307D02*
X303692Y507107D01*
G01X302892Y504707D02*
Y506307D01*
G01X303692Y503907D02*
X302892Y504707D01*
G01X304924Y503907D02*
X303692D01*
G01X305724Y503107D02*
X304924Y503907D01*
G01X305724Y500868D02*
Y503107D01*
G01X307192Y499400D02*
X305724Y500868D01*
G01X307192Y493120D02*
Y499400D01*
G01X305724Y491652D02*
X307192Y493120D01*
G01X305724Y490580D02*
Y491652D01*
G01X306334Y489970D02*
X305724Y490580D01*
G01X309434Y489970D02*
X306334D01*
G01X310044Y489360D02*
X309434Y489970D01*
G01X310044Y487380D02*
Y489360D01*
G01X309434Y486770D02*
X310044Y487380D01*
G01X306334Y486770D02*
X309434D01*
G01X305724Y486160D02*
X306334Y486770D01*
G01X305724Y482737D02*
Y486160D01*
G01X304843Y481856D02*
X305724Y482737D01*
G01X302367Y481856D02*
X304843D01*
G01X301409Y480898D02*
X302367Y481856D01*
G01X301409Y478758D02*
Y480898D01*
G01X302317Y477850D02*
X301409Y478758D01*
G01X306542Y477850D02*
X302317D01*
G01X307296Y477096D02*
X306542Y477850D01*
G01X329486Y519206D02*
Y530388D01*
G01X329792Y518900D02*
X329486Y519206D01*
G01X329792Y517100D02*
Y518900D01*
G01X329092Y516400D02*
X329792Y517100D01*
G01X329092Y514700D02*
Y516400D01*
G01X329692Y514100D02*
X329092Y514700D01*
G01X329692Y511500D02*
Y514100D01*
G01X329092Y510900D02*
X329692Y511500D01*
G01X329092Y509576D02*
Y510900D01*
G01X331892Y506776D02*
X329092Y509576D01*
G01X331892Y499468D02*
Y506776D01*
G01X348790Y482570D02*
X331892Y499468D01*
G01X339340Y516952D02*
Y527848D01*
G01X339792Y516500D02*
X339340Y516952D01*
G01X339792Y514400D02*
Y516500D01*
G01X339192Y513800D02*
X339792Y514400D01*
G01X339192Y512000D02*
Y513800D01*
G01X339692Y511500D02*
X339192Y512000D01*
G01X339692Y509533D02*
Y511500D01*
G01X342392Y506833D02*
X339692Y509533D01*
G01X342392Y498840D02*
Y506833D01*
G01X354790Y486442D02*
X342392Y498840D01*
G01X352905Y520013D02*
Y539339D01*
G01X352692Y519800D02*
X352905Y520013D01*
G01X352692Y516600D02*
Y519800D01*
G01X353119Y516173D02*
X352692Y516600D01*
G01X353119Y514327D02*
Y516173D01*
G01X352171Y513379D02*
X353119Y514327D01*
G01X352171Y512121D02*
Y513379D01*
G01X353192Y511100D02*
X352171Y512121D01*
G01X353192Y504399D02*
Y511100D01*
G01X362790Y494801D02*
X353192Y504399D01*
G01X342792Y519400D02*
Y530400D01*
G01X342951Y519241D02*
X342792Y519400D01*
G01X342951Y516859D02*
Y519241D01*
G01X342652Y516560D02*
X342951Y516859D01*
G01X342652Y514140D02*
Y516560D01*
G01X342951Y513841D02*
X342652Y514140D01*
G01X342951Y511559D02*
Y513841D01*
G01X342695Y511303D02*
X342951Y511559D01*
G01X342695Y509359D02*
Y511303D01*
G01X344392Y507662D02*
X342695Y509359D01*
G01X344392Y499670D02*
Y507662D01*
G01X356790Y487272D02*
X344392Y499670D01*
G01X332792Y519500D02*
Y530400D01*
G01X332492Y519200D02*
X332792Y519500D01*
G01X332492Y517000D02*
Y519200D01*
G01X332992Y516500D02*
X332492Y517000D01*
G01X332992Y514400D02*
Y516500D01*
G01X332592Y514000D02*
X332992Y514400D01*
G01X332592Y511600D02*
Y514000D01*
G01X333892Y510300D02*
X332592Y511600D01*
G01X333892Y499846D02*
Y510300D01*
G01X350790Y482948D02*
X333892Y499846D01*
G01X326049Y521049D02*
Y532957D01*
G01X325892Y520892D02*
X326049Y521049D01*
G01X325892Y516900D02*
Y520892D01*
G01X326392Y516400D02*
X325892Y516900D01*
G01X326392Y514400D02*
Y516400D01*
G01X325792Y513800D02*
X326392Y514400D01*
G01X325792Y511500D02*
Y513800D01*
G01X326392Y510900D02*
X325792Y511500D01*
G01X326392Y509446D02*
Y510900D01*
G01X329692Y506146D02*
X326392Y509446D01*
G01X329692Y499248D02*
Y506146D01*
G01X331367Y497573D02*
X329692Y499248D01*
G01X331367Y496711D02*
Y497573D01*
G01X330249Y495593D02*
X331367Y496711D01*
G01X330249Y494786D02*
Y495593D01*
G01X331233Y493802D02*
X330249Y494786D01*
G01X332150Y493802D02*
X331233D01*
G01X333213Y494865D02*
X332150Y493802D01*
G01X334075Y494865D02*
X333213D01*
G01X335059Y493881D02*
X334075Y494865D01*
G01X335059Y493019D02*
Y493881D01*
G01X333985Y491945D02*
X335059Y493019D01*
G01X333985Y491083D02*
Y491945D01*
G01X334969Y490099D02*
X333985Y491083D01*
G01X335831Y490099D02*
X334969D01*
G01X336905Y491173D02*
X335831Y490099D01*
G01X337767Y491173D02*
X336905D01*
G01X338751Y490189D02*
X337767Y491173D01*
G01X338751Y489327D02*
Y490189D01*
G01X337963Y488539D02*
X338751Y489327D01*
G01X337963Y487611D02*
Y488539D01*
G01X338947Y486627D02*
X337963Y487611D01*
G01X339743Y486627D02*
X338947D01*
G01X340597Y487481D02*
X339743Y486627D01*
G01X341459Y487481D02*
X340597D01*
G01X346790Y482150D02*
X341459Y487481D01*
G01X349556Y519236D02*
Y533036D01*
G01X349792Y519000D02*
X349556Y519236D01*
G01X349792Y516600D02*
Y519000D01*
G01X349192Y516000D02*
X349792Y516600D01*
G01X349192Y514300D02*
Y516000D01*
G01X349792Y513700D02*
X349192Y514300D01*
G01X349792Y511700D02*
Y513700D01*
G01X348392Y510300D02*
X349792Y511700D01*
G01X348392Y506370D02*
Y510300D01*
G01X360790Y493972D02*
X348392Y506370D01*
G01X319892Y498300D02*
X342746Y475446D01*
G01X319892Y511100D02*
Y498300D01*
G01X319192Y511800D02*
X319892Y511100D01*
G01X319192Y513800D02*
Y511800D01*
G01X319592Y514200D02*
X319192Y513800D01*
G01X319592Y516500D02*
Y514200D01*
G01X319092Y517000D02*
X319592Y516500D01*
G01X319092Y527500D02*
Y517000D01*
G01X296124Y517357D02*
Y529842D01*
G01X295724Y516957D02*
X296124Y517357D01*
G01X295724Y512057D02*
Y516957D01*
G01X296168Y511613D02*
X295724Y512057D01*
G01X296168Y501376D02*
Y511613D01*
G01X295992Y501200D02*
X296168Y501376D01*
G01X295992Y494400D02*
Y501200D01*
G01X296524Y493868D02*
X295992Y494400D01*
G01X296524Y487432D02*
Y493868D01*
G01X336292Y516900D02*
Y527700D01*
G01X335892Y516500D02*
X336292Y516900D01*
G01X335892Y514200D02*
Y516500D01*
G01X336366Y513726D02*
X335892Y514200D01*
G01X336366Y511774D02*
Y513726D01*
G01X335892Y511300D02*
X336366Y511774D01*
G01X335892Y507310D02*
Y511300D01*
G01X336692Y506510D02*
X335892Y507310D01*
G01X338930Y506510D02*
X336692D01*
G01X339730Y505710D02*
X338930Y506510D01*
G01X339730Y504110D02*
Y505710D01*
G01X338930Y503310D02*
X339730Y504110D01*
G01X336692Y503310D02*
X338930D01*
G01X336048Y502666D02*
X336692Y503310D01*
G01X336048Y500608D02*
Y502666D01*
G01X336783Y499873D02*
X336048Y500608D01*
G01X338529Y499873D02*
X336783D01*
G01X344101Y494301D02*
X338529Y499873D01*
G01X344101Y492491D02*
Y494301D01*
G01X345459Y491133D02*
X344101Y492491D01*
G01X347269Y491133D02*
X345459D01*
G01X348627Y489775D02*
X347269Y491133D01*
G01X348627Y487965D02*
Y489775D01*
G01X349985Y486607D02*
X348627Y487965D01*
G01X351795Y486607D02*
X349985D01*
G01X352790Y485612D02*
X351795Y486607D01*
G01X322492Y498800D02*
X344790Y476502D01*
G01X322492Y511200D02*
Y498800D01*
G01X322892Y511600D02*
X322492Y511200D01*
G01X322892Y513900D02*
Y511600D01*
G01X322392Y514400D02*
X322892Y513900D01*
G01X322392Y516300D02*
Y514400D01*
G01X322992Y516900D02*
X322392Y516300D01*
G01X322992Y519300D02*
Y516900D01*
G01X322792Y519500D02*
X322992Y519300D01*
G01X322792Y530700D02*
Y519500D01*
G01X298634Y475752D02*
X304764Y469622D01*
G01X298634Y482595D02*
Y475752D01*
G01X303192Y487153D02*
X298634Y482595D01*
G01X303192Y493500D02*
Y487153D01*
G01X302692Y494000D02*
X303192Y493500D01*
G01X302692Y500100D02*
Y494000D01*
G01X300992Y501800D02*
X302692Y500100D01*
G01X300992Y507500D02*
Y501800D01*
G01X302924Y509432D02*
X300992Y507500D01*
G01X302924Y511157D02*
Y509432D01*
G01X302283Y511798D02*
X302924Y511157D01*
G01X302283Y516832D02*
Y511798D01*
G01X303274Y517823D02*
X302283Y516832D01*
G01X303274Y519200D02*
Y517823D01*
G01X302692Y519782D02*
X303274Y519200D01*
G01X302692Y528000D02*
Y519782D01*
G01X316192Y516900D02*
Y527700D01*
G01X315792Y516500D02*
X316192Y516900D01*
G01X315792Y514300D02*
Y516500D01*
G01X316292Y513800D02*
X315792Y514300D01*
G01X316292Y511800D02*
Y513800D01*
G01X315792Y511300D02*
X316292Y511800D01*
G01X315792Y499500D02*
Y511300D01*
G01X340746Y474546D02*
X315792Y499500D01*
G01X313492Y498800D02*
X338746Y473546D01*
G01X313492Y510900D02*
Y498800D01*
G01X312392Y512000D02*
X313492Y510900D01*
G01X312392Y513600D02*
Y512000D01*
G01X312992Y514200D02*
X312392Y513600D01*
G01X312992Y516600D02*
Y514200D01*
G01X311842Y517750D02*
X312992Y516600D01*
G01X311842Y527050D02*
Y517750D01*
G01X300957Y465629D02*
X300294Y464966D01*
G01X302165Y465629D02*
X300957D01*
G01X302775Y466239D02*
X302165Y465629D01*
G01X302775Y468219D02*
Y466239D01*
G01X302165Y468829D02*
X302775Y468219D01*
G01X297863Y468829D02*
X302165D01*
G01X294192Y472500D02*
X297863Y468829D01*
G01X294192Y481760D02*
Y472500D01*
G01X299024Y486592D02*
X294192Y481760D01*
G01X299024Y493732D02*
Y486592D01*
G01X300292Y495000D02*
X299024Y493732D01*
G01X300292Y498100D02*
Y495000D01*
G01X299024Y499368D02*
X300292Y498100D01*
G01X299024Y511257D02*
Y499368D01*
G01X299924Y512157D02*
X299024Y511257D01*
G01X299924Y516557D02*
Y512157D01*
G01X299124Y517357D02*
X299924Y516557D01*
G01X299124Y529842D02*
Y517357D01*
G01X346118Y520698D02*
Y530374D01*
G01X345577Y520157D02*
X346118Y520698D01*
G01X345577Y517339D02*
Y520157D01*
G01X346496Y516420D02*
X345577Y517339D01*
G01X346496Y514504D02*
Y516420D01*
G01X345400Y513408D02*
X346496Y514504D01*
G01X345400Y511772D02*
Y513408D01*
G01X346392Y510780D02*
X345400Y511772D01*
G01X346392Y505540D02*
Y510780D01*
G01X349159Y502773D02*
X346392Y505540D01*
G01X349159Y501281D02*
Y502773D01*
G01X348216Y500338D02*
X349159Y501281D01*
G01X348216Y499178D02*
Y500338D01*
G01X349347Y498047D02*
X348216Y499178D01*
G01X350451Y498047D02*
X349347D01*
G01X351602Y499198D02*
X350451Y498047D01*
G01X352734Y499198D02*
X351602D01*
G01X353865Y498067D02*
X352734Y499198D01*
G01X353865Y496935D02*
Y498067D01*
G01X352448Y495518D02*
X353865Y496935D01*
G01X352448Y494486D02*
Y495518D01*
G01X353579Y493355D02*
X352448Y494486D01*
G01X354811Y493355D02*
X353579D01*
G01X356063Y494607D02*
X354811Y493355D01*
G01X304924Y588118D02*
X304328Y588714D01*
G01X304924Y574868D02*
Y588118D01*
G01X306266Y573526D02*
X304924Y574868D01*
G01X306266Y557873D02*
Y573526D01*
G01X305774Y557381D02*
X306266Y557873D01*
G01X305774Y555157D02*
Y557381D01*
G01X306324Y554607D02*
X305774Y555157D01*
G01X306324Y550057D02*
Y554607D01*
G01X305724Y549457D02*
X306324Y550057D01*
G01X305724Y547068D02*
Y549457D01*
G01X306292Y546500D02*
X305724Y547068D01*
G01X306292Y538368D02*
Y546500D01*
G01X305724Y537800D02*
X306292Y538368D01*
G01X305724Y536368D02*
Y537800D01*
G01X306292Y535800D02*
X305724Y536368D01*
G01X324407Y555857D02*
Y566814D01*
G01Y555115D02*
Y555857D01*
G01X325492Y554030D02*
X324407Y555115D01*
G01X325492Y549500D02*
Y554030D01*
G01X326092Y548900D02*
X325492Y549500D01*
G01X326092Y546800D02*
Y548900D01*
G01X329383Y543509D02*
X326092Y546800D01*
G01X329383Y530491D02*
Y543509D01*
G01X329486Y530388D02*
X329383Y530491D01*
G01X341757Y567439D02*
X341140Y566822D01*
G01X341757Y571385D02*
Y567439D01*
G01X341063Y572079D02*
X341757Y571385D01*
G01X339020Y572079D02*
X341063D01*
G01X338368Y571427D02*
X339020Y572079D01*
G01X338368Y569943D02*
Y571427D01*
G01X336075Y567650D02*
X338368Y569943D01*
G01X336075Y565505D02*
Y567650D01*
G01X336676Y564904D02*
X336075Y565505D01*
G01X337623Y564904D02*
X336676D01*
G01X338149Y564378D02*
X337623Y564904D01*
G01X338149Y562989D02*
Y564378D01*
G01X337539Y562379D02*
X338149Y562989D01*
G01X336207Y562379D02*
X337539D01*
G01X335619Y561791D02*
X336207Y562379D01*
G01X335619Y560801D02*
Y561791D01*
G01X336251Y560169D02*
X335619Y560801D01*
G01X337539Y560169D02*
X336251D01*
G01X338149Y559559D02*
X337539Y560169D01*
G01X338149Y558058D02*
Y559559D01*
G01X340350Y555857D02*
X338149Y558058D01*
G01X341140Y555857D02*
X340350D01*
G01X341140Y553648D02*
Y555857D01*
G01X339418Y551926D02*
X341140Y553648D01*
G01X339418Y532826D02*
Y551926D01*
G01X339339Y532747D02*
X339418Y532826D01*
G01X339339Y530653D02*
Y532747D01*
G01X339507Y530485D02*
X339339Y530653D01*
G01X339507Y528015D02*
Y530485D01*
G01X339340Y527848D02*
X339507Y528015D01*
G01X351179Y555857D02*
Y566822D01*
G01Y553723D02*
Y555857D01*
G01X350575Y553119D02*
X351179Y553723D01*
G01X350575Y550383D02*
Y553119D01*
G01X349454Y549262D02*
X350575Y550383D01*
G01X349454Y546338D02*
Y549262D01*
G01X351692Y544100D02*
X349454Y546338D01*
G01X351692Y540552D02*
Y544100D01*
G01X352905Y539339D02*
X351692Y540552D01*
G01X344486Y565386D02*
Y566822D01*
G01X343876Y564776D02*
X344486Y565386D01*
G01X340571Y564776D02*
X343876D01*
G01X339982Y564187D02*
X340571Y564776D01*
G01X339982Y563197D02*
Y564187D01*
G01X340613Y562566D02*
X339982Y563197D01*
G01X345287Y562566D02*
X340613D01*
G01X345939Y561914D02*
X345287Y562566D01*
G01X345939Y560924D02*
Y561914D01*
G01X345371Y560356D02*
X345939Y560924D01*
G01X340507Y560356D02*
X345371D01*
G01X339833Y559682D02*
X340507Y560356D01*
G01X339833Y558692D02*
Y559682D01*
G01X340379Y558146D02*
X339833Y558692D01*
G01X343876Y558146D02*
X340379D01*
G01X344486Y557536D02*
X343876Y558146D01*
G01X344486Y555857D02*
Y557536D01*
G01Y553575D02*
Y555857D01*
G01X342865Y551954D02*
X344486Y553575D01*
G01X342865Y535873D02*
Y551954D01*
G01X342525Y535533D02*
X342865Y535873D01*
G01X342525Y533667D02*
Y535533D01*
G01X343092Y533100D02*
X342525Y533667D01*
G01X343092Y530700D02*
Y533100D01*
G01X342792Y530400D02*
X343092Y530700D01*
G01X327754Y572138D02*
Y574757D01*
G01X329471Y570421D02*
X327754Y572138D01*
G01X329471Y554179D02*
Y570421D01*
G01X327754Y552462D02*
X329471Y554179D01*
G01X327754Y547914D02*
Y552462D01*
G01X332836Y542832D02*
X327754Y547914D01*
G01X332836Y536044D02*
Y542832D01*
G01X332484Y535692D02*
X332836Y536044D01*
G01X332484Y530708D02*
Y535692D01*
G01X332792Y530400D02*
X332484Y530708D01*
G01X321061Y555857D02*
Y566814D01*
G01X322993Y553925D02*
X321061Y555857D01*
G01X322993Y549501D02*
Y553925D01*
G01X322786Y549294D02*
X322993Y549501D01*
G01X322786Y546706D02*
Y549294D01*
G01X326092Y543400D02*
X322786Y546706D01*
G01X326092Y533000D02*
Y543400D01*
G01X326049Y532957D02*
X326092Y533000D01*
G01X347833Y571763D02*
Y574757D01*
G01X349556Y570040D02*
X347833Y571763D01*
G01X349556Y554664D02*
Y570040D01*
G01X348692Y553800D02*
X349556Y554664D01*
G01X348692Y551451D02*
Y553800D01*
G01X347833Y550592D02*
X348692Y551451D01*
G01X347833Y547922D02*
Y550592D01*
G01Y545059D02*
Y547922D01*
G01X349438Y543454D02*
X347833Y545059D01*
G01X349438Y535946D02*
Y543454D01*
G01X349292Y535800D02*
X349438Y535946D01*
G01X349292Y533300D02*
Y535800D01*
G01X349556Y533036D02*
X349292Y533300D01*
G01X319437Y527845D02*
X319092Y527500D01*
G01X319437Y530555D02*
Y527845D01*
G01X319349Y530643D02*
X319437Y530555D01*
G01X319349Y543443D02*
Y530643D01*
G01X316102Y546690D02*
X319349Y543443D01*
G01X316102Y549510D02*
Y546690D01*
G01X316292Y549700D02*
X316102Y549510D01*
G01X316292Y551400D02*
Y549700D01*
G01X315592Y552100D02*
X316292Y551400D01*
G01X315592Y554633D02*
Y552100D01*
G01X314368Y555857D02*
X315592Y554633D01*
G01X296524Y586357D02*
X293792Y589089D01*
G01X296524Y584932D02*
Y586357D01*
G01X295992Y584400D02*
X296524Y584932D01*
G01X295992Y575700D02*
Y584400D01*
G01X296421Y575271D02*
X295992Y575700D01*
G01X296421Y574139D02*
Y575271D01*
G01X295251Y572969D02*
X296421Y574139D01*
G01X295251Y568470D02*
Y572969D01*
G01X296324Y567397D02*
X295251Y568470D01*
G01X296324Y565932D02*
Y567397D01*
G01X295992Y565600D02*
X296324Y565932D01*
G01X295992Y557532D02*
Y565600D01*
G01X296324Y557200D02*
X295992Y557532D01*
G01X296324Y555357D02*
Y557200D01*
G01X295724Y554757D02*
X296324Y555357D01*
G01X295724Y549857D02*
Y554757D01*
G01X296167Y549414D02*
X295724Y549857D01*
G01X296167Y536275D02*
Y549414D01*
G01X295724Y535832D02*
X296167Y536275D01*
G01X295724Y530242D02*
Y535832D01*
G01X296124Y529842D02*
X295724Y530242D01*
G01X336323Y573287D02*
X337793Y574757D01*
G01X336323Y570438D02*
Y573287D01*
G01X334744Y568859D02*
X336323Y570438D01*
G01X333908Y568859D02*
X334744D01*
G01X332786Y567737D02*
X333908Y568859D01*
G01X332786Y555106D02*
Y567737D01*
G01X333748Y554144D02*
X332786Y555106D01*
G01X334844Y554144D02*
X333748D01*
G01X336054Y552934D02*
X334844Y554144D01*
G01X336054Y552238D02*
Y552934D01*
G01X337793Y550499D02*
X336054Y552238D01*
G01X337793Y547914D02*
Y550499D01*
G01X336156Y546277D02*
X337793Y547914D01*
G01X336156Y530564D02*
Y546277D01*
G01X336068Y530476D02*
X336156Y530564D01*
G01X336068Y527924D02*
Y530476D01*
G01X336292Y527700D02*
X336068Y527924D01*
G01X354526Y566821D02*
X354525Y566822D01*
G01X354526Y555857D02*
Y566821D01*
G01X354155Y555486D02*
X354526Y555857D01*
G01X354155Y553063D02*
Y555486D01*
G01X352892Y551800D02*
X354155Y553063D01*
G01X352892Y546100D02*
Y551800D01*
G01X356154Y542838D02*
X352892Y546100D01*
G01X323227Y531135D02*
X322792Y530700D01*
G01X323227Y535555D02*
Y531135D01*
G01X322787Y535995D02*
X323227Y535555D01*
G01X322787Y538105D02*
Y535995D01*
G01X322092Y538800D02*
X322787Y538105D01*
G01X322092Y543458D02*
Y538800D01*
G01X319349Y546201D02*
X322092Y543458D01*
G01X319349Y549543D02*
Y546201D01*
G01X318992Y549900D02*
X319349Y549543D01*
G01X318992Y552602D02*
Y549900D01*
G01X319451Y553061D02*
X318992Y552602D01*
G01X319451Y559557D02*
Y553061D01*
G01X314368Y564640D02*
X319451Y559557D01*
G01X314368Y566814D02*
Y564640D01*
G01X303274Y528582D02*
X302692Y528000D01*
G01X303274Y529416D02*
Y528582D01*
G01X302324Y530366D02*
X303274Y529416D01*
G01X302324Y535932D02*
Y530366D01*
G01X302924Y536532D02*
X302324Y535932D01*
G01X302924Y537900D02*
Y536532D01*
G01X302692Y538132D02*
X302924Y537900D01*
G01X302692Y546300D02*
Y538132D01*
G01X302924Y546532D02*
X302692Y546300D01*
G01X302924Y548957D02*
Y546532D01*
G01X302424Y549457D02*
X302924Y548957D01*
G01X302424Y554857D02*
Y549457D01*
G01X303224Y555657D02*
X302424Y554857D01*
G01X303224Y557100D02*
Y555657D01*
G01X302658Y557666D02*
X303224Y557100D01*
G01X302658Y565666D02*
Y557666D01*
G01X303224Y566232D02*
X302658Y565666D01*
G01X303224Y567297D02*
Y566232D01*
G01X302124Y568397D02*
X303224Y567297D01*
G01X302124Y573142D02*
Y568397D01*
G01X303024Y574042D02*
X302124Y573142D01*
G01X303024Y575700D02*
Y574042D01*
G01X302692Y576032D02*
X303024Y575700D01*
G01X302692Y584500D02*
Y576032D01*
G01X303024Y584832D02*
X302692Y584500D01*
G01X303024Y586507D02*
Y584832D01*
G01X300492Y589039D02*
X303024Y586507D01*
G01X311021Y569571D02*
Y574757D01*
G01X312752Y567840D02*
X311021Y569571D01*
G01X312752Y551860D02*
Y567840D01*
G01X312649Y551757D02*
X312752Y551860D01*
G01X312649Y546843D02*
Y551757D01*
G01X316087Y543405D02*
X312649Y546843D01*
G01X316087Y535895D02*
Y543405D01*
G01X315999Y535807D02*
X316087Y535895D01*
G01X315999Y527893D02*
Y535807D01*
G01X316192Y527700D02*
X315999Y527893D01*
G01X312739Y527947D02*
X311842Y527050D01*
G01X312739Y535353D02*
Y527947D01*
G01X312634Y535458D02*
X312739Y535353D01*
G01X312634Y543759D02*
Y535458D01*
G01X311021Y545372D02*
X312634Y543759D01*
G01X311021Y547914D02*
Y545372D01*
G01X299824Y530542D02*
X299124Y529842D01*
G01X299824Y535468D02*
Y530542D01*
G01X299024Y536268D02*
X299824Y535468D01*
G01X299024Y537832D02*
Y536268D01*
G01X299292Y538100D02*
X299024Y537832D01*
G01X299292Y546200D02*
Y538100D01*
G01X299024Y546468D02*
X299292Y546200D01*
G01X299024Y549057D02*
Y546468D01*
G01X299924Y549957D02*
X299024Y549057D01*
G01X299924Y554357D02*
Y549957D01*
G01X298824Y555457D02*
X299924Y554357D01*
G01X298824Y557031D02*
Y555457D01*
G01X299292Y557499D02*
X298824Y557031D01*
G01X299292Y566000D02*
Y557499D01*
G01X299124Y566168D02*
X299292Y566000D01*
G01X299124Y567597D02*
Y566168D01*
G01X299690Y568163D02*
X299124Y567597D01*
G01X299690Y573401D02*
Y568163D01*
G01X299024Y574067D02*
X299690Y573401D01*
G01X299024Y575632D02*
Y574067D01*
G01X299292Y575900D02*
X299024Y575632D01*
G01X299292Y584500D02*
Y575900D01*
G01X299024Y584768D02*
X299292Y584500D01*
G01X299024Y587368D02*
Y584768D01*
G01X298981Y587368D02*
X299024D01*
G01X297635Y588714D02*
X298981Y587368D01*
G01X354526Y570022D02*
Y574757D01*
G01X356205Y568343D02*
X354526Y570022D01*
G01Y550592D02*
X355771Y551837D01*
G01X354526Y547923D02*
Y550592D01*
G01X354525Y547922D02*
X354526Y547923D01*
G01X354525Y546844D02*
Y547922D01*
G01X358992Y542377D02*
X354525Y546844D01*
G01X344486Y570370D02*
Y574757D01*
G01X346103Y568753D02*
X344486Y570370D01*
G01X346103Y565319D02*
Y568753D01*
G01X347649Y563773D02*
X346103Y565319D01*
G01X347649Y558766D02*
Y563773D01*
G01X346103Y557220D02*
X347649Y558766D01*
G01X346103Y551691D02*
Y557220D01*
G01X344486Y550074D02*
X346103Y551691D01*
G01X344486Y547922D02*
Y550074D01*
G01Y545506D02*
Y547922D01*
G01X346192Y543800D02*
X344486Y545506D01*
G01X346192Y533200D02*
Y543800D01*
G01X345892Y532900D02*
X346192Y533200D01*
G01X345892Y530600D02*
Y532900D01*
G01X346118Y530374D02*
X345892Y530600D01*
G01X293792Y593260D02*
X294289Y593757D01*
G01X293792Y589089D02*
Y593260D01*
G01X300492Y593267D02*
Y589039D01*
G01X300982Y593757D02*
X300492Y593267D01*
G01X398029Y30236D02*
Y28007D01*
G01X399752Y31959D02*
X398029Y30236D01*
G01X399752Y47828D02*
Y31959D01*
G01X404722Y28023D02*
X404723Y28022D01*
G01X404722Y32686D02*
Y28023D01*
G01X403060Y34348D02*
X404722Y32686D01*
G01X410051Y29989D02*
X408069Y28007D01*
G01X410051Y34724D02*
Y29989D01*
G01X414762Y32227D02*
Y28021D01*
G01X415609Y33074D02*
X414762Y32227D01*
G01X398029Y49551D02*
X399752Y47828D01*
G01X398029Y52164D02*
Y49551D01*
G01X398819Y52954D02*
X398029Y52164D01*
G01X398819Y54052D02*
Y52954D01*
G01X398029Y54842D02*
X398819Y54052D01*
G01X398029Y57766D02*
Y54842D01*
G01X396968Y58827D02*
X398029Y57766D01*
G01X392592Y58827D02*
X396968D01*
G01X391792Y59627D02*
X392592Y58827D01*
G01X391792Y61227D02*
Y59627D01*
G01X392592Y62027D02*
X391792Y61227D01*
G01X395420Y62027D02*
X392592D01*
G01X396092Y62699D02*
X395420Y62027D01*
G01X396092Y66628D02*
Y62699D01*
G01X397487Y68023D02*
X396092Y66628D01*
G01X397487Y70932D02*
Y68023D01*
G01X395384Y73035D02*
X397487Y70932D01*
G01X395384Y76202D02*
Y73035D01*
G01X396938Y77756D02*
X395384Y76202D01*
G01X396938Y83144D02*
Y77756D01*
G01X395947Y84135D02*
X396938Y83144D01*
G01X395947Y86055D02*
Y84135D01*
G01X396623Y86731D02*
X395947Y86055D01*
G01X396623Y88168D02*
Y86731D01*
G01X395492Y89299D02*
X396623Y88168D01*
G01X395492Y96897D02*
Y89299D01*
G01X416398Y64594D02*
X416742Y64250D01*
G01X416398Y83494D02*
Y64594D01*
G01X416181Y83711D02*
X416398Y83494D01*
G01X416181Y85889D02*
Y83711D01*
G01X416666Y86374D02*
X416181Y85889D01*
G01X415963Y89077D02*
X416666Y88374D01*
G01X415963Y91087D02*
Y89077D01*
G01X416788Y91912D02*
X415963Y91087D01*
G01X403060Y52582D02*
Y34348D01*
G01X404723Y54245D02*
X403060Y52582D01*
G01X404723Y54857D02*
Y54245D01*
G01X404135Y54857D02*
X404723D01*
G01X400942Y58050D02*
X404135Y54857D01*
G01X399765Y62966D02*
X400942Y58050D01*
G01X399765Y66971D02*
Y62966D01*
G01X399760Y66994D02*
X399765Y66971D01*
G01X399760Y74445D02*
Y66994D01*
G01X399392Y74813D02*
X399760Y74445D01*
G01X399392Y82452D02*
Y74813D01*
G01X400383Y83443D02*
X399392Y82452D01*
G01X400383Y85339D02*
Y83443D01*
G01X399392Y86330D02*
X400383Y85339D01*
G01X399392Y88033D02*
Y86330D01*
G01X400699Y89340D02*
X399392Y88033D01*
G01X400699Y90674D02*
Y89340D01*
G01X397592Y93781D02*
X400699Y90674D01*
G01X397592Y98186D02*
Y93781D01*
G01X356199Y37630D02*
Y40392D01*
G01X356182Y94392D02*
X364627Y102837D01*
G01X356182Y91332D02*
Y94392D01*
G01X355824Y90974D02*
X356182Y91332D01*
G01X355824Y88874D02*
Y90974D01*
G01X356167Y88531D02*
X355824Y88874D01*
G01X356167Y85917D02*
Y88531D01*
G01X355924Y85674D02*
X356167Y85917D01*
G01X355924Y83530D02*
Y85674D01*
G01X356524Y82930D02*
X355924Y83530D01*
G01X356524Y73455D02*
Y82930D01*
G01X355628Y72559D02*
X356524Y73455D01*
G01X355628Y67155D02*
Y72559D01*
G01X356153Y66630D02*
X355628Y67155D01*
G01X356153Y64641D02*
Y66630D01*
G01X356763Y64031D02*
X356153Y64641D01*
G01X358756Y64031D02*
X356763D01*
G01X359366Y63421D02*
X358756Y64031D01*
G01X359366Y61521D02*
Y63421D01*
G01X358756Y60911D02*
X359366Y61521D01*
G01X356474Y60911D02*
X358756D01*
G01X355974Y60411D02*
X356474Y60911D01*
G01X355974Y58938D02*
Y60411D01*
G01X356833Y58079D02*
X355974Y58938D01*
G01X356833Y54541D02*
Y58079D01*
G01X409803Y59817D02*
X414763Y54857D01*
G01X409803Y67296D02*
Y59817D01*
G01X410492Y67985D02*
X409803Y67296D01*
G01X410492Y71709D02*
Y67985D01*
G01X409793Y72408D02*
X410492Y71709D01*
G01X409793Y82361D02*
Y72408D01*
G01X409239Y82915D02*
X409793Y82361D01*
G01X409239Y85747D02*
Y82915D01*
G01X409920Y86428D02*
X409239Y85747D01*
G01X409920Y88420D02*
Y86428D01*
G01X409544Y88796D02*
X409920Y88420D01*
G01X409544Y91352D02*
Y88796D01*
G01X409953Y91761D02*
X409544Y91352D01*
G01X409953Y95839D02*
Y91761D01*
G01X396492Y37765D02*
X394684Y35957D01*
G01X396492Y45600D02*
Y37765D01*
G01X395892Y46200D02*
X396492Y45600D01*
G01X395892Y48382D02*
Y46200D01*
G01X394682Y49592D02*
X395892Y48382D01*
G01X392692Y51582D02*
X394682Y49592D01*
G01X392692Y55800D02*
Y51582D01*
G01X389692Y58800D02*
X392692Y55800D01*
G01X389692Y62200D02*
Y58800D01*
G01X392792Y65300D02*
X389692Y62200D01*
G01X392792Y92786D02*
Y65300D01*
G01X389113Y96465D02*
X392792Y92786D01*
G01X409789Y34986D02*
X410051Y34724D01*
G01X409789Y36710D02*
Y34986D01*
G01X406350Y40149D02*
X409789Y36710D01*
G01X406350Y53123D02*
Y40149D01*
G01X408069Y54842D02*
X406350Y53123D01*
G01X407954Y54957D02*
X408069Y54842D01*
G01X407036Y54957D02*
X407954D01*
G01X403040Y58953D02*
X407036Y54957D01*
G01X403040Y67477D02*
Y58953D01*
G01X402010Y68507D02*
X403040Y67477D01*
G01X402010Y71946D02*
Y68507D01*
G01X403093Y73029D02*
X402010Y71946D01*
G01X403092Y73032D02*
X403093Y73029D01*
G01X403092Y75372D02*
Y73032D01*
G01X401962Y76502D02*
X403092Y75372D01*
G01X401962Y79244D02*
Y76502D01*
G01X403092Y80374D02*
X401962Y79244D01*
G01X403092Y82900D02*
Y80374D01*
G01X402692Y83300D02*
X403092Y82900D01*
G01X402692Y86163D02*
Y83300D01*
G01X403175Y86646D02*
X402692Y86163D01*
G01X403175Y88138D02*
Y86646D01*
G01X402692Y88621D02*
X403175Y88138D01*
G01X402692Y91528D02*
Y88621D01*
G01X403561Y92397D02*
X402692Y91528D01*
G01X403561Y94142D02*
Y92397D01*
G01X402203Y95500D02*
X403561Y94142D01*
G01X416673Y33074D02*
X415609D01*
G01X416382Y51344D02*
X419849Y47877D01*
G01X416382Y56310D02*
Y51344D01*
G01X412900Y59792D02*
X416382Y56310D01*
G01X412900Y64508D02*
Y59792D01*
G01X413156Y64764D02*
X412900Y64508D01*
G01X413156Y72269D02*
Y64764D01*
G01X413026Y72399D02*
X413156Y72269D01*
G01X413026Y83635D02*
Y72399D01*
G01X413215Y83824D02*
X413026Y83635D01*
G01X413215Y85825D02*
Y83824D01*
G01X412961Y86079D02*
X413215Y85825D01*
G01X412961Y88569D02*
Y86079D01*
G01X413215Y88823D02*
X412961Y88569D01*
G01X413215Y91077D02*
Y88823D01*
G01X412892Y91400D02*
X413215Y91077D01*
G01X412892Y95800D02*
Y91400D01*
G01X414763Y37698D02*
Y35957D01*
G01X415379Y38314D02*
X414763Y37698D01*
G01X416688Y38314D02*
X415379D01*
G01X412143Y42128D02*
X417113D01*
G01X411643Y41628D02*
X412143Y42128D01*
G01X411643Y40673D02*
Y41628D01*
G01X411143Y40173D02*
X411643Y40673D01*
G01X409189Y40173D02*
X411143D01*
G01X408523Y40839D02*
X409189Y40173D01*
G01X408523Y44237D02*
Y40839D01*
G01X409535Y45249D02*
X408523Y44237D01*
G01X413793Y45249D02*
X409535D01*
G01X414763Y46219D02*
X413793Y45249D01*
G01X414763Y46922D02*
Y46219D01*
G01Y48887D02*
Y46922D01*
G01X409697Y53953D02*
X414763Y48887D01*
G01X409697Y56347D02*
Y53953D01*
G01X409087Y56957D02*
X409697Y56347D01*
G01X407635Y56957D02*
X409087D01*
G01X406336Y58256D02*
X407635Y56957D01*
G01X406336Y66631D02*
Y58256D01*
G01X406192Y66775D02*
X406336Y66631D01*
G01X406192Y69988D02*
Y66775D01*
G01X406522Y70318D02*
X406192Y69988D01*
G01X406522Y71810D02*
Y70318D01*
G01X406358Y71974D02*
X406522Y71810D01*
G01X406358Y74767D02*
Y71974D01*
G01X406692Y75101D02*
X406358Y74767D01*
G01X406692Y85175D02*
Y75101D01*
G01X406192Y85675D02*
X406692Y85175D01*
G01X406192Y88888D02*
Y85675D01*
G01X406522Y89218D02*
X406192Y88888D01*
G01X406522Y90710D02*
Y89218D01*
G01X406192Y91040D02*
X406522Y90710D01*
G01X406192Y95590D02*
Y91040D01*
G01X394840Y97549D02*
X395492Y96897D01*
G01X393901Y97549D02*
X394840D01*
G01X392866Y96514D02*
X393901Y97549D01*
G01X391684Y96514D02*
X392866D01*
G01X390603Y97595D02*
X391684Y96514D01*
G01X390603Y98777D02*
Y97595D01*
G01X391836Y100010D02*
X390603Y98777D01*
G01X391836Y101142D02*
Y100010D01*
G01X390705Y102273D02*
X391836Y101142D01*
G01X389573Y102273D02*
X390705D01*
G01X388508Y101208D02*
X389573Y102273D01*
G01X387075Y101208D02*
X388508D01*
G01X385944Y102339D02*
X387075Y101208D01*
G01X385944Y103170D02*
Y102339D01*
G01X387630Y104856D02*
X385944Y103170D01*
G01X387630Y105778D02*
Y104856D01*
G01X384136Y109272D02*
X387630Y105778D01*
G01X384136Y195798D02*
Y109272D01*
G01X410592Y101400D02*
X416788Y95204D01*
G01X410592Y109331D02*
Y101400D01*
G01X393948Y125975D02*
X410592Y109331D01*
G01X393948Y192984D02*
Y125975D01*
G01X360092Y192853D02*
Y115389D01*
G01X385719Y110059D02*
X397592Y98186D01*
G01X385719Y200166D02*
Y110059D01*
G01X368092Y107669D02*
Y192974D01*
G01X364627Y104204D02*
X368092Y107669D01*
G01X364627Y102837D02*
Y104204D01*
G01X403992Y101800D02*
X409953Y95839D01*
G01X403992Y110075D02*
Y101800D01*
G01X403199Y110868D02*
X403992Y110075D01*
G01X402032Y110868D02*
X403199D01*
G01X401144Y109980D02*
X402032Y110868D01*
G01X400014Y109980D02*
X401144D01*
G01X398881Y111113D02*
X400014Y109980D01*
G01X398881Y112243D02*
Y111113D01*
G01X399886Y113247D02*
X398881Y112243D01*
G01X399886Y114377D02*
Y113247D01*
G01X398753Y115510D02*
X399886Y114377D01*
G01X397623Y115510D02*
X398753D01*
G01X396618Y114506D02*
X397623Y115510D01*
G01X395488Y114506D02*
X396618D01*
G01X394355Y115639D02*
X395488Y114506D01*
G01X394355Y116769D02*
Y115639D01*
G01X395360Y117773D02*
X394355Y116769D01*
G01X395360Y118903D02*
Y117773D01*
G01X394469Y119794D02*
X395360Y118903D01*
G01X391696Y119794D02*
X394469D01*
G01X390516Y120974D02*
X391696Y119794D01*
G01X390516Y192316D02*
Y120974D01*
G01X412592Y102300D02*
X419592Y95300D01*
G01X412592Y110161D02*
Y102300D01*
G01X395749Y127004D02*
X412592Y110161D01*
G01X395749Y192972D02*
Y127004D01*
G01X386227Y96465D02*
X389113D01*
G01X384278Y98414D02*
X386227Y96465D01*
G01X384278Y104970D02*
Y98414D01*
G01X382514Y106734D02*
X384278Y104970D01*
G01X382514Y195289D02*
Y106734D01*
G01X409155Y136236D02*
X446832Y98559D01*
G01X409155Y194050D02*
Y136236D01*
G01X402806Y131266D02*
Y195555D01*
G01X425692Y108380D02*
X402806Y131266D01*
G01X401250Y129992D02*
Y195652D01*
G01X423692Y107550D02*
X401250Y129992D01*
G01X401060Y95500D02*
X402203D01*
G01X399875Y96685D02*
X401060Y95500D01*
G01X399875Y99017D02*
Y96685D01*
G01X395963Y102929D02*
X399875Y99017D01*
G01X395963Y103791D02*
Y102929D01*
G01X396864Y104692D02*
X395963Y103791D01*
G01X396864Y105400D02*
Y104692D01*
G01X395365Y106899D02*
X396864Y105400D01*
G01X394657Y106899D02*
X395365D01*
G01X393756Y105998D02*
X394657Y106899D01*
G01X392894Y105998D02*
X393756D01*
G01X391549Y107343D02*
X392894Y105998D01*
G01X391549Y108205D02*
Y107343D01*
G01X393295Y109951D02*
X391549Y108205D01*
G01X393295Y110708D02*
Y109951D01*
G01X391821Y112182D02*
X393295Y110708D01*
G01X391112Y112182D02*
X391821D01*
G01X389342Y110412D02*
X391112Y112182D01*
G01X388480Y110412D02*
X389342D01*
G01X387496Y111396D02*
X388480Y110412D01*
G01X387496Y199996D02*
Y111396D01*
G01X362092Y114559D02*
Y192853D01*
G01X406192Y102500D02*
X412892Y95800D01*
G01X406192Y110901D02*
Y102500D01*
G01X392026Y125067D02*
X406192Y110901D01*
G01X392026Y192547D02*
Y125067D01*
G01X405992Y133740D02*
X431892Y107840D01*
G01X405992Y194366D02*
Y133740D01*
G01X399392Y102390D02*
X406192Y95590D01*
G01X399392Y107700D02*
Y102390D01*
G01X389006Y118086D02*
X399392Y107700D01*
G01X389006Y191891D02*
Y118086D01*
G01X399537Y128875D02*
X418892Y109520D01*
G01X399537Y195507D02*
Y128875D01*
G01X364092Y113729D02*
Y192561D01*
G01X404353Y132549D02*
X429792Y107110D01*
G01X404353Y195531D02*
Y132549D01*
G01X356788Y99194D02*
X354913D01*
G01X357919Y100325D02*
X356788Y99194D01*
G01X357919Y101457D02*
Y100325D01*
G01X356850Y102526D02*
X357919Y101457D01*
G01X356850Y103658D02*
Y102526D01*
G01X357981Y104789D02*
X356850Y103658D01*
G01X359113Y104789D02*
X357981D01*
G01X360182Y103720D02*
X359113Y104789D01*
G01X361314Y103720D02*
X360182D01*
G01X362445Y104851D02*
X361314Y103720D01*
G01X362445Y105983D02*
Y104851D01*
G01X361376Y107052D02*
X362445Y105983D01*
G01X361376Y108184D02*
Y107052D01*
G01X362507Y109315D02*
X361376Y108184D01*
G01X365409Y109315D02*
X362507D01*
G01X366092Y109998D02*
X365409Y109315D01*
G01X366092Y192683D02*
Y109998D01*
G01X407617Y134945D02*
X436153Y106409D01*
G01X407617Y194172D02*
Y134945D01*
G01X356092Y189905D02*
Y117100D01*
G01X358092Y116218D02*
Y190734D01*
G01X397914Y127668D02*
X416821Y108761D01*
G01X397914Y195410D02*
Y127668D01*
G01X356188Y192638D02*
Y198807D01*
G01X358092Y190734D02*
X356188Y192638D01*
G01X382192Y407043D02*
Y496600D01*
G01X394192Y406684D02*
Y480353D01*
G01X354790Y407727D02*
Y486442D01*
G01X402192Y407687D02*
Y477868D01*
G01X362790Y408331D02*
Y494801D01*
G01X404192Y407669D02*
Y477262D01*
G01X356790Y407982D02*
Y487272D01*
G01X408192Y475826D02*
Y405358D01*
G01X406192Y476600D02*
Y405734D01*
G01X384192Y489158D02*
Y406734D01*
G01X414192Y406826D02*
Y473230D01*
G01X360790Y408385D02*
Y493972D01*
G01X396192Y406935D02*
Y479634D01*
G01X386192Y488670D02*
Y406737D01*
G01X390192Y487010D02*
Y406540D01*
G01X364790Y408465D02*
Y498700D01*
G01X410192Y405805D02*
Y475109D01*
G01X412192Y406100D02*
Y473892D01*
G01X400192Y407615D02*
Y478476D01*
G01X392192Y486180D02*
Y406612D01*
G01X398192Y407132D02*
Y478968D01*
G01X366790Y408694D02*
Y500114D01*
G01X388192Y487840D02*
Y406629D01*
G01X358790Y408586D02*
Y493252D01*
G01X392882Y508490D02*
Y548792D01*
G01X387992Y503600D02*
X392882Y508490D01*
G01X387992Y502400D02*
Y503600D01*
G01X382192Y496600D02*
X387992Y502400D01*
G01X412892Y516500D02*
Y527700D01*
G01X413292Y516100D02*
X412892Y516500D01*
G01X413292Y514600D02*
Y516100D01*
G01X412892Y514200D02*
X413292Y514600D01*
G01X412892Y511400D02*
Y514200D01*
G01X413492Y510800D02*
X412892Y511400D01*
G01X413492Y504651D02*
Y510800D01*
G01X404285Y495444D02*
X413492Y504651D01*
G01X404285Y494582D02*
Y495444D01*
G01X405873Y492994D02*
X404285Y494582D01*
G01X405873Y492112D02*
Y492994D01*
G01X404889Y491128D02*
X405873Y492112D01*
G01X404048Y491128D02*
X404889D01*
G01X402440Y492736D02*
X404048Y491128D01*
G01X401577Y492736D02*
X402440D01*
G01X400136Y491295D02*
X401577Y492736D01*
G01X400136Y486297D02*
Y491295D01*
G01X394192Y480353D02*
X400136Y486297D01*
G01X414222Y494065D02*
X426892Y506735D01*
G01X414222Y489898D02*
Y494065D01*
G01X402192Y477868D02*
X414222Y489898D01*
G01X416222Y493236D02*
X428992Y506006D01*
G01X416222Y489292D02*
Y493236D01*
G01X404192Y477262D02*
X416222Y489292D01*
G01X420222Y487856D02*
X408192Y475826D01*
G01X418222Y488630D02*
X406192Y476600D01*
G01X386236Y491202D02*
X384192Y489158D01*
G01X386236Y493144D02*
Y491202D01*
G01X384192Y495188D02*
X386236Y493144D01*
G01X384192Y496302D02*
Y495188D01*
G01X385521Y497631D02*
X384192Y496302D01*
G01X386471Y497631D02*
X385521D01*
G01X388831Y495271D02*
X386471Y497631D01*
G01X389963Y495271D02*
X388831D01*
G01X391094Y496402D02*
X389963Y495271D01*
G01X391094Y497534D02*
Y496402D01*
G01X388714Y499914D02*
X391094Y497534D01*
G01X388714Y500622D02*
Y499914D01*
G01X390269Y502177D02*
X388714Y500622D01*
G01X390977Y502177D02*
X390269D01*
G01X393357Y499797D02*
X390977Y502177D01*
G01X394489Y499797D02*
X393357D01*
G01X395620Y500928D02*
X394489Y499797D01*
G01X395620Y502060D02*
Y500928D01*
G01X393151Y504529D02*
X395620Y502060D01*
G01X393151Y505661D02*
Y504529D01*
G01X395492Y508002D02*
X393151Y505661D01*
G01X395492Y510500D02*
Y508002D01*
G01X396998Y512006D02*
X395492Y510500D01*
G01X396998Y513594D02*
Y512006D01*
G01X395333Y515259D02*
X396998Y513594D01*
G01X395333Y517681D02*
Y515259D01*
G01X396314Y518662D02*
X395333Y517681D01*
G01X396314Y529724D02*
Y518662D01*
G01X414192Y473230D02*
X446797Y505835D01*
G01X416292Y516400D02*
X416692Y516800D01*
G01X416292Y514500D02*
Y516400D01*
G01X416892Y513900D02*
X416292Y514500D01*
G01X415792Y510700D02*
X416892Y511800D01*
G01X415792Y504122D02*
Y510700D01*
G01X408092Y496422D02*
X415792Y504122D01*
G01X408092Y491534D02*
Y496422D01*
G01X396192Y479634D02*
X408092Y491534D01*
G01X397620Y500098D02*
X386192Y488670D01*
G01X397620Y507044D02*
Y500098D01*
G01X399992Y509416D02*
X397620Y507044D01*
G01X399992Y511200D02*
Y509416D01*
G01X399492Y511700D02*
X399992Y511200D01*
G01X399492Y513700D02*
Y511700D01*
G01X400492Y514700D02*
X399492Y513700D01*
G01X400492Y515900D02*
Y514700D01*
G01X399492Y516900D02*
X400492Y515900D01*
G01X399492Y519300D02*
Y516900D01*
G01X399744Y519552D02*
X399492Y519300D01*
G01X399744Y542674D02*
Y519552D01*
G01X399387Y496205D02*
X390192Y487010D01*
G01X399386Y496205D02*
X399387D01*
G01X403292Y500111D02*
X399386Y496205D01*
G01X403292Y503130D02*
Y500111D01*
G01X401894Y504528D02*
X403292Y503130D01*
G01X401894Y505660D02*
Y504528D01*
G01X403334Y507100D02*
X401894Y505660D01*
G01X406304Y507100D02*
X403334D01*
G01X407492Y508288D02*
X406304Y507100D01*
G01X407492Y510300D02*
Y508288D01*
G01X406192Y511600D02*
X407492Y510300D01*
G01X406192Y513900D02*
Y511600D01*
G01X406592Y514300D02*
X406192Y513900D01*
G01X406592Y516500D02*
Y514300D01*
G01X405607Y517485D02*
X406592Y516500D01*
G01X405607Y520165D02*
Y517485D01*
G01X406217Y520775D02*
X405607Y520165D01*
G01X407845Y520775D02*
X406217D01*
G01X408455Y521385D02*
X407845Y520775D01*
G01X408455Y522775D02*
Y521385D01*
G01X407845Y523385D02*
X408455Y522775D01*
G01X405943Y523385D02*
X407845D01*
G01X405139Y524189D02*
X405943Y523385D01*
G01X405139Y525796D02*
Y524189D01*
G01X406349Y527006D02*
X405139Y525796D01*
G01X356692Y524630D02*
Y527400D01*
G01X355956Y523894D02*
X356692Y524630D01*
G01X355956Y520986D02*
Y523894D01*
G01X356692Y520250D02*
X355956Y520986D01*
G01X356692Y517856D02*
Y520250D01*
G01X355435Y516599D02*
X356692Y517856D01*
G01X355435Y514101D02*
Y516599D01*
G01X356072Y513464D02*
X355435Y514101D01*
G01X356072Y512006D02*
Y513464D01*
G01X354924Y510858D02*
X356072Y512006D01*
G01X354924Y505868D02*
Y510858D01*
G01X356464Y504328D02*
X354924Y505868D01*
G01X358078Y504328D02*
X356464D01*
G01X358955Y505205D02*
X358078Y504328D01*
G01X360087Y505205D02*
X358955D01*
G01X361218Y504074D02*
X360087Y505205D01*
G01X361218Y502942D02*
Y504074D01*
G01X360100Y501824D02*
X361218Y502942D01*
G01X360100Y500692D02*
Y501824D01*
G01X361231Y499561D02*
X360100Y500692D01*
G01X363929Y499561D02*
X361231D01*
G01X364790Y498700D02*
X363929Y499561D01*
G01X410192Y475109D02*
X422222Y487139D01*
G01X412192Y473892D02*
X442592Y504292D01*
G01X412222Y494894D02*
X422647Y505319D01*
G01X412222Y490506D02*
Y494894D01*
G01X400192Y478476D02*
X412222Y490506D01*
G01X392902Y486890D02*
X392192Y486180D01*
G01X394034Y486890D02*
X392902D01*
G01X395742Y485182D02*
X394034Y486890D01*
G01X396874Y485182D02*
X395742D01*
G01X398005Y486313D02*
X396874Y485182D01*
G01X398005Y487445D02*
Y486313D01*
G01X396297Y489153D02*
X398005Y487445D01*
G01X396297Y490285D02*
Y489153D01*
G01X406967Y500955D02*
X396297Y490285D01*
G01X406967Y502087D02*
Y500955D01*
G01X406443Y502611D02*
X406967Y502087D01*
G01X406443Y503985D02*
Y502611D01*
G01X407636Y505178D02*
X406443Y503985D01*
G01X409521Y505178D02*
X407636D01*
G01X410799Y506456D02*
X409521Y505178D01*
G01X410799Y508183D02*
Y506456D01*
G01X409581Y509401D02*
X410799Y508183D01*
G01X409581Y511089D02*
Y509401D01*
G01X409992Y511500D02*
X409581Y511089D01*
G01X409992Y513700D02*
Y511500D01*
G01X409492Y514200D02*
X409992Y513700D01*
G01X409492Y516600D02*
Y514200D01*
G01X410192Y517300D02*
X409492Y516600D01*
G01X410192Y526800D02*
Y517300D01*
G01X410222Y495723D02*
X419862Y505363D01*
G01X410222Y490998D02*
Y495723D01*
G01X398192Y478968D02*
X410222Y490998D01*
G01X358692Y517306D02*
Y526900D01*
G01X357244Y515858D02*
X358692Y517306D01*
G01X357244Y514589D02*
Y515858D01*
G01X357719Y514114D02*
X357244Y514589D01*
G01X357719Y511327D02*
Y514114D01*
G01X357070Y510678D02*
X357719Y511327D01*
G01X357070Y507764D02*
Y510678D01*
G01X357774Y507060D02*
X357070Y507764D01*
G01X364105Y507060D02*
X357774D01*
G01X365236Y505929D02*
X364105Y507060D01*
G01X365236Y501668D02*
Y505929D01*
G01X366790Y500114D02*
X365236Y501668D01*
G01X401292Y500940D02*
X388192Y487840D01*
G01X401292Y502301D02*
Y500940D01*
G01X399620Y503973D02*
X401292Y502301D01*
G01X399620Y506215D02*
Y503973D01*
G01X402792Y509387D02*
X399620Y506215D01*
G01X402792Y511300D02*
Y509387D01*
G01X403292Y511800D02*
X402792Y511300D01*
G01X403292Y513800D02*
Y511800D01*
G01X402692Y514400D02*
X403292Y513800D01*
G01X402692Y516200D02*
Y514400D01*
G01X403392Y516900D02*
X402692Y516200D01*
G01X403392Y519300D02*
Y516900D01*
G01X403050Y519642D02*
X403392Y519300D01*
G01X403050Y535258D02*
Y519642D01*
G01X357435Y494607D02*
X356063D01*
G01X358790Y493252D02*
X357435Y494607D01*
G01X394682Y574755D02*
X394684Y574757D01*
G01X394682Y572310D02*
Y574755D01*
G01X396692Y570300D02*
X394682Y572310D01*
G01X396692Y568700D02*
Y570300D01*
G01X395792Y567800D02*
X396692Y568700D01*
G01X395792Y557800D02*
Y567800D01*
G01X396395Y557197D02*
X395792Y557800D01*
G01X396395Y554803D02*
Y557197D01*
G01X394682Y553090D02*
X396395Y554803D01*
G01X394682Y550592D02*
Y553090D01*
G01X392882Y548792D02*
X394682Y550592D01*
G01X414763Y572633D02*
Y574757D01*
G01X414761Y572631D02*
X414763Y572633D01*
G01X416376Y571016D02*
X414761Y572631D01*
G01X416376Y549535D02*
Y571016D01*
G01X414763Y547922D02*
X416376Y549535D01*
G01X414763Y545236D02*
Y547922D01*
G01X413026Y543499D02*
X414763Y545236D01*
G01X413026Y532834D02*
Y543499D01*
G01X412892Y532700D02*
X413026Y532834D01*
G01X412892Y530600D02*
Y532700D01*
G01X413129Y530363D02*
X412892Y530600D01*
G01X413129Y527937D02*
Y530363D01*
G01X412892Y527700D02*
X413129Y527937D01*
G01X398029Y555842D02*
Y566807D01*
G01X396585Y529995D02*
X396314Y529724D01*
G01X396585Y532707D02*
Y529995D01*
G01X396321Y532971D02*
X396585Y532707D01*
G01X396321Y546961D02*
Y532971D01*
G01X396229Y547053D02*
X396321Y546961D01*
G01X396229Y549063D02*
Y547053D01*
G01X398029Y550863D02*
X396229Y549063D01*
G01X398029Y555842D02*
Y550863D01*
G01X416390Y543198D02*
X419813Y546621D01*
G01X416390Y535698D02*
Y543198D01*
G01X416398Y535690D02*
X416390Y535698D01*
G01X416398Y527894D02*
Y535690D01*
G01X416692Y527600D02*
X416398Y527894D01*
G01X404723Y555857D02*
Y566822D01*
G01X403065Y545995D02*
X399744Y542674D01*
G01X403065Y552787D02*
Y545995D01*
G01X404723Y554445D02*
X403065Y552787D01*
G01X404723Y555857D02*
Y554445D01*
G01X406349Y530643D02*
Y527006D01*
G01X405945Y531047D02*
X406349Y530643D01*
G01X405945Y535453D02*
Y531047D01*
G01X406356Y535864D02*
X405945Y535453D01*
G01X406356Y538064D02*
Y535864D01*
G01X406992Y538700D02*
X406356Y538064D01*
G01X406992Y543800D02*
Y538700D01*
G01X409779Y546587D02*
X406992Y543800D01*
G01X409779Y549087D02*
Y546587D01*
G01X409892Y549200D02*
X409779Y549087D01*
G01X409892Y553934D02*
Y549200D01*
G01X409683Y554143D02*
X409892Y553934D01*
G01X409683Y556652D02*
Y554143D01*
G01X410986Y557955D02*
X409683Y556652D01*
G01X413078Y557955D02*
X410986D01*
G01X414763Y559640D02*
X413078Y557955D01*
G01X414763Y566822D02*
Y559640D01*
G01X356154Y536302D02*
Y542838D01*
G01X355742Y535890D02*
X356154Y536302D01*
G01X355742Y530888D02*
Y535890D01*
G01X356161Y530469D02*
X355742Y530888D01*
G01X356161Y527931D02*
Y530469D01*
G01X356692Y527400D02*
X356161Y527931D01*
G01X409779Y527213D02*
X410192Y526800D01*
G01X409779Y530487D02*
Y527213D01*
G01X409992Y530700D02*
X409779Y530487D01*
G01X409992Y535600D02*
Y530700D01*
G01X409793Y535799D02*
X409992Y535600D01*
G01X409793Y543601D02*
Y535799D01*
G01X413100Y546908D02*
X409793Y543601D01*
G01X413100Y554194D02*
Y546908D01*
G01X414763Y555857D02*
X413100Y554194D01*
G01X356205Y554997D02*
Y568343D01*
G01X355771Y554563D02*
X356205Y554997D01*
G01X355771Y551837D02*
Y554563D01*
G01X358992Y540068D02*
Y542377D01*
G01X359792Y539268D02*
X358992Y540068D01*
G01X359792Y528000D02*
Y539268D01*
G01X358692Y526900D02*
X359792Y528000D01*
G01X407155Y566807D02*
X408069D01*
G01X406480Y566132D02*
X407155Y566807D01*
G01X406480Y565044D02*
Y566132D01*
G01X407090Y564434D02*
X406480Y565044D01*
G01X411809Y564434D02*
X407090D01*
G01X412523Y563720D02*
X411809Y564434D01*
G01X412523Y560282D02*
Y563720D01*
G01X411882Y559641D02*
X412523Y560282D01*
G01X409278Y559641D02*
X411882D01*
G01X408668Y560251D02*
X409278Y559641D01*
G01X408668Y561506D02*
Y560251D01*
G01X408111Y562063D02*
X408668Y561506D01*
G01X407149Y562063D02*
X408111D01*
G01X406373Y561287D02*
X407149Y562063D01*
G01X406373Y556652D02*
Y561287D01*
G01X407183Y555842D02*
X406373Y556652D01*
G01X408069Y555842D02*
X407183D01*
G01X403092Y535300D02*
X403050Y535258D01*
G01X403092Y543200D02*
Y535300D01*
G01X406341Y546449D02*
X403092Y543200D01*
G01X406341Y552670D02*
Y546449D01*
G01X408069Y554398D02*
X406341Y552670D01*
G01X408069Y555842D02*
Y554398D01*
G01X443146Y-42355D02*
G02Y-45915I0J-1780D01*
G01X424801Y32871D02*
Y28007D01*
G01X423082Y34590D02*
X424801Y32871D01*
G01X455044Y31700D02*
X456620Y33276D01*
G01X453820Y31700D02*
X455044D01*
G01X451573Y29453D02*
X453820Y31700D01*
G01X451573Y27899D02*
Y29453D01*
G01X458266Y30021D02*
Y27899D01*
G01X460145Y31900D02*
X458266Y30021D01*
G01X461545Y31900D02*
X460145D01*
G01X463001Y33356D02*
X461545Y31900D01*
G01X438189Y30103D02*
X433232Y35060D01*
G01X438189Y28022D02*
Y30103D01*
G01X476245Y29146D02*
X474998Y27899D01*
G01X476245Y30400D02*
Y29146D01*
G01X477545Y31700D02*
X476245Y30400D01*
G01X478545Y31700D02*
X477545D01*
G01X417802Y31945D02*
X416673Y33074D01*
G01X418788Y31945D02*
X417802D01*
G01X419849Y33006D02*
X418788Y31945D01*
G01X444880Y30012D02*
Y28022D01*
G01X439813Y35079D02*
X444880Y30012D01*
G01X431494Y29998D02*
Y28007D01*
G01X426533Y34959D02*
X431494Y29998D01*
G01X423082Y51814D02*
Y34590D01*
G01X422124Y52772D02*
X423082Y51814D01*
G01X420820Y52772D02*
X422124D01*
G01X419844Y53748D02*
X420820Y52772D01*
G01X419844Y55677D02*
Y53748D01*
G01X416742Y58779D02*
X419844Y55677D01*
G01X416742Y64250D02*
Y58779D01*
G01X416666Y88374D02*
Y86374D01*
G01X416788Y95204D02*
Y91912D01*
G01X456466Y91105D02*
Y98590D01*
G01X456469Y91102D02*
X456466Y91105D01*
G01X456469Y89871D02*
Y91102D01*
G01X456483Y89857D02*
X456469Y89871D01*
G01X456483Y86468D02*
Y89857D01*
G01X456133Y86118D02*
X456483Y86468D01*
G01X456133Y73203D02*
Y86118D01*
G01X456483Y72853D02*
X456133Y73203D01*
G01X456483Y66653D02*
Y72853D01*
G01X456466Y66636D02*
X456483Y66653D01*
G01X456466Y64475D02*
Y66636D01*
G01X454292Y62301D02*
X456466Y64475D01*
G01X454292Y54701D02*
Y62301D01*
G01X452769Y53178D02*
X454292Y54701D01*
G01X452769Y51414D02*
Y53178D01*
G01X454619Y49564D02*
X452769Y51414D01*
G01X454629Y49564D02*
X454619D01*
G01X455845Y48348D02*
X454629Y49564D01*
G01X455845Y35675D02*
Y48348D01*
G01X456620Y34900D02*
X455845Y35675D01*
G01X456620Y33276D02*
Y34900D01*
G01X424250Y54842D02*
X424801D01*
G01X418972Y60120D02*
X424250Y54842D01*
G01X418972Y63780D02*
Y60120D01*
G01X419842Y64650D02*
X418972Y63780D01*
G01X419842Y67166D02*
Y64650D01*
G01X419549Y67459D02*
X419842Y67166D01*
G01X419549Y71471D02*
Y67459D01*
G01X419861Y71783D02*
X419549Y71471D01*
G01X419861Y72647D02*
Y71783D01*
G01X419844Y72664D02*
X419861Y72647D01*
G01X419844Y75054D02*
Y72664D01*
G01X420149Y75359D02*
X419844Y75054D01*
G01X420149Y91074D02*
Y75359D01*
G01X419592Y91631D02*
X420149Y91074D01*
G01X419592Y95300D02*
Y91631D01*
G01X463001Y34700D02*
Y33356D01*
G01X462385Y35316D02*
X463001Y34700D01*
G01X462385Y48441D02*
Y35316D01*
G01X460912Y49914D02*
X462385Y48441D01*
G01X458839Y51987D02*
X460912Y49914D01*
G01X458839Y53048D02*
Y51987D01*
G01X460333Y54542D02*
X458839Y53048D01*
G01X460333Y61942D02*
Y54542D01*
G01X462833Y64442D02*
X460333Y61942D01*
G01X462833Y99873D02*
Y64442D01*
G01X445178Y47220D02*
X444880Y46922D01*
G01X445178Y51946D02*
Y47220D01*
G01X446992Y53760D02*
X445178Y51946D01*
G01X446992Y67241D02*
Y53760D01*
G01X446832Y67401D02*
X446992Y67241D01*
G01X446832Y98559D02*
Y67401D01*
G01X460045Y34567D02*
X460912Y33700D01*
G01X460045Y36868D02*
Y34567D01*
G01X458412Y38501D02*
X460045Y36868D01*
G01X458412Y39800D02*
Y38501D01*
G01X459762Y41150D02*
X458412Y39800D01*
G01X459762Y42050D02*
Y41150D01*
G01X458512Y43300D02*
X459762Y42050D01*
G01X458512Y44499D02*
Y43300D01*
G01X460045Y46032D02*
X458512Y44499D01*
G01X460045Y48000D02*
Y46032D01*
G01X457145Y50900D02*
X460045Y48000D01*
G01X457145Y53836D02*
Y50900D01*
G01X458266Y54957D02*
X457145Y53836D01*
G01X456992Y56231D02*
X458266Y54957D01*
G01X456992Y61879D02*
Y56231D01*
G01X460133Y65020D02*
X456992Y61879D01*
G01X460133Y66259D02*
Y65020D01*
G01X458983Y67409D02*
X460133Y66259D01*
G01X458983Y71991D02*
Y67409D01*
G01X460333Y73341D02*
X458983Y71991D01*
G01X460333Y85368D02*
Y73341D01*
G01X458983Y86718D02*
X460333Y85368D01*
G01X458983Y90928D02*
Y86718D01*
G01X460066Y92011D02*
X458983Y90928D01*
G01X460066Y98525D02*
Y92011D01*
G01X432653Y91787D02*
Y95139D01*
G01X433339Y91101D02*
X432653Y91787D01*
G01X433339Y88847D02*
Y91101D01*
G01X432971Y88479D02*
X433339Y88847D01*
G01X432971Y85969D02*
Y88479D01*
G01X433200Y85740D02*
X432971Y85969D01*
G01X433200Y72627D02*
Y85740D01*
G01X431736Y71163D02*
X433200Y72627D01*
G01X431736Y68153D02*
Y71163D01*
G01X433219Y66670D02*
X431736Y68153D01*
G01X433219Y59827D02*
Y66670D01*
G01X438187Y54859D02*
X433219Y59827D01*
G01X429979Y91487D02*
Y94813D01*
G01X429566Y91074D02*
X429979Y91487D01*
G01X429566Y88974D02*
Y91074D01*
G01X429997Y88543D02*
X429566Y88974D01*
G01X429997Y86105D02*
Y88543D01*
G01X429552Y85660D02*
X429997Y86105D01*
G01X429552Y83388D02*
Y85660D01*
G01X429754Y83186D02*
X429552Y83388D01*
G01X429754Y72347D02*
Y83186D01*
G01X429466Y72059D02*
X429754Y72347D01*
G01X429466Y70159D02*
Y72059D01*
G01X429773Y69852D02*
X429466Y70159D01*
G01X429773Y60331D02*
Y69852D01*
G01X433131Y56973D02*
X429773Y60331D01*
G01X433131Y53561D02*
Y56973D01*
G01X431713Y52143D02*
X433131Y53561D01*
G01X431713Y49779D02*
Y52143D01*
G01X433232Y48260D02*
X431713Y49779D01*
G01X433232Y35060D02*
Y48260D01*
G01X476433Y51825D02*
X478344Y49914D01*
G01X476433Y53610D02*
Y51825D01*
G01X477983Y55160D02*
X476433Y53610D01*
G01X477983Y55732D02*
Y55160D01*
G01X479891Y57640D02*
X477983Y55732D01*
G01X419849Y36995D02*
Y33006D01*
G01X420475Y37621D02*
X419849Y36995D01*
G01X420475Y44425D02*
Y37621D01*
G01X419849Y45051D02*
X420475Y44425D01*
G01X419849Y47877D02*
Y45051D01*
G01X443256Y37583D02*
X444882Y35957D01*
G01X443256Y47607D02*
Y37583D01*
G01X442692Y48970D02*
X443256Y47607D01*
G01X442692Y52600D02*
Y48970D01*
G01X443256Y53164D02*
X442692Y52600D01*
G01X443256Y56436D02*
Y53164D01*
G01X439811Y59881D02*
X443256Y56436D01*
G01X439811Y66981D02*
Y59881D01*
G01X439292Y67500D02*
X439811Y66981D01*
G01X439292Y69200D02*
Y67500D01*
G01X440192Y70100D02*
X439292Y69200D01*
G01X440192Y71900D02*
Y70100D01*
G01X439828Y72264D02*
X440192Y71900D01*
G01X439828Y74636D02*
Y72264D01*
G01X440292Y75100D02*
X439828Y74636D01*
G01X440292Y85700D02*
Y75100D01*
G01X439258Y86734D02*
X440292Y85700D01*
G01X439258Y87866D02*
Y86734D01*
G01X440492Y89100D02*
X439258Y87866D01*
G01X440492Y90700D02*
Y89100D01*
G01X439452Y91740D02*
X440492Y90700D01*
G01X439452Y95349D02*
Y91740D01*
G01X417592Y39218D02*
X416688Y38314D01*
G01X417592Y41649D02*
Y39218D01*
G01X417113Y42128D02*
X417592Y41649D01*
G01X426520Y59816D02*
X431494Y54842D01*
G01X426520Y82692D02*
Y59816D01*
G01X426963Y83135D02*
X426520Y82692D01*
G01X426963Y85360D02*
Y83135D01*
G01X425849Y86474D02*
X426963Y85360D01*
G01X425849Y88224D02*
Y86474D01*
G01X426849Y89224D02*
X425849Y88224D01*
G01X426849Y91042D02*
Y89224D01*
G01X425692Y92199D02*
X426849Y91042D01*
G01X425692Y95600D02*
Y92199D01*
G01X451573Y62682D02*
Y54957D01*
G01X453373Y64482D02*
X451573Y62682D01*
G01X453373Y66419D02*
Y64482D01*
G01X452633Y67159D02*
X453373Y66419D01*
G01X452633Y72103D02*
Y67159D01*
G01X453633Y73103D02*
X452633Y72103D01*
G01X453633Y85418D02*
Y73103D01*
G01X452633Y86418D02*
X453633Y85418D01*
G01X452633Y91218D02*
Y86418D01*
G01X453992Y92577D02*
X452633Y91218D01*
G01X453992Y93300D02*
Y92577D01*
G01X452692Y94600D02*
X453992Y93300D01*
G01X453445Y34788D02*
X454533Y33700D01*
G01X453445Y36668D02*
Y34788D01*
G01X452012Y38101D02*
X453445Y36668D01*
G01X452012Y39300D02*
Y38101D01*
G01X453512Y40800D02*
X452012Y39300D01*
G01X453512Y42000D02*
Y40800D01*
G01X452062Y43450D02*
X453512Y42000D01*
G01X452062Y44849D02*
Y43450D01*
G01X453445Y46232D02*
X452062Y44849D01*
G01X453445Y48101D02*
Y46232D01*
G01X450645Y50901D02*
X453445Y48101D01*
G01X450645Y54029D02*
Y50901D01*
G01X451573Y54957D02*
X450645Y54029D01*
G01X439813Y49600D02*
Y35079D01*
G01X439805Y49608D02*
X439813Y49600D01*
G01X439805Y56683D02*
Y49608D01*
G01X436558Y59930D02*
X439805Y56683D01*
G01X436558Y67266D02*
Y59930D01*
G01X436792Y67500D02*
X436558Y67266D01*
G01X436792Y69500D02*
Y67500D01*
G01X435992Y70300D02*
X436792Y69500D01*
G01X435992Y72000D02*
Y70300D01*
G01X436492Y72500D02*
X435992Y72000D01*
G01X436492Y83000D02*
Y72500D01*
G01X435992Y83500D02*
X436492Y83000D01*
G01X435992Y85500D02*
Y83500D01*
G01X436892Y86400D02*
X435992Y85500D01*
G01X436892Y88500D02*
Y86400D01*
G01X436092Y89300D02*
X436892Y88500D01*
G01X436092Y90800D02*
Y89300D01*
G01X436692Y91400D02*
X436092Y90800D01*
G01X436692Y95280D02*
Y91400D01*
G01X476870Y35574D02*
X478344Y34100D01*
G01X476870Y36668D02*
Y35574D01*
G01X475437Y38101D02*
X476870Y36668D01*
G01X475437Y39324D02*
Y38101D01*
G01X476937Y40824D02*
X475437Y39324D01*
G01X476937Y42176D02*
Y40824D01*
G01X475437Y43676D02*
X476937Y42176D01*
G01X475437Y44799D02*
Y43676D01*
G01X477112Y46474D02*
X475437Y44799D01*
G01X477112Y47859D02*
Y46474D01*
G01X474070Y50901D02*
X477112Y47859D01*
G01X474070Y54029D02*
Y50901D01*
G01X474998Y54957D02*
X474070Y54029D01*
G01X474239Y55716D02*
X474998Y54957D01*
G01X474239Y56848D02*
Y55716D01*
G01X476798Y59407D02*
X474239Y56848D01*
G01X476798Y60894D02*
Y59407D01*
G01X475992Y61700D02*
X476798Y60894D01*
G01X475992Y63500D02*
Y61700D01*
G01X476798Y64306D02*
X475992Y63500D01*
G01X476798Y66538D02*
Y64306D01*
G01X476433Y66903D02*
X476798Y66538D01*
G01X476433Y72541D02*
Y66903D01*
G01X477233Y73341D02*
X476433Y72541D01*
G01X477233Y85718D02*
Y73341D01*
G01X476433Y86518D02*
X477233Y85718D01*
G01X476433Y91218D02*
Y86518D01*
G01X476833Y91618D02*
X476433Y91218D01*
G01X476833Y93659D02*
Y91618D01*
G01X475892Y94600D02*
X476833Y93659D01*
G01X444880Y57812D02*
Y54859D01*
G01X443274Y59418D02*
X444880Y57812D01*
G01X443274Y60895D02*
Y59418D01*
G01X443884Y61505D02*
X443274Y60895D01*
G01X444624Y61505D02*
X443884D01*
G01X445234Y62115D02*
X444624Y61505D01*
G01X445234Y63505D02*
Y62115D01*
G01X444624Y64115D02*
X445234Y63505D01*
G01X443884Y64115D02*
X444624D01*
G01X443274Y64725D02*
X443884Y64115D01*
G01X443274Y67620D02*
Y64725D01*
G01X443884Y68230D02*
X443274Y67620D01*
G01X444582Y68230D02*
X443884D01*
G01X445192Y68840D02*
X444582Y68230D01*
G01X445192Y70230D02*
Y68840D01*
G01X444582Y70840D02*
X445192Y70230D01*
G01X443884Y70840D02*
X444582D01*
G01X443274Y71450D02*
X443884Y70840D01*
G01X443274Y75166D02*
Y71450D01*
G01X442407Y76033D02*
X443274Y75166D01*
G01X442407Y78397D02*
Y76033D01*
G01X443018Y79008D02*
X442407Y78397D01*
G01X444499Y79008D02*
X443018D01*
G01X445109Y79618D02*
X444499Y79008D01*
G01X445109Y81008D02*
Y79618D01*
G01X444499Y81618D02*
X445109Y81008D01*
G01X443212Y81618D02*
X444499D01*
G01X442566Y82264D02*
X443212Y81618D01*
G01X442566Y85279D02*
Y82264D01*
G01X443862Y86575D02*
X442566Y85279D01*
G01X443862Y88177D02*
Y86575D01*
G01X442689Y89350D02*
X443862Y88177D01*
G01X442689Y90619D02*
Y89350D01*
G01X444856Y92786D02*
X442689Y90619D01*
G01X444856Y96426D02*
Y92786D01*
G01X426533Y53559D02*
Y34959D01*
G01X426418Y53674D02*
X426533Y53559D01*
G01X426418Y55574D02*
Y53674D01*
G01X423092Y58900D02*
X426418Y55574D01*
G01X423092Y66902D02*
Y58900D01*
G01X423639Y67449D02*
X423092Y66902D01*
G01X423639Y70969D02*
Y67449D01*
G01X423076Y71532D02*
X423639Y70969D01*
G01X423076Y76016D02*
Y71532D01*
G01X422666Y76426D02*
X423076Y76016D01*
G01X422666Y85591D02*
Y76426D01*
G01X423311Y86236D02*
X422666Y85591D01*
G01X423311Y88412D02*
Y86236D01*
G01X422688Y89035D02*
X423311Y88412D01*
G01X422688Y91013D02*
Y89035D01*
G01X423692Y92017D02*
X422688Y91013D01*
G01X423692Y94600D02*
Y92017D01*
G01X416821Y101471D02*
X423692Y94600D01*
G01X474470Y143810D02*
X454692Y163588D01*
G01X474470Y142678D02*
Y143810D01*
G01X472438Y140646D02*
X474470Y142678D01*
G01X472438Y139854D02*
Y140646D01*
G01X474097Y138195D02*
X472438Y139854D01*
G01X474889Y138195D02*
X474097D01*
G01X476827Y140133D02*
X474889Y138195D01*
G01X477959Y140133D02*
X476827D01*
G01X479090Y139002D02*
X477959Y140133D01*
G01X477952Y136732D02*
X479090Y137870D01*
G01X477952Y135940D02*
Y136732D01*
G01X479534Y134358D02*
X477952Y135940D01*
G01X419890Y144295D02*
Y178501D01*
G01X428992Y135193D02*
X419890Y144295D01*
G01X428992Y133935D02*
Y135193D01*
G01X425792Y130735D02*
X428992Y133935D01*
G01X425792Y129264D02*
Y130735D01*
G01X456466Y98590D02*
X425792Y129264D01*
G01X452043Y155141D02*
X453489Y156587D01*
G01X452043Y154349D02*
Y155141D01*
G01X453514Y152878D02*
X452043Y154349D01*
G01X454306Y152878D02*
X453514D01*
G01X455752Y154324D02*
X454306Y152878D01*
G01X456884Y154324D02*
X455752D01*
G01X458015Y153193D02*
X456884Y154324D01*
G01X458015Y152061D02*
Y153193D01*
G01X456369Y150415D02*
X458015Y152061D01*
G01X456369Y149623D02*
Y150415D01*
G01X457840Y148152D02*
X456369Y149623D01*
G01X458632Y148152D02*
X457840D01*
G01X460278Y149798D02*
X458632Y148152D01*
G01X461410Y149798D02*
X460278D01*
G01X462685Y148523D02*
X461410Y149798D01*
G01X462685Y147391D02*
Y148523D01*
G01X460192Y144898D02*
X462685Y147391D01*
G01X460192Y143300D02*
Y144898D01*
G01X488592Y114900D02*
X460192Y143300D01*
G01X440020Y122686D02*
X462833Y99873D01*
G01X440020Y123478D02*
Y122686D01*
G01X441241Y124699D02*
X440020Y123478D01*
G01X442033Y124699D02*
X441241D01*
G01X444813Y121919D02*
X442033Y124699D01*
G01X445880Y121919D02*
X444813D01*
G01X447075Y123114D02*
X445880Y121919D01*
G01X447075Y124182D02*
Y123114D01*
G01X424890Y146367D02*
X447075Y124182D01*
G01X424890Y178501D02*
Y146367D01*
G01X430162Y128429D02*
X460066Y98525D01*
G01X430162Y129221D02*
Y128429D01*
G01X431672Y130731D02*
X430162Y129221D01*
G01X432464Y130731D02*
X431672D01*
G01X435548Y127647D02*
X432464Y130731D01*
G01X436340Y127647D02*
X435548D01*
G01X437811Y129118D02*
X436340Y127647D01*
G01X437811Y129910D02*
Y129118D01*
G01X422390Y145331D02*
X437811Y129910D01*
G01X422390Y178498D02*
Y145331D01*
G01X440767Y152325D02*
X483983Y109109D01*
G01X440767Y167469D02*
Y152325D01*
G01X425692Y102100D02*
Y108380D01*
G01X432653Y95139D02*
X425692Y102100D01*
G01X423692Y101100D02*
Y107550D01*
G01X429979Y94813D02*
X423692Y101100D01*
G01X438267Y151226D02*
X479592Y109901D01*
G01X438267Y179774D02*
Y151226D01*
G01X431892Y102909D02*
X439452Y95349D01*
G01X431892Y107840D02*
Y102909D01*
G01X488011Y133805D02*
X457192Y164624D01*
G01X418892Y102400D02*
X425692Y95600D01*
G01X418892Y109520D02*
Y102400D01*
G01X443267Y153425D02*
X486483Y110209D01*
G01X443267Y162336D02*
Y153425D01*
G01X452692Y95300D02*
Y94600D01*
G01X453992Y96600D02*
X452692Y95300D01*
G01X453992Y97378D02*
Y96600D01*
G01X419827Y131543D02*
X453992Y97378D01*
G01X419827Y132335D02*
Y131543D01*
G01X421167Y133675D02*
X419827Y132335D01*
G01X421959Y133675D02*
X421167D01*
G01X422847Y132787D02*
X421959Y133675D01*
G01X423857Y132787D02*
X422847D01*
G01X425110Y134040D02*
X423857Y132787D01*
G01X425110Y135050D02*
Y134040D01*
G01X417666Y142494D02*
X425110Y135050D01*
G01X417666Y178774D02*
Y142494D01*
G01X429792Y102180D02*
X436692Y95280D01*
G01X429792Y107110D02*
Y102180D01*
G01X475892Y110001D02*
Y94600D01*
G01X475409Y110484D02*
X475892Y110001D01*
G01X474279Y110484D02*
X475409D01*
G01X473610Y109814D02*
X474279Y110484D01*
G01X472480Y109814D02*
X473610D01*
G01X471347Y110947D02*
X472480Y109814D01*
G01X471347Y112077D02*
Y110947D01*
G01X472016Y112746D02*
X471347Y112077D01*
G01X472016Y113877D02*
Y112746D01*
G01X470883Y115010D02*
X472016Y113877D01*
G01X469753Y115010D02*
X470883D01*
G01X469084Y114340D02*
X469753Y115010D01*
G01X467954Y114340D02*
X469084D01*
G01X466821Y115473D02*
X467954Y114340D01*
G01X466821Y116603D02*
Y115473D01*
G01X467490Y117272D02*
X466821Y116603D01*
G01X467490Y118403D02*
Y117272D01*
G01X466357Y119536D02*
X467490Y118403D01*
G01X465227Y119536D02*
X466357D01*
G01X464558Y118866D02*
X465227Y119536D01*
G01X463428Y118866D02*
X464558D01*
G01X462295Y119999D02*
X463428Y118866D01*
G01X462295Y121898D02*
Y119999D01*
G01X460801Y123392D02*
X462295Y121898D01*
G01X458902Y123392D02*
X460801D01*
G01X457769Y124525D02*
X458902Y123392D01*
G01X457769Y125655D02*
Y124525D01*
G01X458438Y126324D02*
X457769Y125655D01*
G01X458438Y127455D02*
Y126324D01*
G01X435698Y150195D02*
X458438Y127455D01*
G01X435698Y179831D02*
Y150195D01*
G01X443806Y97476D02*
X444856Y96426D01*
G01X440516Y97476D02*
X443806D01*
G01X439526Y98466D02*
X440516Y97476D01*
G01X439526Y99598D02*
Y98466D01*
G01X440679Y100751D02*
X439526Y99598D01*
G01X440679Y101883D02*
Y100751D01*
G01X439548Y103014D02*
X440679Y101883D01*
G01X438416Y103014D02*
X439548D01*
G01X437263Y101861D02*
X438416Y103014D01*
G01X436131Y101861D02*
X437263D01*
G01X435000Y102992D02*
X436131Y101861D01*
G01X435000Y104124D02*
Y102992D01*
G01X436153Y105277D02*
X435000Y104124D01*
G01X436153Y106409D02*
Y105277D01*
G01X466221Y148523D02*
X452192Y162552D01*
G01X466221Y147391D02*
Y148523D01*
G01X464757Y145927D02*
X466221Y147391D01*
G01X464757Y145135D02*
Y145927D01*
G01X466228Y143664D02*
X464757Y145135D01*
G01X467020Y143664D02*
X466228D01*
G01X468484Y145128D02*
X467020Y143664D01*
G01X469616Y145128D02*
X468484D01*
G01X470824Y143920D02*
X469616Y145128D01*
G01X470824Y142568D02*
Y143920D01*
G01X468392Y140136D02*
X470824Y142568D01*
G01X468392Y138636D02*
Y140136D01*
G01X492992Y114036D02*
X468392Y138636D01*
G01X416821Y108761D02*
Y101471D01*
G01X454692Y163588D02*
Y184800D01*
G01X469884Y169836D02*
Y185408D01*
G01X517392Y122328D02*
X469884Y169836D01*
G01X449692Y161516D02*
Y183700D01*
G01X453489Y157719D02*
X449692Y161516D01*
G01X453489Y156587D02*
Y157719D01*
G01X441377Y168079D02*
X440767Y167469D01*
G01X442532Y168079D02*
X441377D01*
G01X443092Y168639D02*
X442532Y168079D01*
G01X443092Y170629D02*
Y168639D01*
G01X442532Y171189D02*
X443092Y170629D01*
G01X441377Y171189D02*
X442532D01*
G01X440767Y171799D02*
X441377Y171189D01*
G01X440767Y179774D02*
Y171799D01*
G01X440710Y179831D02*
X440767Y179774D01*
G01X474884Y173760D02*
X509444Y139200D01*
G01X474884Y186158D02*
Y173760D01*
G01X467384Y168800D02*
Y185192D01*
G01X512492Y123692D02*
X467384Y168800D01*
G01X438210Y179831D02*
X438267Y179774D01*
G01X457192Y164624D02*
Y184900D01*
G01X445970Y165039D02*
X443267Y162336D01*
G01X445970Y173516D02*
Y165039D01*
G01X443267Y176219D02*
X445970Y173516D01*
G01X443267Y179774D02*
Y176219D01*
G01X443210Y179831D02*
X443267Y179774D01*
G01X472384Y170872D02*
X507311Y135945D01*
G01X472384Y185598D02*
Y170872D01*
G01X452192Y162552D02*
Y184000D01*
G01X449509Y464579D02*
X448871Y465217D01*
G01X449509Y463717D02*
Y464579D01*
G01X448108Y462316D02*
X449509Y463717D01*
G01X447246Y462316D02*
X448108D01*
G01X446608Y462954D02*
X447246Y462316D01*
G01X445746Y462954D02*
X446608D01*
G01X439308Y456516D02*
X445746Y462954D01*
G01X439308Y411535D02*
Y456516D01*
G01X471732Y442384D02*
X494653Y465305D01*
G01X471732Y422124D02*
Y442384D01*
G01X456632Y445475D02*
Y422124D01*
G01X467235Y456078D02*
X456632Y445475D01*
G01X467235Y456940D02*
Y456078D01*
G01X466241Y457934D02*
X467235Y456940D01*
G01X466241Y458796D02*
Y457934D01*
G01X467225Y459780D02*
X466241Y458796D01*
G01X468087Y459780D02*
X467225D01*
G01X469081Y458786D02*
X468087Y459780D01*
G01X469943Y458786D02*
X469081D01*
G01X470927Y459770D02*
X469943Y458786D01*
G01X470927Y460632D02*
Y459770D01*
G01X469933Y461626D02*
X470927Y460632D01*
G01X469933Y462488D02*
Y461626D01*
G01X470917Y463472D02*
X469933Y462488D01*
G01X471779Y463472D02*
X470917D01*
G01X472773Y462478D02*
X471779Y463472D01*
G01X473635Y462478D02*
X472773D01*
G01X474619Y463462D02*
X473635Y462478D01*
G01X474619Y464324D02*
Y463462D01*
G01X473625Y465318D02*
X474619Y464324D01*
G01X469232Y442694D02*
Y422124D01*
G01X494603Y468065D02*
X469232Y442694D01*
G01X426708Y461051D02*
X461636Y495979D01*
G01X426708Y418521D02*
Y461051D01*
G01X424208Y462094D02*
X427008Y464894D01*
G01X424208Y418511D02*
Y462094D01*
G01X436808Y456780D02*
X476992Y496964D01*
G01X436808Y411022D02*
Y456780D01*
G01X466732Y443164D02*
X501337Y477769D01*
G01X466732Y422124D02*
Y443164D01*
G01X460350Y458897D02*
X487405Y485952D01*
G01X460350Y458036D02*
Y458897D01*
G01X461343Y457043D02*
X460350Y458036D01*
G01X461343Y456181D02*
Y457043D01*
G01X460359Y455197D02*
X461343Y456181D01*
G01X459496Y455197D02*
X460359D01*
G01X458504Y456189D02*
X459496Y455197D01*
G01X457642Y456189D02*
X458504D01*
G01X456658Y455205D02*
X457642Y456189D01*
G01X456658Y454344D02*
Y455205D01*
G01X457651Y453351D02*
X456658Y454344D01*
G01X457651Y452489D02*
Y453351D01*
G01X456667Y451505D02*
X457651Y452489D01*
G01X455804Y451505D02*
X456667D01*
G01X454812Y452497D02*
X455804Y451505D01*
G01X453950Y452497D02*
X454812D01*
G01X451632Y450179D02*
X453950Y452497D01*
G01X451632Y422124D02*
Y450179D01*
G01X444318Y452214D02*
X472617Y480513D01*
G01X444318Y409681D02*
Y452214D01*
G01X441818Y453250D02*
X465480Y476912D01*
G01X441818Y410424D02*
Y453250D01*
G01X419208Y417842D02*
Y469042D01*
G01X449132Y450631D02*
X486953Y488452D01*
G01X449132Y422124D02*
Y450631D01*
G01X474292Y441708D02*
X495581Y462997D01*
G01X474292Y422184D02*
Y441708D01*
G01X474232Y422124D02*
X474292Y422184D01*
G01X421708Y418081D02*
Y468093D01*
G01X454242Y446053D02*
Y422014D01*
G01X463601Y455412D02*
X454242Y446053D01*
G01X463601Y459391D02*
Y455412D01*
G01X487865Y483655D02*
X463601Y459391D01*
G01X462449Y479657D02*
X479492Y496700D01*
G01X462449Y478795D02*
Y479657D01*
G01X463087Y478157D02*
X462449Y478795D01*
G01X463087Y477295D02*
Y478157D01*
G01X461686Y475894D02*
X463087Y477295D01*
G01X460824Y475894D02*
X461686D01*
G01X460186Y476532D02*
X460824Y475894D01*
G01X459324Y476532D02*
X460186D01*
G01X457923Y475131D02*
X459324Y476532D01*
G01X457923Y474269D02*
Y475131D01*
G01X458561Y473631D02*
X457923Y474269D01*
G01X458561Y472769D02*
Y473631D01*
G01X457160Y471368D02*
X458561Y472769D01*
G01X456298Y471368D02*
X457160D01*
G01X455660Y472006D02*
X456298Y471368D01*
G01X454798Y472006D02*
X455660D01*
G01X453397Y470605D02*
X454798Y472006D01*
G01X453397Y469743D02*
Y470605D01*
G01X454035Y469105D02*
X453397Y469743D01*
G01X454035Y468243D02*
Y469105D01*
G01X452634Y466842D02*
X454035Y468243D01*
G01X451772Y466842D02*
X452634D01*
G01X451134Y467480D02*
X451772Y466842D01*
G01X450272Y467480D02*
X451134D01*
G01X448871Y466079D02*
X450272Y467480D01*
G01X448871Y465217D02*
Y466079D01*
G01X426514Y522234D02*
Y530451D01*
G01X425720Y521440D02*
X426514Y522234D01*
G01X425720Y517772D02*
Y521440D01*
G01X427343Y516149D02*
X425720Y517772D01*
G01X427343Y514521D02*
Y516149D01*
G01X425912Y513090D02*
X427343Y514521D01*
G01X425912Y511830D02*
Y513090D01*
G01X426892Y510850D02*
X425912Y511830D01*
G01X426892Y506735D02*
Y510850D01*
G01X429789Y519703D02*
Y533103D01*
G01X430127Y519365D02*
X429789Y519703D01*
G01X430127Y517135D02*
Y519365D01*
G01X429392Y516400D02*
X430127Y517135D01*
G01X429392Y514700D02*
Y516400D01*
G01X429992Y514100D02*
X429392Y514700D01*
G01X429992Y511400D02*
Y514100D01*
G01X428992Y510400D02*
X429992Y511400D01*
G01X428992Y506006D02*
Y510400D01*
G01X420222Y491578D02*
Y487856D01*
G01X436328Y507684D02*
X420222Y491578D01*
G01X436328Y511336D02*
Y507684D01*
G01X436692Y511700D02*
X436328Y511336D01*
G01X436692Y514000D02*
Y511700D01*
G01X436292Y514400D02*
X436692Y514000D01*
G01X436292Y516500D02*
Y514400D01*
G01X436692Y516900D02*
X436292Y516500D01*
G01X436692Y519500D02*
Y516900D01*
G01X436519Y519673D02*
X436692Y519500D01*
G01X436519Y532873D02*
Y519673D01*
G01X418222Y492407D02*
Y488630D01*
G01X433280Y507465D02*
X418222Y492407D01*
G01X433280Y511112D02*
Y507465D01*
G01X432892Y511500D02*
X433280Y511112D01*
G01X432892Y513900D02*
Y511500D01*
G01X433364Y514372D02*
X432892Y513900D01*
G01X433364Y516728D02*
Y514372D01*
G01X432916Y517176D02*
X433364Y516728D01*
G01X432916Y519424D02*
Y517176D01*
G01X433213Y519721D02*
X432916Y519424D01*
G01X433213Y530179D02*
Y519721D01*
G01X473625Y466180D02*
Y465318D01*
G01X474609Y467164D02*
X473625Y466180D01*
G01X475471Y467164D02*
X474609D01*
G01X476465Y466170D02*
X475471Y467164D01*
G01X477327Y466170D02*
X476465D01*
G01X478311Y467154D02*
X477327Y466170D01*
G01X477317Y469010D02*
X478311Y468016D01*
G01X477317Y469872D02*
Y469010D01*
G01X478301Y470856D02*
X477317Y469872D01*
G01X464450Y526454D02*
X462833Y528071D01*
G01X464450Y525261D02*
Y526454D01*
G01X463840Y524651D02*
X464450Y525261D01*
G01X461905Y524651D02*
X463840D01*
G01X461268Y524014D02*
X461905Y524651D01*
G01X461268Y522624D02*
Y524014D01*
G01X461851Y522041D02*
X461268Y522624D01*
G01X463840Y522041D02*
X461851D01*
G01X464450Y521431D02*
X463840Y522041D01*
G01X464450Y520355D02*
Y521431D01*
G01X462833Y518738D02*
X464450Y520355D01*
G01X462833Y508841D02*
Y518738D01*
G01X461903Y507911D02*
X462833Y508841D01*
G01X461903Y506871D02*
Y507911D01*
G01X461342Y506310D02*
X461903Y506871D01*
G01X460422Y506310D02*
X461342D01*
G01X459862Y505750D02*
X460422Y506310D01*
G01X459862Y504631D02*
Y505750D01*
G01X460472Y504021D02*
X459862Y504631D01*
G01X462221Y504021D02*
X460472D01*
G01X462831Y503411D02*
X462221Y504021D01*
G01X462831Y502021D02*
Y503411D01*
G01X462221Y501411D02*
X462831Y502021D01*
G01X462196Y501411D02*
X462221D01*
G01X461636Y500851D02*
X462196Y501411D01*
G01X461636Y495979D02*
Y500851D01*
G01X459093Y520040D02*
Y526801D01*
G01X460133Y519000D02*
X459093Y520040D01*
G01X460133Y517457D02*
Y519000D01*
G01X458983Y516307D02*
X460133Y517457D01*
G01X458983Y512057D02*
Y516307D01*
G01X460333Y510707D02*
X458983Y512057D01*
G01X460333Y509641D02*
Y510707D01*
G01X457714Y507022D02*
X460333Y509641D01*
G01X457714Y495600D02*
Y507022D01*
G01X434927Y472813D02*
X457714Y495600D01*
G01X433797Y472813D02*
X434927D01*
G01X432629Y473981D02*
X433797Y472813D01*
G01X431498Y473981D02*
X432629D01*
G01X430365Y472848D02*
X431498Y473981D01*
G01X430365Y471718D02*
Y472848D01*
G01X431534Y470549D02*
X430365Y471718D01*
G01X431534Y469420D02*
Y470549D01*
G01X430401Y468287D02*
X431534Y469420D01*
G01X429271Y468287D02*
X430401D01*
G01X428421Y469137D02*
X429271Y468287D01*
G01X427264Y469137D02*
X428421D01*
G01X426131Y468004D02*
X427264Y469137D01*
G01X426131Y466900D02*
Y468004D01*
G01X427008Y466023D02*
X426131Y466900D01*
G01X427008Y464894D02*
Y466023D01*
G01X446485Y520062D02*
Y530307D01*
G01X446797Y519750D02*
X446485Y520062D01*
G01X446797Y514505D02*
Y519750D01*
G01X445892Y513600D02*
X446797Y514505D01*
G01X445892Y511800D02*
Y513600D01*
G01X446797Y510895D02*
X445892Y511800D01*
G01X446797Y505835D02*
Y510895D01*
G01X416692Y516800D02*
Y527600D01*
G01X416892Y511800D02*
Y513900D01*
G01X476692Y519841D02*
Y527800D01*
G01X477392Y519141D02*
X476692Y519841D01*
G01X477392Y517500D02*
Y519141D01*
G01X475992Y516100D02*
X477392Y517500D01*
G01X475992Y512000D02*
Y516100D01*
G01X476992Y511000D02*
X475992Y512000D01*
G01X476992Y496964D02*
Y511000D01*
G01X477167Y487901D02*
X478155Y486913D01*
G01X476305Y487901D02*
X477167D01*
G01X475321Y486917D02*
X476305Y487901D01*
G01X475321Y486055D02*
Y486917D01*
G01X476309Y485067D02*
X475321Y486055D01*
G01X476309Y484205D02*
Y485067D01*
G01X475325Y483221D02*
X476309Y484205D01*
G01X474463Y483221D02*
X475325D01*
G01X473475Y484209D02*
X474463Y483221D01*
G01X472613Y484209D02*
X473475D01*
G01X471629Y483225D02*
X472613Y484209D01*
G01X471629Y482363D02*
Y483225D01*
G01X472617Y481375D02*
X471629Y482363D01*
G01X472617Y480513D02*
Y481375D01*
G01X465480Y479788D02*
X482192Y496500D01*
G01X465480Y476912D02*
Y479788D01*
G01X453533Y517407D02*
Y529359D01*
G01X452633Y516507D02*
X453533Y517407D01*
G01X452633Y511757D02*
Y516507D01*
G01X453374Y511016D02*
X452633Y511757D01*
G01X453374Y503208D02*
Y511016D01*
G01X419208Y469042D02*
X453374Y503208D01*
G01X439810Y516682D02*
Y530682D01*
G01X440292Y516200D02*
X439810Y516682D01*
G01X440292Y514400D02*
Y516200D01*
G01X439273Y513381D02*
X440292Y514400D01*
G01X439273Y512019D02*
Y513381D01*
G01X440372Y510920D02*
X439273Y512019D01*
G01X440372Y508899D02*
Y510920D01*
G01X422222Y490749D02*
X440372Y508899D01*
G01X422222Y487139D02*
Y490749D01*
G01X443240Y519552D02*
Y530548D01*
G01X443333Y519459D02*
X443240Y519552D01*
G01X443333Y516941D02*
Y519459D01*
G01X443080Y516688D02*
X443333Y516941D01*
G01X443080Y514112D02*
Y516688D01*
G01X443333Y513859D02*
X443080Y514112D01*
G01X443333Y511641D02*
Y513859D01*
G01X442592Y510900D02*
X443333Y511641D01*
G01X442592Y504292D02*
Y510900D01*
G01X423092Y519600D02*
Y530400D01*
G01X423392Y519300D02*
X423092Y519600D01*
G01X423392Y516800D02*
Y519300D01*
G01X422892Y516300D02*
X423392Y516800D01*
G01X422892Y514400D02*
Y516300D01*
G01X423592Y513700D02*
X422892Y514400D01*
G01X423592Y512200D02*
Y513700D01*
G01X422647Y511255D02*
X423592Y512200D01*
G01X422647Y505319D02*
Y511255D01*
G01X419555Y516937D02*
Y527563D01*
G01X419935Y516557D02*
X419555Y516937D01*
G01X419935Y514343D02*
Y516557D01*
G01X419494Y513902D02*
X419935Y514343D01*
G01X419494Y511598D02*
Y513902D01*
G01X419862Y511230D02*
X419494Y511598D01*
G01X419862Y505363D02*
Y511230D01*
G01X456592Y519459D02*
Y527300D01*
G01X456233Y519100D02*
X456592Y519459D01*
G01X456233Y517457D02*
Y519100D01*
G01X456483Y517207D02*
X456233Y517457D01*
G01X456483Y511791D02*
Y517207D01*
G01X455492Y510800D02*
X456483Y511791D01*
G01X455492Y496978D02*
Y510800D01*
G01X439883Y481369D02*
X455492Y496978D01*
G01X438884Y481369D02*
X439883D01*
G01X437500Y482753D02*
X438884Y481369D01*
G01X436368Y482753D02*
X437500D01*
G01X435274Y481659D02*
X436368Y482753D01*
G01X435274Y480527D02*
Y481659D01*
G01X436492Y479309D02*
X435274Y480527D01*
G01X436492Y478077D02*
Y479309D01*
G01X435461Y477046D02*
X436492Y478077D01*
G01X434229Y477046D02*
X435461D01*
G01X433011Y478264D02*
X434229Y477046D01*
G01X431879Y478264D02*
X433011D01*
G01X421708Y468093D02*
X431879Y478264D01*
G01X476070Y566699D02*
X474998D01*
G01X476770Y565999D02*
X476070Y566699D01*
G01X476770Y564725D02*
Y565999D01*
G01X475633Y563588D02*
X476770Y564725D01*
G01X475633Y562512D02*
Y563588D01*
G01X476645Y561500D02*
X475633Y562512D01*
G01X476645Y560300D02*
Y561500D01*
G01X475633Y559288D02*
X476645Y560300D01*
G01X475633Y558212D02*
Y559288D01*
G01X476745Y557100D02*
X475633Y558212D01*
G01X476745Y554467D02*
Y557100D01*
G01X476570Y554292D02*
X476745Y554467D01*
G01X476570Y552600D02*
Y554292D01*
G01X478256Y550914D02*
X476570Y552600D01*
G01X431494Y553164D02*
Y555842D01*
G01X429776Y551446D02*
X431494Y553164D01*
G01X429776Y547184D02*
Y551446D01*
G01X426514Y543922D02*
X429776Y547184D01*
G01X426514Y535145D02*
Y543922D01*
G01X427012Y534647D02*
X426514Y535145D01*
G01X427012Y530949D02*
Y534647D01*
G01X426514Y530451D02*
X427012Y530949D01*
G01X436548Y565181D02*
X438189Y566822D01*
G01X436548Y554856D02*
Y565181D01*
G01X435725Y554033D02*
X436548Y554856D01*
G01X435725Y551343D02*
Y554033D01*
G01X433213Y548831D02*
X435725Y551343D01*
G01X433213Y546521D02*
Y548831D01*
G01X429760Y543068D02*
X433213Y546521D01*
G01X429760Y533132D02*
Y543068D01*
G01X429789Y533103D02*
X429760Y533132D01*
G01X436475Y532917D02*
X436519Y532873D01*
G01X436475Y543483D02*
Y532917D01*
G01X439810Y546818D02*
X436475Y543483D01*
G01X439810Y551418D02*
Y546818D01*
G01X443248Y554856D02*
X439810Y551418D01*
G01X443248Y557244D02*
Y554856D01*
G01X443092Y557400D02*
X443248Y557244D01*
G01X443092Y565034D02*
Y557400D01*
G01X444880Y566822D02*
X443092Y565034D01*
G01X431773Y531619D02*
X433213Y530179D01*
G01X431773Y534373D02*
Y531619D01*
G01X433227Y535827D02*
X431773Y534373D01*
G01X433227Y543535D02*
Y535827D01*
G01X436504Y546812D02*
X433227Y543535D01*
G01X436504Y549112D02*
Y546812D01*
G01X438187Y550795D02*
X436504Y549112D01*
G01X438187Y555859D02*
Y550795D01*
G01X459246Y566699D02*
X458266D01*
G01X459845Y566100D02*
X459246Y566699D01*
G01X459845Y564900D02*
Y566100D01*
G01X458901Y563956D02*
X459845Y564900D01*
G01X458901Y562744D02*
Y563956D01*
G01X459745Y561900D02*
X458901Y562744D01*
G01X459745Y560200D02*
Y561900D01*
G01X458901Y559356D02*
X459745Y560200D01*
G01X458901Y557936D02*
Y559356D01*
G01X460045Y556792D02*
X458901Y557936D01*
G01X460045Y555199D02*
Y556792D01*
G01X459138Y554292D02*
X460045Y555199D01*
G01X459138Y552600D02*
Y554292D01*
G01X460824Y550914D02*
X459138Y552600D01*
G01X460912Y550914D02*
X460824D01*
G01X460912Y550564D02*
Y550914D01*
G01X462833Y548643D02*
X460912Y550564D01*
G01X462833Y547159D02*
Y548643D01*
G01X464530Y545462D02*
X462833Y547159D01*
G01X464530Y544301D02*
Y545462D01*
G01X463920Y543691D02*
X464530Y544301D01*
G01X461613Y543691D02*
X463920D01*
G01X461003Y543081D02*
X461613Y543691D01*
G01X461003Y541691D02*
Y543081D01*
G01X461613Y541081D02*
X461003Y541691D01*
G01X463920Y541081D02*
X461613D01*
G01X464530Y540471D02*
X463920Y541081D01*
G01X464530Y539437D02*
Y540471D01*
G01X462833Y537740D02*
X464530Y539437D01*
G01X462833Y528071D02*
Y537740D01*
G01X459746Y572500D02*
X460912D01*
G01X456561Y569315D02*
X459746Y572500D01*
G01X456561Y557662D02*
Y569315D01*
G01X458266Y555957D02*
X456561Y557662D01*
G01X456833Y554524D02*
X458266Y555957D01*
G01X456833Y552007D02*
Y554524D01*
G01X460183Y548657D02*
X456833Y552007D01*
G01X460183Y546991D02*
Y548657D01*
G01X458802Y545610D02*
X460183Y546991D01*
G01X458802Y539381D02*
Y545610D01*
G01X460183Y538000D02*
X458802Y539381D01*
G01X460183Y536491D02*
Y538000D01*
G01X459033Y535341D02*
X460183Y536491D01*
G01X459033Y530559D02*
Y535341D01*
G01X460133Y529459D02*
X459033Y530559D01*
G01X460133Y527841D02*
Y529459D01*
G01X459093Y526801D02*
X460133Y527841D01*
G01X444880Y574755D02*
X444882Y574757D01*
G01X444880Y569712D02*
Y574755D01*
G01X447292Y567300D02*
X444880Y569712D01*
G01X447292Y557800D02*
Y567300D01*
G01X446792Y557300D02*
X447292Y557800D01*
G01X446792Y552200D02*
Y557300D01*
G01X445792Y551200D02*
X446792Y552200D01*
G01X445792Y549700D02*
Y551200D01*
G01X446992Y548500D02*
X445792Y549700D01*
G01X446992Y539200D02*
Y548500D01*
G01X446570Y538778D02*
X446992Y539200D01*
G01X446570Y530392D02*
Y538778D01*
G01X446485Y530307D02*
X446570Y530392D01*
G01X423120Y565126D02*
X424801Y566807D01*
G01X423120Y555016D02*
Y565126D01*
G01X421931Y553827D02*
X423120Y555016D01*
G01X420681Y553827D02*
X421931D01*
G01X419592Y552738D02*
X420681Y553827D01*
G01X419592Y549400D02*
Y552738D01*
G01X419813Y549179D02*
X419592Y549400D01*
G01X419813Y546621D02*
Y549179D01*
G01X473293Y567849D02*
X478344Y572900D01*
G01X473293Y557662D02*
Y567849D01*
G01X474998Y555957D02*
X473293Y557662D01*
G01X474333Y555292D02*
X474998Y555957D01*
G01X474333Y551721D02*
Y555292D01*
G01X477233Y548821D02*
X474333Y551721D01*
G01X477233Y547041D02*
Y548821D01*
G01X476667Y546475D02*
X477233Y547041D01*
G01X476667Y538266D02*
Y546475D01*
G01X477233Y537700D02*
X476667Y538266D01*
G01X477233Y536742D02*
Y537700D01*
G01X475592Y535101D02*
X477233Y536742D01*
G01X475592Y531000D02*
Y535101D01*
G01X477176Y529416D02*
X475592Y531000D01*
G01X477176Y528284D02*
Y529416D01*
G01X476692Y527800D02*
X477176Y528284D01*
G01X453545Y572500D02*
X454533D01*
G01X450490Y569445D02*
X453545Y572500D01*
G01X450490Y568257D02*
Y569445D01*
G01X449868Y567635D02*
X450490Y568257D01*
G01X449868Y557662D02*
Y567635D01*
G01X451573Y555957D02*
X449868Y557662D01*
G01X451031Y555415D02*
X451573Y555957D01*
G01X451031Y551109D02*
Y555415D01*
G01X453483Y548657D02*
X451031Y551109D01*
G01X453483Y536142D02*
Y548657D01*
G01X452702Y535361D02*
X453483Y536142D01*
G01X452702Y530190D02*
Y535361D01*
G01X453533Y529359D02*
X452702Y530190D01*
G01X444880Y553164D02*
Y555859D01*
G01X443263Y551547D02*
X444880Y553164D01*
G01X443263Y546771D02*
Y551547D01*
G01X439795Y543303D02*
X443263Y546771D01*
G01X439795Y530697D02*
Y543303D01*
G01X439810Y530682D02*
X439795Y530697D01*
G01X444880Y545388D02*
Y547922D01*
G01X443263Y543771D02*
X444880Y545388D01*
G01X443263Y530571D02*
Y543771D01*
G01X443240Y530548D02*
X443263Y530571D01*
G01X429871Y565184D02*
X431494Y566807D01*
G01X429871Y555023D02*
Y565184D01*
G01X426092Y551244D02*
X429871Y555023D01*
G01X426092Y549400D02*
Y551244D01*
G01X426528Y548964D02*
X426092Y549400D01*
G01X426528Y546836D02*
Y548964D01*
G01X423076Y543384D02*
X426528Y546836D01*
G01X423076Y535606D02*
Y543384D01*
G01X423492Y535190D02*
X423076Y535606D01*
G01X423492Y530800D02*
Y535190D01*
G01X423092Y530400D02*
X423492Y530800D01*
G01X424801Y553262D02*
Y555842D01*
G01X423992Y552453D02*
X424801Y553262D01*
G01X423992Y549800D02*
Y552453D01*
G01X423090Y548898D02*
X423992Y549800D01*
G01X423090Y546898D02*
Y548898D01*
G01X419829Y543637D02*
X423090Y546898D01*
G01X419829Y535563D02*
Y543637D01*
G01X419592Y535326D02*
X419829Y535563D01*
G01X419592Y530200D02*
Y535326D01*
G01X419829Y529963D02*
X419592Y530200D01*
G01X419829Y527837D02*
Y529963D01*
G01X419555Y527563D02*
X419829Y527837D01*
G01X452645Y566699D02*
X451573D01*
G01X453245Y566099D02*
X452645Y566699D01*
G01X453245Y565201D02*
Y566099D01*
G01X452208Y564164D02*
X453245Y565201D01*
G01X452208Y562936D02*
Y564164D01*
G01X453145Y561999D02*
X452208Y562936D01*
G01X453145Y560601D02*
Y561999D01*
G01X452208Y559664D02*
X453145Y560601D01*
G01X452208Y558336D02*
Y559664D01*
G01X453345Y557199D02*
X452208Y558336D01*
G01X453345Y555300D02*
Y557199D01*
G01X452845Y554800D02*
X453345Y555300D01*
G01X452845Y552600D02*
Y554800D01*
G01X454531Y550914D02*
X452845Y552600D01*
G01X454619Y550914D02*
X454531D01*
G01X456133Y549400D02*
X454619Y550914D01*
G01X456133Y546959D02*
Y549400D01*
G01X456592Y546500D02*
X456133Y546959D01*
G01X456592Y538059D02*
Y546500D01*
G01X456133Y537600D02*
X456592Y538059D01*
G01X456133Y535456D02*
Y537600D01*
G01X456733Y534856D02*
X456133Y535456D01*
G01X456733Y530697D02*
Y534856D01*
G01X456233Y530197D02*
X456733Y530697D01*
G01X456233Y527659D02*
Y530197D01*
G01X456592Y527300D02*
X456233Y527659D01*
G01X495794Y29597D02*
Y34203D01*
G01X496944Y28447D02*
X495794Y29597D01*
G01X496944Y26653D02*
Y28447D01*
G01X495077Y24786D02*
X496944Y26653D01*
G01X495077Y17157D02*
Y24786D01*
G01X517444Y29499D02*
Y34447D01*
G01X516344Y28399D02*
X517444Y29499D01*
G01X516344Y18792D02*
Y28399D01*
G01X513244Y15692D02*
X516344Y18792D01*
G01X513244Y14025D02*
Y15692D01*
G01X515155Y12114D02*
X513244Y14025D01*
G01X489444Y29347D02*
Y34299D01*
G01X490344Y28447D02*
X489444Y29347D01*
G01X490344Y27216D02*
Y28447D01*
G01X488384Y25256D02*
X490344Y27216D01*
G01X488384Y17157D02*
Y25256D01*
G01X535167Y31900D02*
X536623Y33356D01*
G01X533767Y31900D02*
X535167D01*
G01X531888Y30021D02*
X533767Y31900D01*
G01X531888Y27899D02*
Y30021D01*
G01X519944Y14018D02*
X521848Y12114D01*
G01X519944Y15614D02*
Y14018D01*
G01X523294Y18964D02*
X519944Y15614D01*
G01X523294Y28699D02*
Y18964D01*
G01X523844Y29249D02*
X523294Y28699D01*
G01X523844Y34547D02*
Y29249D01*
G01X513244Y29099D02*
Y34751D01*
G01X513844Y28499D02*
X513244Y29099D01*
G01X513844Y20052D02*
Y28499D01*
G01X511809Y18017D02*
X513844Y20052D01*
G01X511809Y17157D02*
Y18017D01*
G01X480345Y33500D02*
X478545Y31700D01*
G01X499644Y25853D02*
Y114456D01*
G01X497184Y23393D02*
X499644Y25853D01*
G01X497184Y16692D02*
Y23393D01*
G01X495861Y15369D02*
X497184Y16692D01*
G01X495861Y13976D02*
Y15369D01*
G01X497723Y12114D02*
X495861Y13976D01*
G01X482938Y29146D02*
X481691Y27899D01*
G01X482938Y30400D02*
Y29146D01*
G01X484238Y31700D02*
X482938Y30400D01*
G01X485238Y31700D02*
X484238D01*
G01X487038Y33500D02*
X485238Y31700D01*
G01X520744Y19399D02*
X518502Y17157D01*
G01X520744Y28199D02*
Y19399D01*
G01X519944Y28999D02*
X520744Y28199D01*
G01X519944Y34851D02*
Y28999D01*
G01X493294Y28849D02*
Y35049D01*
G01X493277Y28832D02*
X493294Y28849D01*
G01X493277Y26453D02*
Y28832D01*
G01X491192Y24368D02*
X493277Y26453D01*
G01X491192Y17262D02*
Y24368D01*
G01X489444Y15514D02*
X491192Y17262D01*
G01X489444Y14100D02*
Y15514D01*
G01X491430Y12114D02*
X489444Y14100D01*
G01X528666Y31700D02*
X530242Y33276D01*
G01X527442Y31700D02*
X528666D01*
G01X526192Y30450D02*
X527442Y31700D01*
G01X526192Y28896D02*
Y30450D01*
G01X525195Y27899D02*
X526192Y28896D01*
G01X497144Y92264D02*
Y104796D01*
G01X495794Y90914D02*
X497144Y92264D01*
G01X495794Y86714D02*
Y90914D01*
G01X497144Y85364D02*
X495794Y86714D01*
G01X497144Y73453D02*
Y85364D01*
G01X495794Y72103D02*
X497144Y73453D01*
G01X495794Y67397D02*
Y72103D01*
G01X497144Y66047D02*
X495794Y67397D01*
G01X497144Y54452D02*
Y66047D01*
G01X495794Y53102D02*
X497144Y54452D01*
G01X495794Y48914D02*
Y53102D01*
G01X497144Y47564D02*
X495794Y48914D01*
G01X497144Y35553D02*
Y47564D01*
G01X495794Y34203D02*
X497144Y35553D01*
G01X516392Y91966D02*
Y105400D01*
G01X517344Y91014D02*
X516392Y91966D01*
G01X517344Y86514D02*
Y91014D01*
G01X516544Y85714D02*
X517344Y86514D01*
G01X516544Y72947D02*
Y85714D01*
G01X517444Y72047D02*
X516544Y72947D01*
G01X517444Y67299D02*
Y72047D01*
G01X516644Y66499D02*
X517444Y67299D01*
G01X516644Y53914D02*
Y66499D01*
G01X517344Y53214D02*
X516644Y53914D01*
G01X517344Y48714D02*
Y53214D01*
G01X516544Y47914D02*
X517344Y48714D01*
G01X516544Y35347D02*
Y47914D01*
G01X517444Y34447D02*
X516544Y35347D01*
G01X490492Y92262D02*
Y105200D01*
G01X489444Y91214D02*
X490492Y92262D01*
G01X489444Y86414D02*
Y91214D01*
G01X490444Y85414D02*
X489444Y86414D01*
G01X490444Y73099D02*
Y85414D01*
G01X489444Y72099D02*
X490444Y73099D01*
G01X489444Y67147D02*
Y72099D01*
G01X490344Y66247D02*
X489444Y67147D01*
G01X490344Y54314D02*
Y66247D01*
G01X489444Y53414D02*
X490344Y54314D01*
G01X489444Y48614D02*
Y53414D01*
G01X490444Y47614D02*
X489444Y48614D01*
G01X490444Y35299D02*
Y47614D01*
G01X489444Y34299D02*
X490444Y35299D01*
G01X536447Y63266D02*
Y105051D01*
G01X534316Y61135D02*
X536447Y63266D01*
G01X534316Y54924D02*
Y61135D01*
G01X532792Y53400D02*
X534316Y54924D01*
G01X532792Y51656D02*
Y53400D01*
G01X534534Y49914D02*
X532792Y51656D01*
G01X536007Y48441D02*
X534534Y49914D01*
G01X536007Y35316D02*
Y48441D01*
G01X536623Y34700D02*
X536007Y35316D01*
G01X536623Y33356D02*
Y34700D01*
G01X483470Y35667D02*
X485037Y34100D01*
G01X483470Y36868D02*
Y35667D01*
G01X482112Y38226D02*
X483470Y36868D01*
G01X482112Y39599D02*
Y38226D01*
G01X483312Y40799D02*
X482112Y39599D01*
G01X483312Y41925D02*
Y40799D01*
G01X482112Y43125D02*
X483312Y41925D01*
G01X482112Y44700D02*
Y43125D01*
G01X483912Y46500D02*
X482112Y44700D01*
G01X483912Y47558D02*
Y46500D01*
G01X480570Y50900D02*
X483912Y47558D01*
G01X480570Y53836D02*
Y50900D01*
G01X481691Y54957D02*
X480570Y53836D01*
G01X481691Y55577D02*
Y54957D01*
G01X483933Y57819D02*
X481691Y55577D01*
G01X483933Y66003D02*
Y57819D01*
G01X483133Y66803D02*
X483933Y66003D01*
G01X483133Y72541D02*
Y66803D01*
G01X483633Y73041D02*
X483133Y72541D01*
G01X483633Y85818D02*
Y73041D01*
G01X483033Y86418D02*
X483633Y85818D01*
G01X483033Y91118D02*
Y86418D01*
G01X483983Y92068D02*
X483033Y91118D01*
G01X483983Y96105D02*
Y92068D01*
G01X523244Y35147D02*
X523844Y34547D01*
G01X523244Y48114D02*
Y35147D01*
G01X523944Y48814D02*
X523244Y48114D01*
G01X523944Y53214D02*
Y48814D01*
G01X523294Y53864D02*
X523944Y53214D01*
G01X523294Y66499D02*
Y53864D01*
G01X523844Y67049D02*
X523294Y66499D01*
G01X523844Y72447D02*
Y67049D01*
G01X523244Y73047D02*
X523844Y72447D01*
G01X523244Y85914D02*
Y73047D01*
G01X523944Y86614D02*
X523244Y85914D01*
G01X523944Y91274D02*
Y86614D01*
G01X523292Y91926D02*
X523944Y91274D01*
G01X523292Y105600D02*
Y91926D01*
G01X531888Y61357D02*
Y54957D01*
G01X533797Y63266D02*
X531888Y61357D01*
G01X533797Y66202D02*
Y63266D01*
G01X532566Y67433D02*
X533797Y66202D01*
G01X532566Y72074D02*
Y67433D01*
G01X533866Y73374D02*
X532566Y72074D01*
G01X533866Y85305D02*
Y73374D01*
G01X532692Y86479D02*
X533866Y85305D01*
G01X532692Y91099D02*
Y86479D01*
G01X533697Y92104D02*
X532692Y91099D01*
G01X533697Y104924D02*
Y92104D01*
G01X533667Y34567D02*
X534534Y33700D01*
G01X533667Y36868D02*
Y34567D01*
G01X532034Y38501D02*
X533667Y36868D01*
G01X532034Y39800D02*
Y38501D01*
G01X533384Y41150D02*
X532034Y39800D01*
G01X533384Y42050D02*
Y41150D01*
G01X532134Y43300D02*
X533384Y42050D01*
G01X532134Y44499D02*
Y43300D01*
G01X533667Y46032D02*
X532134Y44499D01*
G01X533667Y48000D02*
Y46032D01*
G01X530767Y50900D02*
X533667Y48000D01*
G01X530767Y53836D02*
Y50900D01*
G01X531888Y54957D02*
X530767Y53836D01*
G01X513892Y91862D02*
Y105000D01*
G01X513244Y91214D02*
X513892Y91862D01*
G01X513244Y86514D02*
Y91214D01*
G01X514044Y85714D02*
X513244Y86514D01*
G01X514044Y82136D02*
Y85714D01*
G01X512792Y80884D02*
X514044Y82136D01*
G01X512792Y78936D02*
Y80884D01*
G01X514044Y77684D02*
X512792Y78936D01*
G01X514044Y73251D02*
Y77684D01*
G01X513244Y72451D02*
X514044Y73251D01*
G01X513244Y66899D02*
Y72451D01*
G01X513644Y66499D02*
X513244Y66899D01*
G01X513644Y63399D02*
Y66499D01*
G01X512492Y62247D02*
X513644Y63399D01*
G01X512492Y60199D02*
Y62247D01*
G01X513644Y59047D02*
X512492Y60199D01*
G01X513644Y53814D02*
Y59047D01*
G01X513244Y53414D02*
X513644Y53814D01*
G01X513244Y48714D02*
Y53414D01*
G01X514044Y47914D02*
X513244Y48714D01*
G01X514044Y45973D02*
Y47914D01*
G01X512692Y44621D02*
X514044Y45973D01*
G01X512692Y42773D02*
Y44621D01*
G01X514044Y41421D02*
X512692Y42773D01*
G01X514044Y35551D02*
Y41421D01*
G01X513244Y34751D02*
X514044Y35551D01*
G01X480345Y34900D02*
Y33500D01*
G01X479733Y35512D02*
X480345Y34900D01*
G01X479733Y48525D02*
Y35512D01*
G01X478344Y49914D02*
X479733Y48525D01*
G01X479891Y66511D02*
Y57640D01*
G01X480633Y67253D02*
X479891Y66511D01*
G01X480633Y72159D02*
Y67253D01*
G01X479733Y73059D02*
X480633Y72159D01*
G01X479733Y85718D02*
Y73059D01*
G01X480533Y86518D02*
X479733Y85718D01*
G01X480533Y91018D02*
Y86518D01*
G01X479891Y91660D02*
X480533Y91018D01*
G01X479891Y94501D02*
Y91660D01*
G01X478392Y96000D02*
X479891Y94501D01*
G01X527067Y34788D02*
X528155Y33700D01*
G01X527067Y37124D02*
Y34788D01*
G01X525634Y38557D02*
X527067Y37124D01*
G01X525634Y39642D02*
Y38557D01*
G01X525971Y39979D02*
X525634Y39642D01*
G01X526571Y39979D02*
X525971D01*
G01X527134Y40542D02*
X526571Y39979D01*
G01X527134Y42258D02*
Y40542D01*
G01X526721Y42671D02*
X527134Y42258D01*
G01X526021Y42671D02*
X526721D01*
G01X525684Y43008D02*
X526021Y42671D01*
G01X525684Y44493D02*
Y43008D01*
G01X527067Y45876D02*
X525684Y44493D01*
G01X527067Y48101D02*
Y45876D01*
G01X526292Y48876D02*
X527067Y48101D01*
G01X526292Y53860D02*
Y48876D01*
G01X525195Y54957D02*
X526292Y53860D01*
G01X525195Y56903D02*
Y54957D01*
G01X527097Y58805D02*
X525195Y56903D01*
G01X527097Y66295D02*
Y58805D01*
G01X526247Y67145D02*
X527097Y66295D01*
G01X526247Y72109D02*
Y67145D01*
G01X527097Y72959D02*
X526247Y72109D01*
G01X527097Y85574D02*
Y72959D01*
G01X526382Y86290D02*
X527097Y85574D01*
G01X526247Y86424D02*
X526382Y86290D01*
G01X526247Y91156D02*
Y86424D01*
G01X527097Y92006D02*
X526247Y91156D01*
G01X527097Y105074D02*
Y92006D01*
G01X487038Y34900D02*
Y33500D01*
G01X486426Y35512D02*
X487038Y34900D01*
G01X486426Y48525D02*
Y35512D01*
G01X485037Y49914D02*
X486426Y48525D01*
G01X483133Y51818D02*
X485037Y49914D01*
G01X483133Y53418D02*
Y51818D01*
G01X486483Y56768D02*
X483133Y53418D01*
G01X486483Y66503D02*
Y56768D01*
G01X487033Y67053D02*
X486483Y66503D01*
G01X487033Y72459D02*
Y67053D01*
G01X486433Y73059D02*
X487033Y72459D01*
G01X486433Y85918D02*
Y73059D01*
G01X487133Y86618D02*
X486433Y85918D01*
G01X487133Y91018D02*
Y86618D01*
G01X486483Y91668D02*
X487133Y91018D01*
G01X486483Y110209D02*
Y91668D01*
G01X520444Y35351D02*
X519944Y34851D01*
G01X520444Y39447D02*
Y35351D01*
G01X518992Y40899D02*
X520444Y39447D01*
G01X518992Y42647D02*
Y40899D01*
G01X520444Y44099D02*
X518992Y42647D01*
G01X520444Y48014D02*
Y44099D01*
G01X519844Y48614D02*
X520444Y48014D01*
G01X519844Y53314D02*
Y48614D01*
G01X520794Y54264D02*
X519844Y53314D01*
G01X520794Y65949D02*
Y54264D01*
G01X519992Y66751D02*
X520794Y65949D01*
G01X519992Y72599D02*
Y66751D01*
G01X520444Y73051D02*
X519992Y72599D01*
G01X520444Y85814D02*
Y73051D01*
G01X519844Y86414D02*
X520444Y85814D01*
G01X519844Y91114D02*
Y86414D01*
G01X520844Y92114D02*
X519844Y91114D01*
G01X520844Y104548D02*
Y92114D01*
G01X493127Y91581D02*
Y105961D01*
G01X493230Y91478D02*
X493127Y91581D01*
G01X493230Y86400D02*
Y91478D01*
G01X492944Y86114D02*
X493230Y86400D01*
G01X492944Y73199D02*
Y86114D01*
G01X493294Y72849D02*
X492944Y73199D01*
G01X493294Y66649D02*
Y72849D01*
G01X493044Y66399D02*
X493294Y66649D01*
G01X493044Y53864D02*
Y66399D01*
G01X493294Y53614D02*
X493044Y53864D01*
G01X493294Y48664D02*
Y53614D01*
G01X492944Y48314D02*
X493294Y48664D01*
G01X492944Y35399D02*
Y48314D01*
G01X493294Y35049D02*
X492944Y35399D01*
G01X529467Y48688D02*
X528241Y49914D01*
G01X529467Y35675D02*
Y48688D01*
G01X530242Y34900D02*
X529467Y35675D01*
G01X530242Y33276D02*
Y34900D01*
G01X529897Y91474D02*
Y105658D01*
G01X530197Y91174D02*
X529897Y91474D01*
G01X530197Y86474D02*
Y91174D01*
G01X529797Y86074D02*
X530197Y86474D01*
G01X529797Y72959D02*
Y86074D01*
G01X530097Y72659D02*
X529797Y72959D01*
G01X530097Y66905D02*
Y72659D01*
G01X529292Y66100D02*
X530097Y66905D01*
G01X529292Y57300D02*
Y66100D01*
G01X528241Y56249D02*
X529292Y57300D01*
G01X528241Y49914D02*
Y56249D01*
G01X479090Y137870D02*
Y139002D01*
G01X480326Y134358D02*
X479534D01*
G01X481464Y135496D02*
X480326Y134358D01*
G01X482596Y135496D02*
X481464D01*
G01X483727Y134365D02*
X482596Y135496D01*
G01X483727Y133233D02*
Y134365D01*
G01X481095Y130601D02*
X483727Y133233D01*
G01X481095Y129469D02*
Y130601D01*
G01X497092Y113472D02*
X481095Y129469D01*
G01X497092Y111700D02*
Y113472D01*
G01X495766Y110374D02*
X497092Y111700D01*
G01X495766Y106174D02*
Y110374D01*
G01X497144Y104796D02*
X495766Y106174D01*
G01X517392Y114300D02*
Y122328D01*
G01X516392Y113300D02*
X517392Y114300D01*
G01X516392Y111648D02*
Y113300D01*
G01X517266Y110774D02*
X516392Y111648D01*
G01X517266Y106274D02*
Y110774D01*
G01X516392Y105400D02*
X517266Y106274D01*
G01X488792Y114900D02*
X488592D01*
G01X490492Y113200D02*
X488792Y114900D01*
G01X490492Y111400D02*
Y113200D01*
G01X489392Y110300D02*
X490492Y111400D01*
G01X489392Y106300D02*
Y110300D01*
G01X490492Y105200D02*
X489392Y106300D01*
G01X510533Y179915D02*
X552292Y138156D01*
G01X536447Y105051D02*
X534534Y106964D01*
G01X483183Y96905D02*
X483983Y96105D01*
G01X482102Y96905D02*
X483183D01*
G01X481542Y97465D02*
X482102Y96905D01*
G01X481542Y99545D02*
Y97465D01*
G01X482102Y100105D02*
X481542Y99545D01*
G01X483183Y100105D02*
X482102D01*
G01X483983Y100905D02*
X483183Y100105D01*
G01X483983Y109109D02*
Y100905D01*
G01X523666Y105974D02*
X523292Y105600D01*
G01X523666Y110974D02*
Y105974D01*
G01X522966Y111674D02*
X523666Y110974D01*
G01X522966Y112974D02*
Y111674D01*
G01X524592Y114600D02*
X522966Y112974D01*
G01X524592Y125900D02*
Y114600D01*
G01X511292Y139200D02*
X524592Y125900D01*
G01X509444Y139200D02*
X511292D01*
G01X531888Y106733D02*
X533697Y104924D01*
G01X531888Y112357D02*
Y106733D01*
G01X512492Y122900D02*
Y123692D01*
G01X511692Y122100D02*
X512492Y122900D01*
G01X511692Y120944D02*
Y122100D01*
G01X512492Y120144D02*
X511692Y120944D01*
G01X514932Y120144D02*
X512492D01*
G01X515492Y119584D02*
X514932Y120144D01*
G01X515492Y117504D02*
Y119584D01*
G01X514932Y116944D02*
X515492Y117504D01*
G01X512568Y116944D02*
X514932D01*
G01X511830Y116206D02*
X512568Y116944D01*
G01X511830Y115162D02*
Y116206D01*
G01X513892Y113100D02*
X511830Y115162D01*
G01X513892Y111400D02*
Y113100D01*
G01X512792Y110300D02*
X513892Y111400D01*
G01X512792Y106100D02*
Y110300D01*
G01X513892Y105000D02*
X512792Y106100D01*
G01X478392Y107100D02*
Y96000D01*
G01X479592Y108300D02*
X478392Y107100D01*
G01X479592Y109901D02*
Y108300D01*
G01X488011Y132081D02*
Y133805D01*
G01X489682Y130410D02*
X488011Y132081D01*
G01X491406Y130410D02*
X489682D01*
G01X492692Y129124D02*
X491406Y130410D01*
G01X492692Y127900D02*
Y129124D01*
G01X490392Y125600D02*
X492692Y127900D01*
G01X490392Y123708D02*
Y125600D01*
G01X499644Y114456D02*
X490392Y123708D01*
G01X526266Y105905D02*
X527097Y105074D01*
G01X526266Y111286D02*
Y105905D01*
G01X525195Y112357D02*
X526266Y111286D01*
G01X525134Y112357D02*
X525195D01*
G01X539340Y129184D02*
X540465Y130309D01*
G01X538208Y129184D02*
X539340D01*
G01X537077Y130315D02*
X538208Y129184D01*
G01X537077Y131447D02*
Y130315D01*
G01X538202Y132572D02*
X537077Y131447D01*
G01X538202Y133704D02*
Y132572D01*
G01X532192Y139714D02*
X538202Y133704D01*
G01X532192Y147648D02*
Y139714D01*
G01X505580Y174260D02*
X532192Y147648D01*
G01X539049Y136393D02*
X566392Y109050D01*
G01X539049Y137525D02*
Y136393D01*
G01X541741Y140217D02*
X539049Y137525D01*
G01X539478Y142480D02*
X540610D01*
G01X538366Y141368D02*
X539478Y142480D01*
G01X537574Y141368D02*
X538366D01*
G01X534692Y144250D02*
X537574Y141368D01*
G01X534692Y148684D02*
Y144250D01*
G01X507231Y176145D02*
X534692Y148684D01*
G01X519092Y106300D02*
X520844Y104548D01*
G01X519092Y110400D02*
Y106300D01*
G01X520466Y111774D02*
X519092Y110400D01*
G01X520466Y113774D02*
Y111774D01*
G01X522092Y115400D02*
X520466Y113774D01*
G01X522092Y121164D02*
Y115400D01*
G01X515232Y128024D02*
X522092Y121164D01*
G01X515232Y129156D02*
Y128024D01*
G01X515918Y129842D02*
X515232Y129156D01*
G01X515918Y130974D02*
Y129842D01*
G01X514787Y132105D02*
X515918Y130974D01*
G01X513655Y132105D02*
X514787D01*
G01X512969Y131419D02*
X513655Y132105D01*
G01X511837Y131419D02*
X512969D01*
G01X510706Y132550D02*
X511837Y131419D01*
G01X510706Y133682D02*
Y132550D01*
G01X511392Y134368D02*
X510706Y133682D01*
G01X511392Y135500D02*
Y134368D01*
G01X510261Y136631D02*
X511392Y135500D01*
G01X509129Y136631D02*
X510261D01*
G01X508443Y135945D02*
X509129Y136631D01*
G01X507311Y135945D02*
X508443D01*
G01X492992Y111300D02*
Y114036D01*
G01X493292Y111000D02*
X492992Y111300D01*
G01X493292Y106126D02*
Y111000D01*
G01X493127Y105961D02*
X493292Y106126D01*
G01X529897Y105658D02*
X528241Y107314D01*
G01X508882Y178030D02*
X545546Y141366D01*
G01X500937Y179915D02*
X510533D01*
G01X483787Y197065D02*
X500937Y179915D01*
G01X522157Y193345D02*
X597017Y118485D01*
G01X512596Y193345D02*
X522157D01*
G01X498491Y207450D02*
X512596Y193345D01*
G01X520506Y191460D02*
X592592Y119374D01*
G01X511815Y191460D02*
X520506D01*
G01X498410Y204865D02*
X511815Y191460D01*
G01X518855Y189575D02*
X588492Y119938D01*
G01X511033Y189575D02*
X518855D01*
G01X495508Y205100D02*
X511033Y189575D01*
G01X498594Y174260D02*
X505580D01*
G01X479552Y193302D02*
X498594Y174260D01*
G01X499375Y176145D02*
X507231D01*
G01X480885Y194635D02*
X499375Y176145D01*
G01X517792Y186917D02*
X572792Y132101D01*
G01X517016Y187690D02*
X517792Y186917D01*
G01X510252Y187690D02*
X517016D01*
G01X495527Y202415D02*
X510252Y187690D01*
G01X500156Y178030D02*
X508882D01*
G01X482292Y195894D02*
X500156Y178030D01*
G01X486492Y427000D02*
Y422864D01*
G01X487642Y428150D02*
X486492Y427000D01*
G01X507511Y428150D02*
X487642D01*
G01X543488Y464127D02*
X507511Y428150D01*
G01X513055Y415300D02*
X562019Y464264D01*
G01X502747Y415300D02*
X513055D01*
G01X501981Y414534D02*
X502747Y415300D01*
G01X511505Y419350D02*
X561915Y469760D01*
G01X499725Y419350D02*
X511505D01*
G01X498063Y417688D02*
X499725Y419350D01*
G01X507558Y450700D02*
X529400Y472542D01*
G01X496692Y450700D02*
X507558D01*
G01X484032Y438040D02*
X496692Y450700D01*
G01X484032Y423105D02*
Y438040D01*
G01X481532Y440068D02*
Y423140D01*
G01X494485Y453021D02*
X481532Y440068D01*
G01X506512Y453021D02*
X494485D01*
G01X535669Y482178D02*
X506512Y453021D01*
G01X501837Y462997D02*
X514059Y475219D01*
G01X495581Y462997D02*
X501837D01*
G01X513346Y412791D02*
X562219Y461664D01*
G01X503774Y412791D02*
X513346D01*
G01X505002Y454906D02*
X534917Y484821D01*
G01X493704Y454906D02*
X505002D01*
G01X479032Y440234D02*
X493704Y454906D01*
G01X479032Y422710D02*
Y440234D01*
G01X512355Y417400D02*
X562063Y467108D01*
G01X501311Y417400D02*
X512355D01*
G01X499913Y416002D02*
X501311Y417400D01*
G01X480292Y526200D02*
Y527500D01*
G01X479192Y525100D02*
X480292Y526200D01*
G01X479192Y523400D02*
Y525100D01*
G01X480392Y522200D02*
X479192Y523400D01*
G01X480392Y520359D02*
Y522200D01*
G01X479392Y519359D02*
X480392Y520359D01*
G01X479392Y517500D02*
Y519359D01*
G01X480892Y516000D02*
X479392Y517500D01*
G01X480892Y512416D02*
Y516000D01*
G01X479492Y511016D02*
X480892Y512416D01*
G01X479492Y496700D02*
Y511016D01*
G01X520192Y519702D02*
Y527800D01*
G01X520692Y519202D02*
X520192Y519702D01*
G01X520692Y517805D02*
Y519202D01*
G01X519944Y517057D02*
X520692Y517805D01*
G01X519944Y511657D02*
Y517057D01*
G01X520444Y511157D02*
X519944Y511657D01*
G01X520444Y497830D02*
Y511157D01*
G01X519692Y497078D02*
X520444Y497830D01*
G01X519692Y495200D02*
Y497078D01*
G01X519092Y494600D02*
X519692Y495200D01*
G01X519092Y488232D02*
Y494600D01*
G01X515550Y484690D02*
X519092Y488232D01*
G01X515550Y479838D02*
Y484690D01*
G01X501017Y465305D02*
X515550Y479838D01*
G01X494653Y465305D02*
X501017D01*
G01X530192Y519537D02*
Y527600D01*
G01X529855Y519200D02*
X530192Y519537D01*
G01X529855Y517457D02*
Y519200D01*
G01X530105Y517207D02*
X529855Y517457D01*
G01X530105Y511791D02*
Y517207D01*
G01X529755Y511441D02*
X530105Y511791D01*
G01X529755Y506040D02*
Y511441D01*
G01X528191Y504476D02*
X529755Y506040D01*
G01X528191Y493544D02*
Y504476D01*
G01X478311Y468016D02*
Y467154D01*
G01X479163Y470856D02*
X478301D01*
G01X480157Y469862D02*
X479163Y470856D01*
G01X481019Y469862D02*
X480157D01*
G01X482003Y470846D02*
X481019Y469862D01*
G01X482003Y471708D02*
Y470846D01*
G01X481009Y472702D02*
X482003Y471708D01*
G01X481009Y473564D02*
Y472702D01*
G01X489085Y481640D02*
X481009Y473564D01*
G01X492479Y481640D02*
X489085D01*
G01X499492Y488653D02*
X492479Y481640D01*
G01X499492Y499700D02*
Y488653D01*
G01X500944Y501152D02*
X499492Y499700D01*
G01X500944Y508048D02*
Y501152D01*
G01X499666Y509326D02*
X500944Y508048D01*
G01X499666Y518874D02*
Y509326D01*
G01X500092Y519300D02*
X499666Y518874D01*
G01X500092Y527600D02*
Y519300D01*
G01X495465Y468065D02*
X494603D01*
G01X496323Y467207D02*
X495465Y468065D01*
G01X497031Y467207D02*
X496323D01*
G01X498169Y468345D02*
X497031Y467207D01*
G01X498169Y469053D02*
Y468345D01*
G01X497311Y469911D02*
X498169Y469053D01*
G01X497311Y470773D02*
Y469911D01*
G01X498295Y471757D02*
X497311Y470773D01*
G01X499157Y471757D02*
X498295D01*
G01X501209Y469705D02*
X499157Y471757D01*
G01X501917Y469705D02*
X501209D01*
G01X503055Y470843D02*
X501917Y469705D01*
G01X503055Y471551D02*
Y470843D01*
G01X501003Y473603D02*
X503055Y471551D01*
G01X501003Y474465D02*
Y473603D01*
G01X502132Y475594D02*
X501003Y474465D01*
G01X508230Y475594D02*
X502132D01*
G01X513561Y480925D02*
X508230Y475594D01*
G01X513561Y486308D02*
Y480925D01*
G01X516544Y489291D02*
X513561Y486308D01*
G01X516544Y494348D02*
Y489291D01*
G01X515692Y495200D02*
X516544Y494348D01*
G01X515692Y503500D02*
Y495200D01*
G01X516544Y504352D02*
X515692Y503500D01*
G01X516544Y511257D02*
Y504352D01*
G01X517444Y512157D02*
X516544Y511257D01*
G01X517444Y516557D02*
Y512157D01*
G01X516644Y517357D02*
X517444Y516557D01*
G01X516644Y519200D02*
Y517357D01*
G01X516792Y519348D02*
X516644Y519200D01*
G01X516792Y527800D02*
Y519348D01*
G01X529400Y472542D02*
X553691Y477397D01*
G01X533592Y519763D02*
Y527600D01*
G01X533755Y519600D02*
X533592Y519763D01*
G01X533755Y517457D02*
Y519600D01*
G01X532605Y516307D02*
X533755Y517457D01*
G01X532605Y512057D02*
Y516307D01*
G01X533955Y510707D02*
X532605Y512057D01*
G01X533955Y508677D02*
Y510707D01*
G01X531888Y506610D02*
X533955Y508677D01*
G01X531888Y499483D02*
Y506610D01*
G01X530792Y498387D02*
X531888Y499483D01*
G01X526892Y519763D02*
Y527800D01*
G01X527155Y519500D02*
X526892Y519763D01*
G01X527155Y517407D02*
Y519500D01*
G01X526255Y516507D02*
X527155Y517407D01*
G01X526255Y511757D02*
Y516507D01*
G01X527255Y510757D02*
X526255Y511757D01*
G01X527255Y508241D02*
Y510757D01*
G01X524992Y505978D02*
X527255Y508241D01*
G01X524992Y498784D02*
Y505978D01*
G01X524595Y498387D02*
X524992Y498784D01*
G01X513492Y519552D02*
Y527800D01*
G01X513644Y519400D02*
X513492Y519552D01*
G01X513644Y517357D02*
Y519400D01*
G01X513244Y516957D02*
X513644Y517357D01*
G01X513244Y512057D02*
Y516957D01*
G01X514044Y511257D02*
X513244Y512057D01*
G01X514044Y505052D02*
Y511257D01*
G01X513492Y504500D02*
X514044Y505052D01*
G01X513492Y495200D02*
Y504500D01*
G01X511992Y493700D02*
X513492Y495200D01*
G01X511992Y487894D02*
Y493700D01*
G01X511493Y487395D02*
X511992Y487894D01*
G01X511493Y481721D02*
Y487395D01*
G01X507541Y477769D02*
X511493Y481721D01*
G01X501337Y477769D02*
X507541D01*
G01X543359Y482178D02*
X535669D01*
G01X493392Y520100D02*
Y527652D01*
G01X492492Y519200D02*
X493392Y520100D01*
G01X492492Y517301D02*
Y519200D01*
G01X493692Y516101D02*
X492492Y517301D01*
G01X493692Y512350D02*
Y516101D01*
G01X493066Y511724D02*
X493692Y512350D01*
G01X493066Y508726D02*
Y511724D01*
G01X495992Y505800D02*
X493066Y508726D01*
G01X495992Y502426D02*
Y505800D01*
G01X492592Y499026D02*
X495992Y502426D01*
G01X492592Y495100D02*
Y499026D01*
G01X493192Y494500D02*
X492592Y495100D01*
G01X493192Y490300D02*
Y494500D01*
G01X488844Y485952D02*
X493192Y490300D01*
G01X487405Y485952D02*
X488844D01*
G01X486692Y520001D02*
Y527900D01*
G01X486092Y519401D02*
X486692Y520001D01*
G01X486092Y517748D02*
Y519401D01*
G01X487033Y516807D02*
X486092Y517748D01*
G01X487033Y511641D02*
Y516807D01*
G01X486433Y511041D02*
X487033Y511641D01*
G01X486433Y503241D02*
Y511041D01*
G01X484692Y501500D02*
X486433Y503241D01*
G01X484692Y492588D02*
Y501500D01*
G01X482709Y490605D02*
X484692Y492588D01*
G01X481847Y490605D02*
X482709D01*
G01X480988Y491464D02*
X481847Y490605D01*
G01X480280Y491464D02*
X480988D01*
G01X479142Y490326D02*
X480280Y491464D01*
G01X479142Y489618D02*
Y490326D01*
G01X480001Y488759D02*
X479142Y489618D01*
G01X480001Y487897D02*
Y488759D01*
G01X479017Y486913D02*
X480001Y487897D01*
G01X478155Y486913D02*
X479017D01*
G01X483595Y517519D02*
Y529595D01*
G01X483197Y517121D02*
X483595Y517519D01*
G01X483197Y511495D02*
Y517121D01*
G01X483410Y511282D02*
X483197Y511495D01*
G01X483410Y508618D02*
Y511282D01*
G01X482192Y507400D02*
X483410Y508618D01*
G01X482192Y496500D02*
Y507400D01*
G01X536892Y519401D02*
Y528100D01*
G01X536455Y518964D02*
X536892Y519401D01*
G01X536455Y507641D02*
Y518964D01*
G01X533766Y504952D02*
X536455Y507641D01*
G01X533766Y494162D02*
Y504952D01*
G01X534534Y493394D02*
X533766Y494162D01*
G01X490092Y520052D02*
Y527800D01*
G01X490692Y519452D02*
X490092Y520052D01*
G01X490692Y517601D02*
Y519452D01*
G01X489444Y516353D02*
X490692Y517601D01*
G01X489444Y511797D02*
Y516353D01*
G01X490344Y510897D02*
X489444Y511797D01*
G01X490344Y509452D02*
Y510897D01*
G01X489492Y508600D02*
X490344Y509452D01*
G01X489492Y507198D02*
Y508600D01*
G01X490292Y506398D02*
X489492Y507198D01*
G01X490992Y506398D02*
X490292D01*
G01X491792Y505598D02*
X490992Y506398D01*
G01X491792Y503998D02*
Y505598D01*
G01X490992Y503198D02*
X491792Y503998D01*
G01X490292Y503198D02*
X490992D01*
G01X489492Y502398D02*
X490292Y503198D01*
G01X489492Y500852D02*
Y502398D01*
G01X490344Y500000D02*
X489492Y500852D01*
G01X490344Y495452D02*
Y500000D01*
G01X489566Y494674D02*
X490344Y495452D01*
G01X489566Y489652D02*
Y494674D01*
G01X488366Y488452D02*
X489566Y489652D01*
G01X486953Y488452D02*
X488366D01*
G01X523492Y519598D02*
Y527800D01*
G01X523294Y519400D02*
X523492Y519598D01*
G01X523294Y517357D02*
Y519400D01*
G01X523844Y516807D02*
X523294Y517357D01*
G01X523844Y512257D02*
Y516807D01*
G01X523244Y511657D02*
X523844Y512257D01*
G01X523244Y503300D02*
Y511657D01*
G01X522792Y502848D02*
X523244Y503300D01*
G01X522792Y492100D02*
Y502848D01*
G01X523398Y491494D02*
X522792Y492100D01*
G01X523398Y484837D02*
Y491494D01*
G01X522176Y483615D02*
X523398Y484837D01*
G01X521247Y483615D02*
X522176D01*
G01X520442Y484420D02*
X521247Y483615D01*
G01X519734Y484420D02*
X520442D01*
G01X518596Y483282D02*
X519734Y484420D01*
G01X518596Y482574D02*
Y483282D01*
G01X519574Y481596D02*
X518596Y482574D01*
G01X519574Y480734D02*
Y481596D01*
G01X516767Y477927D02*
X519574Y480734D01*
G01X516767Y477065D02*
Y477927D01*
G01X517342Y476490D02*
X516767Y477065D01*
G01X517342Y475782D02*
Y476490D01*
G01X516204Y474644D02*
X517342Y475782D01*
G01X515496Y474644D02*
X516204D01*
G01X514921Y475219D02*
X515496Y474644D01*
G01X514059Y475219D02*
X514921D01*
G01X534917Y484821D02*
X553097D01*
G01X489246Y483655D02*
X487865D01*
G01X495192Y489601D02*
X489246Y483655D01*
G01X495192Y493900D02*
Y489601D01*
G01X496966Y495674D02*
X495192Y493900D01*
G01X496966Y499610D02*
Y495674D01*
G01X498392Y501036D02*
X496966Y499610D01*
G01X498392Y507300D02*
Y501036D01*
G01X496966Y508726D02*
X498392Y507300D01*
G01X496966Y510885D02*
Y508726D01*
G01X495794Y512057D02*
X496966Y510885D01*
G01X495794Y516307D02*
Y512057D01*
G01X497144Y517657D02*
X495794Y516307D01*
G01X497144Y519300D02*
Y517657D01*
G01X496492Y519952D02*
X497144Y519300D01*
G01X496492Y527600D02*
Y519952D01*
G01X478344Y550914D02*
X478256D01*
G01X479690Y549568D02*
X478344Y550914D01*
G01X479733Y549568D02*
X479690D01*
G01X479733Y547059D02*
Y549568D01*
G01X480392Y546400D02*
X479733Y547059D01*
G01X480392Y544600D02*
Y546400D01*
G01X479326Y543534D02*
X480392Y544600D01*
G01X479326Y541166D02*
Y543534D01*
G01X480392Y540100D02*
X479326Y541166D01*
G01X480392Y538399D02*
Y540100D01*
G01X479733Y537740D02*
X480392Y538399D01*
G01X479733Y536159D02*
Y537740D01*
G01X480399Y535493D02*
X479733Y536159D01*
G01X480399Y530221D02*
Y535493D01*
G01X479833Y529655D02*
X480399Y530221D01*
G01X479833Y527959D02*
Y529655D01*
G01X480292Y527500D02*
X479833Y527959D01*
G01X520544Y586507D02*
X518502Y588549D01*
G01X520544Y574042D02*
Y586507D01*
G01X519644Y573142D02*
X520544Y574042D01*
G01X519644Y568397D02*
Y573142D01*
G01X520744Y567297D02*
X519644Y568397D01*
G01X520744Y566052D02*
Y567297D01*
G01X520177Y565485D02*
X520744Y566052D01*
G01X520177Y557567D02*
Y565485D01*
G01X520744Y557000D02*
X520177Y557567D01*
G01X520744Y555657D02*
Y557000D01*
G01X519944Y554857D02*
X520744Y555657D01*
G01X519944Y549457D02*
Y554857D01*
G01X520444Y548957D02*
X519944Y549457D01*
G01X520444Y546652D02*
Y548957D01*
G01X520192Y546400D02*
X520444Y546652D01*
G01X520192Y537952D02*
Y546400D01*
G01X520444Y537700D02*
X520192Y537952D01*
G01X520444Y536552D02*
Y537700D01*
G01X519844Y535952D02*
X520444Y536552D01*
G01X519844Y530238D02*
Y535952D01*
G01X520794Y529288D02*
X519844Y530238D01*
G01X520794Y528402D02*
Y529288D01*
G01X520192Y527800D02*
X520794Y528402D01*
G01X529755Y549400D02*
X528241Y550914D01*
G01X529755Y546837D02*
Y549400D01*
G01X530192Y546400D02*
X529755Y546837D01*
G01X530192Y537937D02*
Y546400D01*
G01X529755Y537500D02*
X530192Y537937D01*
G01X529755Y535456D02*
Y537500D01*
G01X530355Y534856D02*
X529755Y535456D01*
G01X530355Y530697D02*
Y534856D01*
G01X529855Y530197D02*
X530355Y530697D01*
G01X529855Y527937D02*
Y530197D01*
G01X530192Y527600D02*
X529855Y527937D01*
G01X499666Y528026D02*
X500092Y527600D01*
G01X499666Y537900D02*
Y528026D01*
G01X500092Y538326D02*
X499666Y537900D01*
G01X500092Y540400D02*
Y538326D01*
G01X498792Y541700D02*
X500092Y540400D01*
G01X498792Y543500D02*
Y541700D01*
G01X500092Y544800D02*
X498792Y543500D01*
G01X500092Y546500D02*
Y544800D01*
G01X499666Y546926D02*
X500092Y546500D01*
G01X499666Y556774D02*
Y546926D01*
G01X500092Y557200D02*
X499666Y556774D01*
G01X500092Y559000D02*
Y557200D01*
G01X499292Y559800D02*
X500092Y559000D01*
G01X499292Y562200D02*
Y559800D01*
G01X500092Y563000D02*
X499292Y562200D01*
G01X500092Y565700D02*
Y563000D01*
G01X499666Y566126D02*
X500092Y565700D01*
G01X499666Y586771D02*
Y566126D01*
G01X497723Y588714D02*
X499666Y586771D01*
G01X516644Y527948D02*
X516792Y527800D01*
G01X516644Y529650D02*
Y527948D01*
G01X517344Y530350D02*
X516644Y529650D01*
G01X517344Y535548D02*
Y530350D01*
G01X516544Y536348D02*
X517344Y535548D01*
G01X516544Y537752D02*
Y536348D01*
G01X516892Y538100D02*
X516544Y537752D01*
G01X516892Y545900D02*
Y538100D01*
G01X516544Y546248D02*
X516892Y545900D01*
G01X516544Y549057D02*
Y546248D01*
G01X517444Y549957D02*
X516544Y549057D01*
G01X517444Y554357D02*
Y549957D01*
G01X516344Y555457D02*
X517444Y554357D01*
G01X516344Y557151D02*
Y555457D01*
G01X516892Y557699D02*
X516344Y557151D01*
G01X516892Y565300D02*
Y557699D01*
G01X516644Y565548D02*
X516892Y565300D01*
G01X516644Y567597D02*
Y565548D01*
G01X517210Y568163D02*
X516644Y567597D01*
G01X517210Y573481D02*
Y568163D01*
G01X516544Y574147D02*
X517210Y573481D01*
G01X516544Y587368D02*
Y574147D01*
G01X516501Y587368D02*
X516544D01*
G01X515155Y588714D02*
X516501Y587368D01*
G01X530455Y554524D02*
X531888Y555957D01*
G01X530455Y552007D02*
Y554524D01*
G01X533805Y548657D02*
X530455Y552007D01*
G01X533805Y547313D02*
Y548657D01*
G01X533592Y547100D02*
X533805Y547313D01*
G01X533592Y538113D02*
Y547100D01*
G01X533805Y537900D02*
X533592Y538113D01*
G01X533805Y536413D02*
Y537900D01*
G01X532655Y535263D02*
X533805Y536413D01*
G01X532655Y530567D02*
Y535263D01*
G01X533755Y529467D02*
X532655Y530567D01*
G01X533755Y527763D02*
Y529467D01*
G01X533592Y527600D02*
X533755Y527763D01*
G01X527105Y547413D02*
Y548657D01*
G01X526892Y547200D02*
X527105Y547413D01*
G01X526892Y538013D02*
Y547200D01*
G01X527105Y537800D02*
X526892Y538013D01*
G01X527105Y536142D02*
Y537800D01*
G01X526107Y535144D02*
X527105Y536142D01*
G01X526107Y530485D02*
Y535144D01*
G01X527155Y529437D02*
X526107Y530485D01*
G01X527155Y528063D02*
Y529437D01*
G01X526892Y527800D02*
X527155Y528063D01*
G01X514044Y586357D02*
X511809Y588592D01*
G01X514044Y574242D02*
Y586357D01*
G01X512771Y572969D02*
X514044Y574242D01*
G01X512771Y568470D02*
Y572969D01*
G01X513844Y567397D02*
X512771Y568470D01*
G01X513844Y565952D02*
Y567397D01*
G01X513492Y565600D02*
X513844Y565952D01*
G01X513492Y557352D02*
Y565600D01*
G01X513844Y557000D02*
X513492Y557352D01*
G01X513844Y555357D02*
Y557000D01*
G01X513244Y554757D02*
X513844Y555357D01*
G01X513244Y549857D02*
Y554757D01*
G01X514044Y549057D02*
X513244Y549857D01*
G01X514044Y547552D02*
Y549057D01*
G01X513477Y546985D02*
X514044Y547552D01*
G01X513477Y538067D02*
Y546985D01*
G01X514044Y537500D02*
X513477Y538067D01*
G01X514044Y536552D02*
Y537500D01*
G01X513244Y535752D02*
X514044Y536552D01*
G01X513244Y530050D02*
Y535752D01*
G01X513644Y529650D02*
X513244Y530050D01*
G01X513644Y527952D02*
Y529650D01*
G01X513492Y527800D02*
X513644Y527952D01*
G01X491430Y586562D02*
Y588714D01*
G01X493392Y584600D02*
X491430Y586562D01*
G01X493392Y583374D02*
Y584600D01*
G01X492782Y582764D02*
X493392Y583374D01*
G01X489964Y582764D02*
X492782D01*
G01X489354Y582154D02*
X489964Y582764D01*
G01X489354Y580174D02*
Y582154D01*
G01X489964Y579564D02*
X489354Y580174D01*
G01X492782Y579564D02*
X489964D01*
G01X493392Y578954D02*
X492782Y579564D01*
G01X493392Y575848D02*
Y578954D01*
G01X492944Y575400D02*
X493392Y575848D01*
G01X492944Y573256D02*
Y575400D01*
G01X493544Y572656D02*
X492944Y573256D01*
G01X493544Y568497D02*
Y572656D01*
G01X493044Y567997D02*
X493544Y568497D01*
G01X493044Y566048D02*
Y567997D01*
G01X493392Y565700D02*
X493044Y566048D01*
G01X493392Y557548D02*
Y565700D01*
G01X492792Y556948D02*
X493392Y557548D01*
G01X492792Y555509D02*
Y556948D01*
G01X493792Y554509D02*
X492792Y555509D01*
G01X493792Y550101D02*
Y554509D01*
G01X492606Y548915D02*
X493792Y550101D01*
G01X492606Y546986D02*
Y548915D01*
G01X493392Y546200D02*
X492606Y546986D01*
G01X493392Y537948D02*
Y546200D01*
G01X492784Y537340D02*
X493392Y537948D01*
G01X492784Y536208D02*
Y537340D01*
G01X493392Y535600D02*
X492784Y536208D01*
G01X493392Y530400D02*
Y535600D01*
G01X492692Y529700D02*
X493392Y530400D01*
G01X492692Y528352D02*
Y529700D01*
G01X493392Y527652D02*
X492692Y528352D01*
G01X485037Y550966D02*
Y550914D01*
G01X486333Y549670D02*
X485037Y550966D01*
G01X486333Y546759D02*
Y549670D01*
G01X486692Y546400D02*
X486333Y546759D01*
G01X486692Y537899D02*
Y546400D01*
G01X486333Y537540D02*
X486692Y537899D01*
G01X486333Y536258D02*
Y537540D01*
G01X487333Y535258D02*
X486333Y536258D01*
G01X487333Y530469D02*
Y535258D01*
G01X486483Y529619D02*
X487333Y530469D01*
G01X486483Y528109D02*
Y529619D01*
G01X486692Y527900D02*
X486483Y528109D01*
G01X482763Y566699D02*
X481691D01*
G01X483463Y565999D02*
X482763Y566699D01*
G01X483463Y564725D02*
Y565999D01*
G01X482326Y563588D02*
X483463Y564725D01*
G01X482326Y562512D02*
Y563588D01*
G01X483338Y561500D02*
X482326Y562512D01*
G01X483338Y560300D02*
Y561500D01*
G01X482326Y559288D02*
X483338Y560300D01*
G01X482326Y558212D02*
Y559288D01*
G01X483438Y557100D02*
X482326Y558212D01*
G01X483438Y554467D02*
Y557100D01*
G01X483263Y554292D02*
X483438Y554467D01*
G01X483263Y552600D02*
Y554292D01*
G01X484949Y550914D02*
X483263Y552600D01*
G01X485037Y550914D02*
X484949D01*
G01X479986Y567849D02*
X485037Y572900D01*
G01X479986Y557662D02*
Y567849D01*
G01X481691Y555957D02*
X479986Y557662D01*
G01X480333Y554599D02*
X481691Y555957D01*
G01X480333Y552107D02*
Y554599D01*
G01X483463Y548977D02*
X480333Y552107D01*
G01X483463Y535972D02*
Y548977D01*
G01X482833Y535342D02*
X483463Y535972D01*
G01X482833Y530357D02*
Y535342D01*
G01X483595Y529595D02*
X482833Y530357D01*
G01X534534Y550564D02*
Y550914D01*
G01X536455Y548643D02*
X534534Y550564D01*
G01X536455Y546837D02*
Y548643D01*
G01X536892Y546400D02*
X536455Y546837D01*
G01X536892Y538137D02*
Y546400D01*
G01X536455Y537700D02*
X536892Y538137D01*
G01X536455Y528537D02*
Y537700D01*
G01X536892Y528100D02*
X536455Y528537D01*
G01X486225Y586929D02*
X488384Y589088D01*
G01X486225Y579569D02*
Y586929D01*
G01X490507Y575287D02*
X486225Y579569D01*
G01X490507Y574155D02*
Y575287D01*
G01X488692Y572340D02*
X490507Y574155D01*
G01X488692Y568901D02*
Y572340D01*
G01X490344Y567249D02*
X488692Y568901D01*
G01X490344Y565952D02*
Y567249D01*
G01X490092Y565700D02*
X490344Y565952D01*
G01X490092Y557800D02*
Y565700D01*
G01X490692Y557200D02*
X490092Y557800D01*
G01X490692Y555505D02*
Y557200D01*
G01X489444Y554257D02*
X490692Y555505D01*
G01X489444Y549557D02*
Y554257D01*
G01X490444Y548557D02*
X489444Y549557D01*
G01X490444Y547252D02*
Y548557D01*
G01X490092Y546900D02*
X490444Y547252D01*
G01X490092Y538052D02*
Y546900D01*
G01X490444Y537700D02*
X490092Y538052D01*
G01X490444Y536242D02*
Y537700D01*
G01X489444Y535242D02*
X490444Y536242D01*
G01X489444Y530348D02*
Y535242D01*
G01X490344Y529448D02*
X489444Y530348D01*
G01X490344Y528052D02*
Y529448D01*
G01X490092Y527800D02*
X490344Y528052D01*
G01X523144Y587470D02*
X521848Y588766D01*
G01X523144Y574248D02*
Y587470D01*
G01X524144Y573248D02*
X523144Y574248D01*
G01X524144Y568497D02*
Y573248D01*
G01X522792Y567145D02*
X524144Y568497D01*
G01X522792Y555659D02*
Y567145D01*
G01X523244Y546948D02*
Y549457D01*
G01X523492Y546700D02*
X523244Y546948D01*
G01X523492Y537748D02*
Y546700D01*
G01X523244Y537500D02*
X523492Y537748D01*
G01X523244Y536148D02*
Y537500D01*
G01X523944Y535448D02*
X523244Y536148D01*
G01X523944Y530258D02*
Y535448D01*
G01X523294Y529608D02*
X523944Y530258D01*
G01X523294Y527998D02*
Y529608D01*
G01X523492Y527800D02*
X523294Y527998D01*
G01X497144Y528252D02*
X496492Y527600D01*
G01X497144Y529248D02*
Y528252D01*
G01X495794Y530598D02*
X497144Y529248D01*
G01X495794Y535202D02*
Y530598D01*
G01X497144Y536552D02*
X495794Y535202D01*
G01X497144Y537700D02*
Y536552D01*
G01X496092Y538752D02*
X497144Y537700D01*
G01X496092Y545300D02*
Y538752D01*
G01X497144Y546352D02*
X496092Y545300D01*
G01X497144Y548507D02*
Y546352D01*
G01X495794Y549857D02*
X497144Y548507D01*
G01X495794Y554107D02*
Y549857D01*
G01X496992Y555305D02*
X495794Y554107D01*
G01X496992Y557252D02*
Y555305D01*
G01X496792Y557452D02*
X496992Y557252D01*
G01X496792Y565800D02*
Y557452D01*
G01X496944Y565952D02*
X496792Y565800D01*
G01X496944Y567247D02*
Y565952D01*
G01X495844Y568347D02*
X496944Y567247D01*
G01X495844Y573053D02*
Y568347D01*
G01X496994Y574203D02*
X495844Y573053D01*
G01X496994Y586457D02*
Y574203D01*
G01X495077Y588374D02*
X496994Y586457D01*
G01X518502Y588549D02*
Y593757D01*
G01X511809Y588592D02*
Y593757D01*
G01X488384Y589088D02*
Y593757D01*
G01X521848Y588766D02*
Y588714D01*
G01X495077Y593757D02*
Y588374D01*
G01X568699Y30021D02*
Y27899D01*
G01X570578Y31900D02*
X568699Y30021D01*
G01X571978Y31900D02*
X570578D01*
G01X573434Y33356D02*
X571978Y31900D01*
G01X593371Y29146D02*
X592124Y27899D01*
G01X593371Y30400D02*
Y29146D01*
G01X594671Y31700D02*
X593371Y30400D01*
G01X595671Y31700D02*
X594671D01*
G01X597471Y33500D02*
X595671Y31700D01*
G01X552167D02*
X553967Y33500D01*
G01X551167Y31700D02*
X552167D01*
G01X549867Y30400D02*
X551167Y31700D01*
G01X549867Y29146D02*
Y30400D01*
G01X548620Y27899D02*
X549867Y29146D01*
G01X586678D02*
X585431Y27899D01*
G01X586678Y30400D02*
Y29146D01*
G01X587978Y31700D02*
X586678Y30400D01*
G01X588978Y31700D02*
X587978D01*
G01X590778Y33500D02*
X588978Y31700D01*
G01X562006Y29453D02*
Y27899D01*
G01X564253Y31700D02*
X562006Y29453D01*
G01X565477Y31700D02*
X564253D01*
G01X567053Y33276D02*
X565477Y31700D01*
G01X558860D02*
X560660Y33500D01*
G01X557860Y31700D02*
X558860D01*
G01X556560Y30400D02*
X557860Y31700D01*
G01X556560Y29146D02*
Y30400D01*
G01X555313Y27899D02*
X556560Y29146D01*
G01X557297Y91906D02*
Y104954D01*
G01X556666Y91275D02*
X557297Y91906D01*
G01X556666Y86505D02*
Y91275D01*
G01X557397Y85774D02*
X556666Y86505D01*
G01X557397Y73205D02*
Y85774D01*
G01X556597Y72405D02*
X557397Y73205D01*
G01X556597Y67027D02*
Y72405D01*
G01X557113Y66511D02*
X556597Y67027D01*
G01X557113Y64952D02*
Y66511D01*
G01X555313Y63152D02*
X557113Y64952D01*
G01X555313Y54957D02*
Y63152D01*
G01X554192Y53836D02*
X555313Y54957D01*
G01X554192Y50900D02*
Y53836D01*
G01X557534Y47558D02*
X554192Y50900D01*
G01X557534Y46500D02*
Y47558D01*
G01X555734Y44700D02*
X557534Y46500D01*
G01X555734Y43125D02*
Y44700D01*
G01X556934Y41925D02*
X555734Y43125D01*
G01X556934Y40799D02*
Y41925D01*
G01X555734Y39599D02*
X556934Y40799D01*
G01X555734Y38226D02*
Y39599D01*
G01X557092Y36868D02*
X555734Y38226D01*
G01X557092Y35667D02*
Y36868D01*
G01X558659Y34100D02*
X557092Y35667D01*
G01X573434Y34700D02*
Y33356D01*
G01X572818Y35316D02*
X573434Y34700D01*
G01X572818Y48441D02*
Y35316D01*
G01X571345Y49914D02*
X572818Y48441D01*
G01X569272Y51987D02*
X571345Y49914D01*
G01X569272Y53080D02*
Y51987D01*
G01X570766Y54574D02*
X569272Y53080D01*
G01X570766Y61674D02*
Y54574D01*
G01X573266Y64174D02*
X570766Y61674D01*
G01X573266Y94074D02*
Y64174D01*
G01X574492Y95300D02*
X573266Y94074D01*
G01X597471Y34900D02*
Y33500D01*
G01X596859Y35512D02*
X597471Y34900D01*
G01X596859Y48525D02*
Y35512D01*
G01X595470Y49914D02*
X596859Y48525D01*
G01X593566Y51818D02*
X595470Y49914D01*
G01X593566Y53418D02*
Y51818D01*
G01X596916Y56768D02*
X593566Y53418D01*
G01X596916Y66503D02*
Y56768D01*
G01X597466Y67053D02*
X596916Y66503D01*
G01X597466Y72627D02*
Y67053D01*
G01X596866Y73227D02*
X597466Y72627D01*
G01X596866Y85918D02*
Y73227D01*
G01X597566Y86618D02*
X596866Y85918D01*
G01X597566Y91018D02*
Y86618D01*
G01X597017Y91567D02*
X597566Y91018D01*
G01X597017Y118485D02*
Y91567D01*
G01X593903Y35667D02*
X595470Y34100D01*
G01X593903Y36868D02*
Y35667D01*
G01X592545Y38226D02*
X593903Y36868D01*
G01X592545Y39599D02*
Y38226D01*
G01X593745Y40799D02*
X592545Y39599D01*
G01X593745Y41925D02*
Y40799D01*
G01X592545Y43125D02*
X593745Y41925D01*
G01X592545Y44700D02*
Y43125D01*
G01X594345Y46500D02*
X592545Y44700D01*
G01X594345Y47558D02*
Y46500D01*
G01X591003Y50900D02*
X594345Y47558D01*
G01X591003Y53836D02*
Y50900D01*
G01X592124Y54957D02*
X591003Y53836D01*
G01X592124Y56133D02*
Y54957D01*
G01X594366Y58375D02*
X592124Y56133D01*
G01X594366Y66003D02*
Y58375D01*
G01X593566Y66803D02*
X594366Y66003D01*
G01X593566Y72575D02*
Y66803D01*
G01X594066Y73075D02*
X593566Y72575D01*
G01X594066Y85818D02*
Y73075D01*
G01X593466Y86418D02*
X594066Y85818D01*
G01X593466Y91118D02*
Y86418D01*
G01X593992Y91644D02*
X593466Y91118D01*
G01X593992Y96918D02*
Y91644D01*
G01X553397Y91712D02*
Y105883D01*
G01X554097Y91012D02*
X553397Y91712D01*
G01X554097Y86674D02*
Y91012D01*
G01X553266Y85843D02*
X554097Y86674D01*
G01X553266Y73126D02*
Y85843D01*
G01X553997Y72395D02*
X553266Y73126D01*
G01X553997Y66991D02*
Y72395D01*
G01X552797Y65791D02*
X553997Y66991D01*
G01X552797Y56176D02*
Y65791D01*
G01X550166Y53545D02*
X552797Y56176D01*
G01X550166Y51714D02*
Y53545D01*
G01X551966Y49914D02*
X550166Y51714D01*
G01X553355Y48525D02*
X551966Y49914D01*
G01X553355Y35512D02*
Y48525D01*
G01X553967Y34900D02*
X553355Y35512D01*
G01X553967Y33500D02*
Y34900D01*
G01X590778D02*
Y33500D01*
G01X590166Y35512D02*
X590778Y34900D01*
G01X590166Y48525D02*
Y35512D01*
G01X588777Y49914D02*
X590166Y48525D01*
G01X586866Y51825D02*
X588777Y49914D01*
G01X586866Y53644D02*
Y51825D01*
G01X588416Y55194D02*
X586866Y53644D01*
G01X588416Y56632D02*
Y55194D01*
G01X590192Y58408D02*
X588416Y56632D01*
G01X590192Y66379D02*
Y58408D01*
G01X590592Y66779D02*
X590192Y66379D01*
G01X590592Y72701D02*
Y66779D01*
G01X590166Y73127D02*
X590592Y72701D01*
G01X590166Y85718D02*
Y73127D01*
G01X590966Y86518D02*
X590166Y85718D01*
G01X590966Y91018D02*
Y86518D01*
G01X590292Y91692D02*
X590966Y91018D01*
G01X590292Y110099D02*
Y91692D01*
G01X563878Y34788D02*
X564966Y33700D01*
G01X563878Y36668D02*
Y34788D01*
G01X562445Y38101D02*
X563878Y36668D01*
G01X562445Y39300D02*
Y38101D01*
G01X563945Y40800D02*
X562445Y39300D01*
G01X563945Y42000D02*
Y40800D01*
G01X562495Y43450D02*
X563945Y42000D01*
G01X562495Y44849D02*
Y43450D01*
G01X563878Y46232D02*
X562495Y44849D01*
G01X563878Y48101D02*
Y46232D01*
G01X561078Y50901D02*
X563878Y48101D01*
G01X561078Y54029D02*
Y50901D01*
G01X562006Y54957D02*
X561078Y54029D01*
G01X563966Y56917D02*
X562006Y54957D01*
G01X563966Y66227D02*
Y56917D01*
G01X563066Y67127D02*
X563966Y66227D01*
G01X563066Y72103D02*
Y67127D01*
G01X564066Y73103D02*
X563066Y72103D01*
G01X564066Y85274D02*
Y73103D01*
G01X563066Y86274D02*
X564066Y85274D01*
G01X563066Y91218D02*
Y86274D01*
G01X563806Y91958D02*
X563066Y91218D01*
G01X563806Y108100D02*
Y91958D01*
G01X567053Y34900D02*
Y33276D01*
G01X566278Y35675D02*
X567053Y34900D01*
G01X566278Y48688D02*
Y35675D01*
G01X565052Y49914D02*
X566278Y48688D01*
G01X564198Y50768D02*
X565052Y49914D01*
G01X564016Y50768D02*
X564198D01*
G01X563066Y51718D02*
X564016Y50768D01*
G01X563066Y53318D02*
Y51718D01*
G01X566092Y56344D02*
X563066Y53318D01*
G01X566092Y65829D02*
Y56344D01*
G01X566916Y66653D02*
X566092Y65829D01*
G01X566916Y72853D02*
Y66653D01*
G01X566566Y73203D02*
X566916Y72853D01*
G01X566566Y85374D02*
Y73203D01*
G01X567566Y86374D02*
X566566Y85374D01*
G01X567566Y90768D02*
Y86374D01*
G01X566392Y91942D02*
X567566Y90768D01*
G01X566392Y109050D02*
Y91942D01*
G01X550897Y92174D02*
Y104775D01*
G01X549797Y91074D02*
X550897Y92174D01*
G01X549797Y86774D02*
Y91074D01*
G01X550566Y86005D02*
X549797Y86774D01*
G01X550566Y73274D02*
Y86005D01*
G01X549797Y72505D02*
X550566Y73274D01*
G01X549797Y67139D02*
Y72505D01*
G01X550597Y66339D02*
X549797Y67139D01*
G01X550597Y56934D02*
Y66339D01*
G01X548620Y54957D02*
X550597Y56934D01*
G01X547692Y54029D02*
X548620Y54957D01*
G01X547692Y50901D02*
Y54029D01*
G01X550734Y47859D02*
X547692Y50901D01*
G01X550734Y46474D02*
Y47859D01*
G01X549059Y44799D02*
X550734Y46474D01*
G01X549059Y43676D02*
Y44799D01*
G01X550559Y42176D02*
X549059Y43676D01*
G01X550559Y40824D02*
Y42176D01*
G01X549059Y39324D02*
X550559Y40824D01*
G01X549059Y38101D02*
Y39324D01*
G01X550492Y36668D02*
X549059Y38101D01*
G01X550492Y35574D02*
Y36668D01*
G01X551966Y34100D02*
X550492Y35574D01*
G01X559897Y92042D02*
Y106076D01*
G01X560597Y91342D02*
X559897Y92042D01*
G01X560597Y86494D02*
Y91342D01*
G01X559897Y85794D02*
X560597Y86494D01*
G01X559897Y73095D02*
Y85794D01*
G01X560597Y72395D02*
X559897Y73095D01*
G01X560597Y66979D02*
Y72395D01*
G01X560206Y66588D02*
X560597Y66979D01*
G01X560206Y63715D02*
Y66588D01*
G01X558306Y61815D02*
X560206Y63715D01*
G01X558306Y54985D02*
Y61815D01*
G01X556513Y53192D02*
X558306Y54985D01*
G01X556513Y52060D02*
Y53192D01*
G01X558659Y49914D02*
X556513Y52060D01*
G01X560048Y48525D02*
X558659Y49914D01*
G01X560048Y35512D02*
Y48525D01*
G01X560660Y34900D02*
X560048Y35512D01*
G01X560660Y33500D02*
Y34900D01*
G01X587303Y35574D02*
X588777Y34100D01*
G01X587303Y36668D02*
Y35574D01*
G01X585870Y38101D02*
X587303Y36668D01*
G01X585870Y39324D02*
Y38101D01*
G01X587370Y40824D02*
X585870Y39324D01*
G01X587370Y42176D02*
Y40824D01*
G01X585870Y43676D02*
X587370Y42176D01*
G01X585870Y44799D02*
Y43676D01*
G01X587545Y46474D02*
X585870Y44799D01*
G01X587545Y47859D02*
Y46474D01*
G01X584503Y50901D02*
X587545Y47859D01*
G01X584503Y54029D02*
Y50901D01*
G01X585431Y54957D02*
X584503Y54029D01*
G01X585431Y57183D02*
Y54957D01*
G01X587292Y59044D02*
X585431Y57183D01*
G01X587292Y66477D02*
Y59044D01*
G01X586866Y66903D02*
X587292Y66477D01*
G01X586866Y72575D02*
Y66903D01*
G01X587666Y73375D02*
X586866Y72575D01*
G01X587666Y85718D02*
Y73375D01*
G01X586866Y86518D02*
X587666Y85718D01*
G01X586866Y91218D02*
Y86518D01*
G01X587231Y91583D02*
X586866Y91218D01*
G01X587231Y94235D02*
Y91583D01*
G01X585992Y95474D02*
X587231Y94235D01*
G01X570478Y34567D02*
X571345Y33700D01*
G01X570478Y36868D02*
Y34567D01*
G01X568845Y38501D02*
X570478Y36868D01*
G01X568845Y39800D02*
Y38501D01*
G01X570195Y41150D02*
X568845Y39800D01*
G01X570195Y42050D02*
Y41150D01*
G01X568945Y43300D02*
X570195Y42050D01*
G01X568945Y44499D02*
Y43300D01*
G01X570478Y46032D02*
X568945Y44499D01*
G01X570478Y48000D02*
Y46032D01*
G01X567578Y50900D02*
X570478Y48000D01*
G01X567578Y53836D02*
Y50900D01*
G01X568699Y54957D02*
X567578Y53836D01*
G01X568699Y62807D02*
Y54957D01*
G01X570566Y64674D02*
X568699Y62807D01*
G01X570566Y66244D02*
Y64674D01*
G01X569416Y67394D02*
X570566Y66244D01*
G01X569416Y72123D02*
Y67394D01*
G01X570766Y73473D02*
X569416Y72123D01*
G01X570766Y85368D02*
Y73473D01*
G01X569416Y86718D02*
X570766Y85368D01*
G01X569416Y90897D02*
Y86718D01*
G01X570638Y92119D02*
X569416Y90897D01*
G01X570642Y92119D02*
X570638D01*
G01X570642Y94189D02*
Y92119D01*
G01X569092Y95739D02*
X570642Y94189D01*
G01X555313Y110727D02*
Y112357D01*
G01X556666Y109374D02*
X555313Y110727D01*
G01X556666Y105585D02*
Y109374D01*
G01X557297Y104954D02*
X556666Y105585D01*
G01X574492Y108022D02*
Y95300D01*
G01X551225Y131289D02*
X574492Y108022D01*
G01X551225Y132422D02*
Y131289D01*
G01X552292Y133489D02*
X551225Y132422D01*
G01X552292Y138156D02*
Y133489D01*
G01X594842Y97768D02*
X593992Y96918D01*
G01X594842Y99848D02*
Y97768D01*
G01X594282Y100408D02*
X594842Y99848D01*
G01X593552Y100408D02*
X594282D01*
G01X592992Y100968D02*
X593552Y100408D01*
G01X592992Y103048D02*
Y100968D01*
G01X593552Y103608D02*
X592992Y103048D01*
G01X594082Y103608D02*
X593552D01*
G01X594642Y104168D02*
X594082Y103608D01*
G01X594642Y106248D02*
Y104168D01*
G01X594082Y106808D02*
X594642Y106248D01*
G01X593392Y106808D02*
X594082D01*
G01X592592Y107608D02*
X593392Y106808D01*
G01X592592Y109208D02*
Y107608D01*
G01X593392Y110008D02*
X592592Y109208D01*
G01X594232Y110008D02*
X593392D01*
G01X594792Y110568D02*
X594232Y110008D01*
G01X594792Y112648D02*
Y110568D01*
G01X594232Y113208D02*
X594792Y112648D01*
G01X593392Y113208D02*
X594232D01*
G01X592592Y114008D02*
X593392Y113208D01*
G01X592592Y119374D02*
Y114008D01*
G01X553397Y105883D02*
X551966Y107314D01*
G01X588492Y111899D02*
X590292Y110099D01*
G01X588492Y113599D02*
Y111899D01*
G01X589392Y114499D02*
X588492Y113599D01*
G01X589392Y117399D02*
Y114499D01*
G01X588492Y118299D02*
X589392Y117399D01*
G01X588492Y119938D02*
Y118299D01*
G01X555175Y116731D02*
X563806Y108100D01*
G01X554043Y116731D02*
X555175D01*
G01X552918Y115606D02*
X554043Y116731D01*
G01X551786Y115606D02*
X552918D01*
G01X550655Y116737D02*
X551786Y115606D01*
G01X550655Y117869D02*
Y116737D01*
G01X551780Y118994D02*
X550655Y117869D01*
G01X551780Y120126D02*
Y118994D01*
G01X550649Y121257D02*
X551780Y120126D01*
G01X549517Y121257D02*
X550649D01*
G01X548392Y120132D02*
X549517Y121257D01*
G01X547260Y120132D02*
X548392D01*
G01X546129Y121263D02*
X547260Y120132D01*
G01X546129Y122395D02*
Y121263D01*
G01X547254Y123520D02*
X546129Y122395D01*
G01X547254Y124652D02*
Y123520D01*
G01X546123Y125783D02*
X547254Y124652D01*
G01X544991Y125783D02*
X546123D01*
G01X543866Y124658D02*
X544991Y125783D01*
G01X542734Y124658D02*
X543866D01*
G01X541603Y125789D02*
X542734Y124658D01*
G01X541603Y126921D02*
Y125789D01*
G01X542728Y128046D02*
X541603Y126921D01*
G01X542728Y129178D02*
Y128046D01*
G01X541597Y130309D02*
X542728Y129178D01*
G01X540465Y130309D02*
X541597D01*
G01X541741Y141349D02*
Y140217D01*
G01X540610Y142480D02*
X541741Y141349D01*
G01X548620Y110121D02*
Y112357D01*
G01X549416Y109324D02*
X548620Y110121D01*
G01X549677Y109064D02*
X549416Y109324D01*
G01X549677Y105995D02*
Y109064D01*
G01X550897Y104775D02*
X549677Y105995D01*
G01X559897Y106076D02*
X558659Y107314D01*
G01X585992Y111176D02*
Y95474D01*
G01X581488Y115680D02*
X585992Y111176D01*
G01X581488Y116812D02*
Y115680D01*
G01X583463Y118787D02*
X581488Y116812D01*
G01X583463Y119579D02*
Y118787D01*
G01X581992Y121050D02*
X583463Y119579D01*
G01X581200Y121050D02*
X581992D01*
G01X579225Y119075D02*
X581200Y121050D01*
G01X578093Y119075D02*
X579225D01*
G01X576962Y120206D02*
X578093Y119075D01*
G01X576962Y121338D02*
Y120206D01*
G01X578487Y122863D02*
X576962Y121338D01*
G01X578487Y123655D02*
Y122863D01*
G01X577016Y125126D02*
X578487Y123655D01*
G01X576224Y125126D02*
X577016D01*
G01X574699Y123601D02*
X576224Y125126D01*
G01X573567Y123601D02*
X574699D01*
G01X572792Y124376D02*
X573567Y123601D01*
G01X572792Y132101D02*
Y124376D01*
G01X569092Y97339D02*
Y95739D01*
G01X569892Y98139D02*
X569092Y97339D01*
G01X571192Y98139D02*
X569892D01*
G01X571992Y98939D02*
X571192Y98139D01*
G01X571992Y100539D02*
Y98939D01*
G01X571192Y101339D02*
X571992Y100539D01*
G01X569892Y101339D02*
X571192D01*
G01X569092Y102139D02*
X569892Y101339D01*
G01X569092Y103739D02*
Y102139D01*
G01X569892Y104539D02*
X569092Y103739D01*
G01X571192Y104539D02*
X569892D01*
G01X571992Y105339D02*
X571192Y104539D01*
G01X571992Y106986D02*
Y105339D01*
G01X547692Y131286D02*
X571992Y106986D01*
G01X547692Y132424D02*
Y131286D01*
G01X549259Y133991D02*
X547692Y132424D01*
G01X549259Y134783D02*
Y133991D01*
G01X547593Y136449D02*
X549259Y134783D01*
G01X546801Y136449D02*
X547593D01*
G01X545231Y134879D02*
X546801Y136449D01*
G01X544099Y134879D02*
X545231D01*
G01X542968Y136010D02*
X544099Y134879D01*
G01X542968Y137142D02*
Y136010D01*
G01X545546Y139720D02*
X542968Y137142D01*
G01X545546Y141366D02*
Y139720D01*
G01X543488Y464989D02*
Y464127D01*
G01X567650Y464264D02*
X593937Y490551D01*
G01X562019Y464264D02*
X567650D01*
G01X568284Y461664D02*
X596136Y489516D01*
G01X562219Y461664D02*
X568284D01*
G01X540982Y467495D02*
X543488Y464989D01*
G01X540982Y468357D02*
Y467495D01*
G01X541966Y469341D02*
X540982Y468357D01*
G01X542828Y469341D02*
X541966D01*
G01X545334Y466835D02*
X542828Y469341D01*
G01X546196Y466835D02*
X545334D01*
G01X547180Y467819D02*
X546196Y466835D01*
G01X547180Y468681D02*
Y467819D01*
G01X544674Y471187D02*
X547180Y468681D01*
G01X544674Y472049D02*
Y471187D01*
G01X545658Y473033D02*
X544674Y472049D01*
G01X546520Y473033D02*
X545658D01*
G01X549026Y470527D02*
X546520Y473033D01*
G01X549888Y470527D02*
X549026D01*
G01X573266Y493905D02*
X549888Y470527D01*
G01X573266Y519274D02*
Y493905D01*
G01X573792Y519800D02*
X573266Y519274D01*
G01X573792Y527200D02*
Y519800D01*
G01X593935Y517426D02*
Y529756D01*
G01X593566Y517057D02*
X593935Y517426D01*
G01X593566Y511657D02*
Y517057D01*
G01X593937Y511286D02*
X593566Y511657D01*
G01X593937Y490551D02*
Y511286D01*
G01X556989Y520066D02*
Y527697D01*
G01X557555Y519500D02*
X556989Y520066D01*
G01X557555Y517857D02*
Y519500D01*
G01X556755Y517057D02*
X557555Y517857D01*
G01X556755Y511657D02*
Y517057D01*
G01X557255Y511157D02*
X556755Y511657D01*
G01X557255Y500829D02*
Y511157D01*
G01X554913Y498487D02*
X557255Y500829D01*
G01X554792Y498487D02*
X554913D01*
G01X587092Y519874D02*
Y527600D01*
G01X587466Y519500D02*
X587092Y519874D01*
G01X587466Y517557D02*
Y519500D01*
G01X586866Y516957D02*
X587466Y517557D01*
G01X586866Y512057D02*
Y516957D01*
G01X587253Y511670D02*
X586866Y512057D01*
G01X587253Y508741D02*
Y511670D01*
G01X585821Y507309D02*
X587253Y508741D01*
G01X585821Y488747D02*
Y507309D01*
G01X566834Y469760D02*
X585821Y488747D01*
G01X561915Y469760D02*
X566834D01*
G01X560392Y520087D02*
Y527600D01*
G01X560105Y519800D02*
X560392Y520087D01*
G01X560105Y517357D02*
Y519800D01*
G01X560655Y516807D02*
X560105Y517357D01*
G01X560655Y512257D02*
Y516807D01*
G01X560055Y511657D02*
X560655Y512257D01*
G01X560055Y497540D02*
Y511657D01*
G01X558659Y496144D02*
X560055Y497540D01*
G01X553592Y519537D02*
Y527900D01*
G01X553455Y519400D02*
X553592Y519537D01*
G01X553455Y517357D02*
Y519400D01*
G01X554255Y516557D02*
X553455Y517357D01*
G01X554255Y512157D02*
Y516557D01*
G01X553355Y511257D02*
X554255Y512157D01*
G01X553355Y501641D02*
Y511257D01*
G01X551366Y499652D02*
X553355Y501641D01*
G01X551366Y493344D02*
Y499652D01*
G01X550292Y519863D02*
Y527700D01*
G01X550655Y519500D02*
X550292Y519863D01*
G01X550655Y517557D02*
Y519500D01*
G01X550055Y516957D02*
X550655Y517557D01*
G01X550055Y512057D02*
Y516957D01*
G01X550855Y511257D02*
X550055Y512057D01*
G01X550855Y504841D02*
Y511257D01*
G01X548620Y502606D02*
X550855Y504841D01*
G01X548620Y498528D02*
Y502606D01*
G01X548492Y498400D02*
X548620Y498528D01*
G01X570392Y519474D02*
Y527700D01*
G01X570566Y519300D02*
X570392Y519474D01*
G01X570566Y517457D02*
Y519300D01*
G01X569416Y516307D02*
X570566Y517457D01*
G01X569416Y512057D02*
Y516307D01*
G01X570766Y510707D02*
X569416Y512057D01*
G01X570766Y494472D02*
Y510707D01*
G01X553691Y477397D02*
X570766Y494472D01*
G01X543969Y481568D02*
X543359Y482178D01*
G01X543969Y480022D02*
Y481568D01*
G01X544579Y479412D02*
X543969Y480022D01*
G01X545969Y479412D02*
X544579D01*
G01X546579Y480022D02*
X545969Y479412D01*
G01X546579Y481568D02*
Y480022D01*
G01X547189Y482178D02*
X546579Y481568D01*
G01X548579Y482178D02*
X547189D01*
G01X549189Y481568D02*
X548579Y482178D01*
G01X549189Y480022D02*
Y481568D01*
G01X549799Y479412D02*
X549189Y480022D01*
G01X551189Y479412D02*
X549799D01*
G01X551799Y480022D02*
X551189Y479412D01*
G01X551799Y481568D02*
Y480022D01*
G01X552409Y482178D02*
X551799Y481568D01*
G01X555398Y482178D02*
X552409D01*
G01X566566Y493346D02*
X555398Y482178D01*
G01X566566Y510973D02*
Y493346D01*
G01X566992Y511399D02*
X566566Y510973D01*
G01X566992Y517131D02*
Y511399D01*
G01X566666Y517457D02*
X566992Y517131D01*
G01X566666Y519500D02*
Y517457D01*
G01X567092Y519926D02*
X566666Y519500D01*
G01X567092Y527500D02*
Y519926D01*
G01X596825Y517448D02*
Y529602D01*
G01X597466Y516807D02*
X596825Y517448D01*
G01X597466Y512257D02*
Y516807D01*
G01X596455Y511246D02*
X597466Y512257D01*
G01X596455Y508476D02*
Y511246D01*
G01X597304Y507627D02*
X596455Y508476D01*
G01X599054Y507627D02*
X597304D01*
G01X599664Y507017D02*
X599054Y507627D01*
G01X599664Y505627D02*
Y507017D01*
G01X599054Y505017D02*
X599664Y505627D01*
G01X596733Y505017D02*
X599054D01*
G01X596070Y504354D02*
X596733Y505017D01*
G01X596070Y502964D02*
Y504354D01*
G01X596627Y502407D02*
X596070Y502964D01*
G01X599054Y502407D02*
X596627D01*
G01X599664Y501797D02*
X599054Y502407D01*
G01X599664Y500407D02*
Y501797D01*
G01X599054Y499797D02*
X599664Y500407D01*
G01X597136Y499797D02*
X599054D01*
G01X596136Y498797D02*
X597136Y499797D01*
G01X596136Y489516D02*
Y498797D01*
G01X563692Y519474D02*
Y527800D01*
G01X563966Y519200D02*
X563692Y519474D01*
G01X563966Y517357D02*
Y519200D01*
G01X563066Y516457D02*
X563966Y517357D01*
G01X563066Y511757D02*
Y516457D01*
G01X564066Y510757D02*
X563066Y511757D01*
G01X564066Y495790D02*
Y510757D01*
G01X553097Y484821D02*
X564066Y495790D01*
G01X591786Y525766D02*
Y526622D01*
G01X591176Y525156D02*
X591786Y525766D01*
G01X590093Y525156D02*
X591176D01*
G01X589483Y524546D02*
X590093Y525156D01*
G01X589483Y522566D02*
Y524546D01*
G01X590093Y521956D02*
X589483Y522566D01*
G01X591176Y521956D02*
X590093D01*
G01X591786Y521346D02*
X591176Y521956D01*
G01X591786Y520508D02*
Y521346D01*
G01X589966Y518688D02*
X591786Y520508D01*
G01X589966Y517657D02*
Y518688D01*
G01X591066Y516557D02*
X589966Y517657D01*
G01X591066Y512157D02*
Y516557D01*
G01X590223Y511314D02*
X591066Y512157D01*
G01X590223Y505665D02*
Y511314D01*
G01X589613Y505055D02*
X590223Y505665D01*
G01X588234Y505055D02*
X589613D01*
G01X587624Y504445D02*
X588234Y505055D01*
G01X587624Y503055D02*
Y504445D01*
G01X588234Y502445D02*
X587624Y503055D01*
G01X589613Y502445D02*
X588234D01*
G01X590223Y501835D02*
X589613Y502445D01*
G01X590223Y500445D02*
Y501835D01*
G01X589613Y499835D02*
X590223Y500445D01*
G01X588234Y499835D02*
X589613D01*
G01X587624Y499225D02*
X588234Y499835D01*
G01X587624Y497835D02*
Y499225D01*
G01X588234Y497225D02*
X587624Y497835D01*
G01X589613Y497225D02*
X588234D01*
G01X590223Y496615D02*
X589613Y497225D01*
G01X590223Y489859D02*
Y496615D01*
G01X567472Y467108D02*
X590223Y489859D01*
G01X562063Y467108D02*
X567472D01*
G01X569679Y566699D02*
X568699D01*
G01X570278Y566100D02*
X569679Y566699D01*
G01X570278Y564900D02*
Y566100D01*
G01X569334Y563956D02*
X570278Y564900D01*
G01X569334Y562744D02*
Y563956D01*
G01X570178Y561900D02*
X569334Y562744D01*
G01X570178Y560200D02*
Y561900D01*
G01X569334Y559356D02*
X570178Y560200D01*
G01X569334Y557936D02*
Y559356D01*
G01X570478Y556792D02*
X569334Y557936D01*
G01X570478Y555199D02*
Y556792D01*
G01X569571Y554292D02*
X570478Y555199D01*
G01X569571Y552600D02*
Y554292D01*
G01X571257Y550914D02*
X569571Y552600D01*
G01X571345Y550914D02*
X571257D01*
G01X573266Y527726D02*
X573792Y527200D01*
G01X573266Y537700D02*
Y527726D01*
G01X573692Y538126D02*
X573266Y537700D01*
G01X573692Y546800D02*
Y538126D01*
G01X573266Y547226D02*
X573692Y546800D01*
G01X573266Y548643D02*
Y547226D01*
G01X571345Y550564D02*
X573266Y548643D01*
G01X571345Y550914D02*
Y550564D01*
G01X590419Y567849D02*
X595470Y572900D01*
G01X590419Y557662D02*
Y567849D01*
G01X592124Y555957D02*
X590419Y557662D01*
G01X591761Y555594D02*
X592124Y555957D01*
G01X591761Y551112D02*
Y555594D01*
G01X594042Y548831D02*
X591761Y551112D01*
G01X594042Y536118D02*
Y548831D01*
G01X593266Y535342D02*
X594042Y536118D01*
G01X593266Y530425D02*
Y535342D01*
G01X593935Y529756D02*
X593266Y530425D01*
G01X553955Y554599D02*
X555313Y555957D01*
G01X553955Y552107D02*
Y554599D01*
G01X557355Y548707D02*
X553955Y552107D01*
G01X557355Y546663D02*
Y548707D01*
G01X556992Y546300D02*
X557355Y546663D01*
G01X556992Y537999D02*
Y546300D01*
G01X557355Y537636D02*
X556992Y537999D01*
G01X557355Y536242D02*
Y537636D01*
G01X556455Y535342D02*
X557355Y536242D01*
G01X556455Y530597D02*
Y535342D01*
G01X557555Y529497D02*
X556455Y530597D01*
G01X557555Y528263D02*
Y529497D01*
G01X556989Y527697D02*
X557555Y528263D01*
G01X583726Y567849D02*
X588777Y572900D01*
G01X583726Y557662D02*
Y567849D01*
G01X585431Y555957D02*
X583726Y557662D01*
G01X584766Y555292D02*
X585431Y555957D01*
G01X584766Y551457D02*
Y555292D01*
G01X587666Y548557D02*
X584766Y551457D01*
G01X587666Y546774D02*
Y548557D01*
G01X587092Y546200D02*
X587666Y546774D01*
G01X587092Y537974D02*
Y546200D01*
G01X587666Y537400D02*
X587092Y537974D01*
G01X587666Y536442D02*
Y537400D01*
G01X586393Y535169D02*
X587666Y536442D01*
G01X586393Y530584D02*
Y535169D01*
G01X587466Y529511D02*
X586393Y530584D01*
G01X587466Y527974D02*
Y529511D01*
G01X587092Y527600D02*
X587466Y527974D01*
G01X558659Y550966D02*
Y550914D01*
G01X559955Y549670D02*
X558659Y550966D01*
G01X559955Y546237D02*
Y549670D01*
G01X560292Y545900D02*
X559955Y546237D01*
G01X560292Y537937D02*
Y545900D01*
G01X559955Y537600D02*
X560292Y537937D01*
G01X559955Y536338D02*
Y537600D01*
G01X560955Y535338D02*
X559955Y536338D01*
G01X560955Y530697D02*
Y535338D01*
G01X560105Y529847D02*
X560955Y530697D01*
G01X560105Y527887D02*
Y529847D01*
G01X560392Y527600D02*
X560105Y527887D01*
G01X553312Y549568D02*
X551966Y550914D01*
G01X553355Y549568D02*
X553312D01*
G01X553355Y546837D02*
Y549568D01*
G01X553692Y546500D02*
X553355Y546837D01*
G01X553692Y538137D02*
Y546500D01*
G01X553355Y537800D02*
X553692Y538137D01*
G01X553355Y536237D02*
Y537800D01*
G01X554021Y535571D02*
X553355Y536237D01*
G01X554021Y530363D02*
Y535571D01*
G01X553455Y529797D02*
X554021Y530363D01*
G01X553455Y528037D02*
Y529797D01*
G01X553592Y527900D02*
X553455Y528037D01*
G01X547955Y555292D02*
X548620Y555957D01*
G01X547955Y551457D02*
Y555292D01*
G01X550855Y548557D02*
X547955Y551457D01*
G01X550855Y547163D02*
Y548557D01*
G01X550292Y546600D02*
X550855Y547163D01*
G01X550292Y538263D02*
Y546600D01*
G01X550592Y537963D02*
X550292Y538263D01*
G01X550592Y536179D02*
Y537963D01*
G01X549582Y535169D02*
X550592Y536179D01*
G01X549582Y530670D02*
Y535169D01*
G01X550655Y529597D02*
X549582Y530670D01*
G01X550655Y528063D02*
Y529597D01*
G01X550292Y527700D02*
X550655Y528063D01*
G01X567792Y555050D02*
X568699Y555957D01*
G01X567792Y551481D02*
Y555050D01*
G01X570616Y548657D02*
X567792Y551481D01*
G01X570616Y547024D02*
Y548657D01*
G01X570392Y546800D02*
X570616Y547024D01*
G01X570392Y537924D02*
Y546800D01*
G01X570616Y537700D02*
X570392Y537924D01*
G01X570616Y536525D02*
Y537700D01*
G01X569355Y535264D02*
X570616Y536525D01*
G01X569355Y530655D02*
Y535264D01*
G01X570566Y529444D02*
X569355Y530655D01*
G01X570566Y527874D02*
Y529444D01*
G01X570392Y527700D02*
X570566Y527874D01*
G01X570179Y572500D02*
X571345D01*
G01X566994Y569315D02*
X570179Y572500D01*
G01X566994Y557662D02*
Y569315D01*
G01X568699Y555957D02*
X566994Y557662D01*
G01X563078Y566699D02*
X562006D01*
G01X563678Y566099D02*
X563078Y566699D01*
G01X563678Y565201D02*
Y566099D01*
G01X562641Y564164D02*
X563678Y565201D01*
G01X562641Y562936D02*
Y564164D01*
G01X563578Y561999D02*
X562641Y562936D01*
G01X563578Y560601D02*
Y561999D01*
G01X562641Y559664D02*
X563578Y560601D01*
G01X562641Y558336D02*
Y559664D01*
G01X563778Y557199D02*
X562641Y558336D01*
G01X563778Y555300D02*
Y557199D01*
G01X563278Y554800D02*
X563778Y555300D01*
G01X563278Y552600D02*
Y554800D01*
G01X565266Y550612D02*
X563278Y552600D01*
G01X565266Y550574D02*
Y550612D01*
G01X566666Y527926D02*
X567092Y527500D01*
G01X566666Y530197D02*
Y527926D01*
G01X567166Y530697D02*
X566666Y530197D01*
G01X567166Y534856D02*
Y530697D01*
G01X566566Y535456D02*
X567166Y534856D01*
G01X566566Y537600D02*
Y535456D01*
G01X566992Y538026D02*
X566566Y537600D01*
G01X566992Y546600D02*
Y538026D01*
G01X566566Y547026D02*
X566992Y546600D01*
G01X566566Y549400D02*
Y547026D01*
G01X565392Y550574D02*
X566566Y549400D01*
G01X565266Y550574D02*
X565392D01*
G01X593196Y566699D02*
X592124D01*
G01X593896Y565999D02*
X593196Y566699D01*
G01X593896Y564725D02*
Y565999D01*
G01X592759Y563588D02*
X593896Y564725D01*
G01X592759Y562512D02*
Y563588D01*
G01X593771Y561500D02*
X592759Y562512D01*
G01X593771Y560300D02*
Y561500D01*
G01X592759Y559288D02*
X593771Y560300D01*
G01X592759Y558212D02*
Y559288D01*
G01X593871Y557100D02*
X592759Y558212D01*
G01X593871Y554467D02*
Y557100D01*
G01X593696Y554292D02*
X593871Y554467D01*
G01X593696Y552688D02*
Y554292D01*
G01X595470Y550914D02*
X593696Y552688D01*
G01X596766Y549618D02*
X595470Y550914D01*
G01X596766Y536526D02*
Y549618D01*
G01X597356Y535936D02*
X596766Y536526D01*
G01X597356Y530133D02*
Y535936D01*
G01X596825Y529602D02*
X597356Y530133D01*
G01X563978Y572500D02*
X564966D01*
G01X560923Y569445D02*
X563978Y572500D01*
G01X560923Y568257D02*
Y569445D01*
G01X560301Y567635D02*
X560923Y568257D01*
G01X560301Y557662D02*
Y567635D01*
G01X562006Y555957D02*
X560301Y557662D01*
G01X560766Y554717D02*
X562006Y555957D01*
G01X560766Y551807D02*
Y554717D01*
G01X563916Y548657D02*
X560766Y551807D01*
G01X563916Y546524D02*
Y548657D01*
G01X563692Y546300D02*
X563916Y546524D01*
G01X563692Y538124D02*
Y546300D01*
G01X563916Y537900D02*
X563692Y538124D01*
G01X563916Y536142D02*
Y537900D01*
G01X562918Y535144D02*
X563916Y536142D01*
G01X562918Y530473D02*
Y535144D01*
G01X563966Y529425D02*
X562918Y530473D01*
G01X563966Y528074D02*
Y529425D01*
G01X563692Y527800D02*
X563966Y528074D01*
G01X586503Y566699D02*
X585431D01*
G01X587203Y565999D02*
X586503Y566699D01*
G01X587203Y564725D02*
Y565999D01*
G01X586066Y563588D02*
X587203Y564725D01*
G01X586066Y562512D02*
Y563588D01*
G01X587078Y561500D02*
X586066Y562512D01*
G01X587078Y560300D02*
Y561500D01*
G01X586066Y559288D02*
X587078Y560300D01*
G01X586066Y558212D02*
Y559288D01*
G01X587178Y557100D02*
X586066Y558212D01*
G01X587178Y554467D02*
Y557100D01*
G01X587003Y554292D02*
X587178Y554467D01*
G01X587003Y552600D02*
Y554292D01*
G01X588689Y550914D02*
X587003Y552600D01*
G01X588777Y550914D02*
X588689D01*
G01X590123Y549568D02*
X588777Y550914D01*
G01X590166Y549568D02*
X590123D01*
G01X590166Y546826D02*
Y549568D01*
G01X590492Y546500D02*
X590166Y546826D01*
G01X590492Y538000D02*
Y546500D01*
G01X590166Y537674D02*
X590492Y538000D01*
G01X590166Y536427D02*
Y537674D01*
G01X590832Y535761D02*
X590166Y536427D01*
G01X590832Y530199D02*
Y535761D01*
G01X590266Y529633D02*
X590832Y530199D01*
G01X590266Y528142D02*
Y529633D01*
G01X591786Y526622D02*
X590266Y528142D01*
G01X776699Y31700D02*
X778275Y33276D01*
G01X775475Y31700D02*
X776699D01*
G01X773228Y29453D02*
X775475Y31700D01*
G01X773228Y27899D02*
Y29453D01*
G01X783200Y31900D02*
X784656Y33356D01*
G01X781800Y31900D02*
X783200D01*
G01X779921Y30021D02*
X781800Y31900D01*
G01X779921Y27899D02*
Y30021D01*
G01X777500Y48688D02*
X776274Y49914D01*
G01X777500Y35675D02*
Y48688D01*
G01X778275Y34900D02*
X777500Y35675D01*
G01X778275Y33276D02*
Y34900D01*
G01X778100Y86400D02*
Y146550D01*
G01X777900Y86200D02*
X778100Y86400D01*
G01X777900Y72400D02*
Y86200D01*
G01X778000Y72300D02*
X777900Y72400D01*
G01X778000Y67000D02*
Y72300D01*
G01X777500Y66500D02*
X778000Y67000D01*
G01X777500Y56530D02*
Y66500D01*
G01X774288Y53318D02*
X777500Y56530D01*
G01X774288Y51900D02*
Y53318D01*
G01X776274Y49914D02*
X774288Y51900D01*
G01X779921Y62821D02*
Y54957D01*
G01X781900Y64800D02*
X779921Y62821D01*
G01X781900Y66150D02*
Y64800D01*
G01X780600Y67450D02*
X781900Y66150D01*
G01X780600Y72000D02*
Y67450D01*
G01X781800Y73200D02*
X780600Y72000D01*
G01X781800Y85300D02*
Y73200D01*
G01X780700Y86400D02*
X781800Y85300D01*
G01X780700Y91000D02*
Y86400D01*
G01X781988Y92288D02*
X780700Y91000D01*
G01X781988Y94212D02*
Y92288D01*
G01X780600Y95600D02*
X781988Y94212D01*
G01X781700Y34567D02*
X782567Y33700D01*
G01X781700Y36868D02*
Y34567D01*
G01X780067Y38501D02*
X781700Y36868D01*
G01X780067Y39800D02*
Y38501D01*
G01X781417Y41150D02*
X780067Y39800D01*
G01X781417Y42050D02*
Y41150D01*
G01X780167Y43300D02*
X781417Y42050D01*
G01X780167Y44499D02*
Y43300D01*
G01X781700Y46032D02*
X780167Y44499D01*
G01X781700Y48000D02*
Y46032D01*
G01X778800Y50900D02*
X781700Y48000D01*
G01X778800Y53836D02*
Y50900D01*
G01X779921Y54957D02*
X778800Y53836D01*
G01X775100Y91900D02*
Y146500D01*
G01X774400Y91200D02*
X775100Y91900D01*
G01X774400Y86400D02*
Y91200D01*
G01X775100Y85700D02*
X774400Y86400D01*
G01X775100Y73000D02*
Y85700D01*
G01X774200Y72100D02*
X775100Y73000D01*
G01X774200Y67200D02*
Y72100D01*
G01X775100Y66300D02*
X774200Y67200D01*
G01X775100Y61000D02*
Y66300D01*
G01X773228Y59128D02*
X775100Y61000D01*
G01X773228Y54957D02*
Y59128D01*
G01X772300Y54029D02*
X773228Y54957D01*
G01X772300Y50901D02*
Y54029D01*
G01X775100Y48101D02*
X772300Y50901D01*
G01X775100Y46232D02*
Y48101D01*
G01X773717Y44849D02*
X775100Y46232D01*
G01X773717Y43450D02*
Y44849D01*
G01X775167Y42000D02*
X773717Y43450D01*
G01X775167Y40800D02*
Y42000D01*
G01X773667Y39300D02*
X775167Y40800D01*
G01X773667Y38101D02*
Y39300D01*
G01X775100Y36668D02*
X773667Y38101D01*
G01X775100Y34788D02*
Y36668D01*
G01X776188Y33700D02*
X775100Y34788D01*
G01X784040Y48441D02*
X782567Y49914D01*
G01X784040Y35316D02*
Y48441D01*
G01X784656Y34700D02*
X784040Y35316D01*
G01X784656Y33356D02*
Y34700D01*
G01X784488Y93688D02*
X785600Y94800D01*
G01X784488Y63988D02*
Y93688D01*
G01X781988Y61488D02*
X784488Y63988D01*
G01X781988Y54588D02*
Y61488D01*
G01X780494Y53094D02*
X781988Y54588D01*
G01X780494Y51987D02*
Y53094D01*
G01X782567Y49914D02*
X780494Y51987D01*
G01X778100Y146550D02*
X861000Y229450D01*
G01X780600Y98934D02*
Y95600D01*
G01X781210Y99544D02*
X780600Y98934D01*
G01X782790Y99544D02*
X781210D01*
G01X783400Y100154D02*
X782790Y99544D01*
G01X783400Y101544D02*
Y100154D01*
G01X782790Y102154D02*
X783400Y101544D01*
G01X781210Y102154D02*
X782790D01*
G01X780600Y102764D02*
X781210Y102154D01*
G01X780600Y104154D02*
Y102764D01*
G01X781210Y104764D02*
X780600Y104154D01*
G01X782790Y104764D02*
X781210D01*
G01X783400Y105374D02*
X782790Y104764D01*
G01X783400Y106764D02*
Y105374D01*
G01X782790Y107374D02*
X783400Y106764D01*
G01X782000Y107374D02*
X782790D01*
G01X781500Y107874D02*
X782000Y107374D01*
G01X781500Y125402D02*
Y107874D01*
G01X780350Y126552D02*
X781500Y125402D01*
G01X780350Y128012D02*
Y126552D01*
G01X781500Y129162D02*
X780350Y128012D01*
G01X781500Y130622D02*
Y129162D01*
G01X780350Y131772D02*
X781500Y130622D01*
G01X780350Y133232D02*
Y131772D01*
G01X781500Y134382D02*
X780350Y133232D01*
G01X781500Y135842D02*
Y134382D01*
G01X780350Y136992D02*
X781500Y135842D01*
G01X780350Y138452D02*
Y136992D01*
G01X781500Y139602D02*
X780350Y138452D01*
G01X781500Y141062D02*
Y139602D01*
G01X780350Y142212D02*
X781500Y141062D01*
G01X780350Y143672D02*
Y142212D01*
G01X781500Y144822D02*
X780350Y143672D01*
G01X781500Y147150D02*
Y144822D01*
G01X794300Y159950D02*
X781500Y147150D01*
G01X775100Y146500D02*
X860600Y232000D01*
G01X783550Y146350D02*
X794675Y157475D01*
G01X783550Y109650D02*
Y146350D01*
G01X785600Y107600D02*
X783550Y109650D01*
G01X785600Y94800D02*
Y107600D01*
G01X782600Y456499D02*
Y507296D01*
G01X783259Y455840D02*
X782600Y456499D01*
G01X784049Y455841D02*
X783259Y455840D01*
G01X786607Y458399D02*
X784049Y455841D01*
G01X787399Y458399D02*
X786607D01*
G01X785861Y454030D02*
X788419Y456588D01*
G01X785861Y453238D02*
Y454030D01*
G01X786881Y452218D02*
X785861Y453238D01*
G01X777574Y456025D02*
Y510952D01*
G01X789336Y444263D02*
X777574Y456025D01*
G01X775386Y455569D02*
Y510417D01*
G01X810255Y420700D02*
X775386Y455569D01*
G01X780074Y456325D02*
Y507775D01*
G01X789799Y446600D02*
X780074Y456325D01*
G01X786200Y525748D02*
Y526900D01*
G01X785590Y525138D02*
X786200Y525748D01*
G01X783810Y525138D02*
X785590D01*
G01X783100Y524428D02*
X783810Y525138D01*
G01X783100Y522448D02*
Y524428D01*
G01X783610Y521938D02*
X783100Y522448D01*
G01X785590Y521938D02*
X783610D01*
G01X786200Y521328D02*
X785590Y521938D01*
G01X786200Y520400D02*
Y521328D01*
G01X784474Y518674D02*
X786200Y520400D01*
G01X784474Y509170D02*
Y518674D01*
G01X782600Y507296D02*
X784474Y509170D01*
G01X777300Y517326D02*
Y529193D01*
G01X778274Y516352D02*
X777300Y517326D01*
G01X778274Y511652D02*
Y516352D01*
G01X777574Y510952D02*
X778274Y511652D01*
G01X775028Y517709D02*
Y529124D01*
G01X774374Y516130D02*
X775028Y517709D01*
G01X774374Y512861D02*
Y516130D01*
G01X774979Y511400D02*
X774374Y512861D01*
G01X775145Y511000D02*
X774979Y511400D01*
G01X775386Y510417D02*
X775145Y511000D01*
G01X780800Y520674D02*
Y527100D01*
G01X781974Y519500D02*
X780800Y520674D01*
G01X781974Y517774D02*
Y519500D01*
G01X780674Y516474D02*
X781974Y517774D01*
G01X780674Y511952D02*
Y516474D01*
G01X781571Y511055D02*
X780674Y511952D01*
G01X781571Y509272D02*
Y511055D01*
G01X780074Y507775D02*
X781571Y509272D01*
G01X782567Y550564D02*
Y550914D01*
G01X784474Y548657D02*
X782567Y550564D01*
G01X784474Y546826D02*
Y548657D01*
G01X785000Y546300D02*
X784474Y546826D01*
G01X785000Y538226D02*
Y546300D01*
G01X784474Y537700D02*
X785000Y538226D01*
G01X784474Y528626D02*
Y537700D01*
G01X786200Y526900D02*
X784474Y528626D01*
G01X780901Y566699D02*
X779921D01*
G01X781500Y566100D02*
X780901Y566699D01*
G01X781500Y564900D02*
Y566100D01*
G01X780556Y563956D02*
X781500Y564900D01*
G01X780556Y562744D02*
Y563956D01*
G01X781400Y561900D02*
X780556Y562744D01*
G01X781400Y560200D02*
Y561900D01*
G01X780556Y559356D02*
X781400Y560200D01*
G01X780556Y557936D02*
Y559356D01*
G01X781700Y556792D02*
X780556Y557936D01*
G01X781700Y555199D02*
Y556792D01*
G01X780793Y554292D02*
X781700Y555199D01*
G01X780793Y552600D02*
Y554292D01*
G01X782479Y550914D02*
X780793Y552600D01*
G01X782567Y550914D02*
X782479D01*
G01X777774Y549414D02*
X776274Y550914D01*
G01X777774Y546726D02*
Y549414D01*
G01X778300Y546200D02*
X777774Y546726D01*
G01X778300Y538026D02*
Y546200D01*
G01X777774Y537500D02*
X778300Y538026D01*
G01X777774Y535867D02*
Y537500D01*
G01X778340Y535301D02*
X777774Y535867D01*
G01X778340Y530233D02*
Y535301D01*
G01X777300Y529193D02*
X778340Y530233D01*
G01X774300Y566699D02*
X773228D01*
G01X774900Y566099D02*
X774300Y566699D01*
G01X774900Y565201D02*
Y566099D01*
G01X773863Y564164D02*
X774900Y565201D01*
G01X773863Y562936D02*
Y564164D01*
G01X774800Y561999D02*
X773863Y562936D01*
G01X774800Y560601D02*
Y561999D01*
G01X773863Y559664D02*
X774800Y560601D01*
G01X773863Y558336D02*
Y559664D01*
G01X775000Y557199D02*
X773863Y558336D01*
G01X775000Y555300D02*
Y557199D01*
G01X774500Y554800D02*
X775000Y555300D01*
G01X774500Y552600D02*
Y554800D01*
G01X776186Y550914D02*
X774500Y552600D01*
G01X776274Y550914D02*
X776186D01*
G01X772799Y555528D02*
X773228Y555957D01*
G01X772799Y551833D02*
Y555528D01*
G01X774124Y550508D02*
X772799Y551833D01*
G01X775107Y548134D02*
X774124Y550508D01*
G01X775107Y536902D02*
Y548134D01*
G01X774274Y534890D02*
X775107Y536902D01*
G01X774274Y530946D02*
Y534890D01*
G01X775028Y529124D02*
X774274Y530946D01*
G01X771523Y567835D02*
X776188Y572500D01*
G01X771523Y557662D02*
Y567835D01*
G01X773228Y555957D02*
X771523Y557662D01*
G01X779921Y555891D02*
Y555957D01*
G01X778958Y554928D02*
X779921Y555891D01*
G01X778958Y551398D02*
Y554928D01*
G01X781774Y548582D02*
X778958Y551398D01*
G01X781774Y546974D02*
Y548582D01*
G01X781600Y546800D02*
X781774Y546974D01*
G01X781600Y538074D02*
Y546800D01*
G01X781774Y537900D02*
X781600Y538074D01*
G01X781774Y536475D02*
Y537900D01*
G01X780674Y535375D02*
X781774Y536475D01*
G01X780674Y530581D02*
Y535375D01*
G01X781974Y529281D02*
X780674Y530581D01*
G01X781974Y528274D02*
Y529281D01*
G01X780800Y527100D02*
X781974Y528274D01*
G01X781401Y572500D02*
X782567D01*
G01X778216Y569315D02*
X781401Y572500D01*
G01X778216Y557662D02*
Y569315D01*
G01X779921Y555957D02*
X778216Y557662D01*
G01X816732Y30021D02*
Y27899D01*
G01X818611Y31900D02*
X816732Y30021D01*
G01X820011Y31900D02*
X818611D01*
G01X821467Y33356D02*
X820011Y31900D01*
G01X800200Y31700D02*
X802000Y33500D01*
G01X799200Y31700D02*
X800200D01*
G01X797900Y30400D02*
X799200Y31700D01*
G01X797900Y29146D02*
Y30400D01*
G01X796653Y27899D02*
X797900Y29146D01*
G01X834711D02*
X833464Y27899D01*
G01X834711Y30400D02*
Y29146D01*
G01X836011Y31700D02*
X834711Y30400D01*
G01X837011Y31700D02*
X836011D01*
G01X838811Y33500D02*
X837011Y31700D01*
G01X806893D02*
X808693Y33500D01*
G01X805893Y31700D02*
X806893D01*
G01X804593Y30400D02*
X805893Y31700D01*
G01X804593Y29146D02*
Y30400D01*
G01X803346Y27899D02*
X804593Y29146D01*
G01X843704Y31700D02*
X845504Y33500D01*
G01X842704Y31700D02*
X843704D01*
G01X841404Y30400D02*
X842704Y31700D01*
G01X841404Y29146D02*
Y30400D01*
G01X840157Y27899D02*
X841404Y29146D01*
G01X813510Y31700D02*
X815086Y33276D01*
G01X812286Y31700D02*
X813510D01*
G01X810039Y29453D02*
X812286Y31700D01*
G01X810039Y27899D02*
Y29453D01*
G01X846850D02*
Y27899D01*
G01X849097Y31700D02*
X846850Y29453D01*
G01X821467Y34700D02*
Y33356D01*
G01X820851Y35316D02*
X821467Y34700D01*
G01X820851Y48441D02*
Y35316D01*
G01X819378Y49914D02*
X820851Y48441D01*
G01X817500Y51792D02*
X819378Y49914D01*
G01X817500Y53199D02*
Y51792D01*
G01X818799Y54498D02*
X817500Y53199D01*
G01X818799Y60766D02*
Y54498D01*
G01X821299Y63266D02*
X818799Y60766D01*
G01X821299Y92964D02*
Y63266D01*
G01X822500Y96164D02*
X821299Y92964D01*
G01X798488Y91618D02*
Y111738D01*
G01X798088Y91218D02*
X798488Y91618D01*
G01X798088Y86518D02*
Y91218D01*
G01X798888Y85718D02*
X798088Y86518D01*
G01X798888Y73287D02*
Y85718D01*
G01X798088Y72487D02*
X798888Y73287D01*
G01X798088Y66903D02*
Y72487D01*
G01X798688Y66303D02*
X798088Y66903D01*
G01X798688Y59218D02*
Y66303D01*
G01X796653Y57183D02*
X798688Y59218D01*
G01X796653Y54957D02*
Y57183D01*
G01X795725Y54029D02*
X796653Y54957D01*
G01X795725Y50901D02*
Y54029D01*
G01X798767Y47859D02*
X795725Y50901D01*
G01X798767Y46474D02*
Y47859D01*
G01X797092Y44799D02*
X798767Y46474D01*
G01X797092Y43676D02*
Y44799D01*
G01X798592Y42176D02*
X797092Y43676D01*
G01X798592Y40824D02*
Y42176D01*
G01X797092Y39324D02*
X798592Y40824D01*
G01X797092Y38101D02*
Y39324D01*
G01X798525Y36668D02*
X797092Y38101D01*
G01X798525Y35574D02*
Y36668D01*
G01X799999Y34100D02*
X798525Y35574D01*
G01X801388Y48525D02*
X799999Y49914D01*
G01X801388Y35512D02*
Y48525D01*
G01X802000Y34900D02*
X801388Y35512D01*
G01X802000Y33500D02*
Y34900D01*
G01X801000Y92206D02*
Y110250D01*
G01X802188Y91018D02*
X801000Y92206D01*
G01X802188Y86518D02*
Y91018D01*
G01X801388Y85718D02*
X802188Y86518D01*
G01X801388Y73011D02*
Y85718D01*
G01X802288Y72111D02*
X801388Y73011D01*
G01X802288Y67253D02*
Y72111D01*
G01X801188Y66153D02*
X802288Y67253D01*
G01X801188Y58182D02*
Y66153D01*
G01X799638Y56632D02*
X801188Y58182D01*
G01X799638Y55008D02*
Y56632D01*
G01X798188Y53558D02*
X799638Y55008D01*
G01X798188Y51725D02*
Y53558D01*
G01X799999Y49914D02*
X798188Y51725D01*
G01X841936Y35667D02*
X843503Y34100D01*
G01X841936Y36868D02*
Y35667D01*
G01X840578Y38226D02*
X841936Y36868D01*
G01X840578Y39599D02*
Y38226D01*
G01X841778Y40799D02*
X840578Y39599D01*
G01X841778Y41925D02*
Y40799D01*
G01X840578Y43125D02*
X841778Y41925D01*
G01X840578Y44700D02*
Y43125D01*
G01X842378Y46500D02*
X840578Y44700D01*
G01X842378Y47558D02*
Y46500D01*
G01X839036Y50900D02*
X842378Y47558D01*
G01X839036Y53836D02*
Y50900D01*
G01X840157Y54957D02*
X839036Y53836D01*
G01X840157Y62957D02*
Y54957D01*
G01X842000Y64800D02*
X840157Y62957D01*
G01X842000Y66402D02*
Y64800D01*
G01X841599Y66803D02*
X842000Y66402D01*
G01X841599Y72599D02*
Y66803D01*
G01X842099Y73099D02*
X841599Y72599D01*
G01X842099Y85818D02*
Y73099D01*
G01X841499Y86418D02*
X842099Y85818D01*
G01X841499Y91118D02*
Y86418D01*
G01X841974Y91593D02*
X841499Y91118D01*
G01X841974Y93674D02*
Y91593D01*
G01X840100Y95548D02*
X841974Y93674D01*
G01X811999Y92118D02*
Y95074D01*
G01X811099Y91218D02*
X811999Y92118D01*
G01X811099Y86418D02*
Y91218D01*
G01X812099Y85418D02*
X811099Y86418D01*
G01X812099Y73103D02*
Y85418D01*
G01X811099Y72103D02*
X812099Y73103D01*
G01X811099Y67201D02*
Y72103D01*
G01X811999Y66301D02*
X811099Y67201D01*
G01X811999Y64998D02*
Y66301D01*
G01X811100Y64099D02*
X811999Y64998D01*
G01X811100Y57319D02*
Y64099D01*
G01X810039Y56258D02*
X811100Y57319D01*
G01X810039Y54957D02*
Y56258D01*
G01X809111Y54029D02*
X810039Y54957D01*
G01X809111Y50901D02*
Y54029D01*
G01X811911Y48101D02*
X809111Y50901D01*
G01X811911Y46232D02*
Y48101D01*
G01X810528Y44849D02*
X811911Y46232D01*
G01X810528Y43450D02*
Y44849D01*
G01X811978Y42000D02*
X810528Y43450D01*
G01X811978Y40800D02*
Y42000D01*
G01X810478Y39300D02*
X811978Y40800D01*
G01X810478Y38101D02*
Y39300D01*
G01X811911Y36668D02*
X810478Y38101D01*
G01X811911Y34788D02*
Y36668D01*
G01X812999Y33700D02*
X811911Y34788D01*
G01X834999Y51725D02*
X836810Y49914D01*
G01X834999Y53670D02*
Y51725D01*
G01X835474Y54145D02*
X834999Y53670D01*
G01X835474Y55657D02*
Y54145D01*
G01X837999Y58182D02*
X835474Y55657D01*
G01X837999Y66153D02*
Y58182D01*
G01X839099Y67253D02*
X837999Y66153D01*
G01X839099Y72201D02*
Y67253D01*
G01X838199Y73101D02*
X839099Y72201D01*
G01X838199Y85718D02*
Y73101D01*
G01X838999Y86518D02*
X838199Y85718D01*
G01X838999Y91018D02*
Y86518D01*
G01X838299Y91718D02*
X838999Y91018D01*
G01X838299Y92800D02*
Y91718D01*
G01X837600Y93499D02*
X838299Y92800D01*
G01X837600Y121350D02*
Y93499D01*
G01X838811Y34900D02*
Y33500D01*
G01X838199Y35512D02*
X838811Y34900D01*
G01X838199Y48525D02*
Y35512D01*
G01X836810Y49914D02*
X838199Y48525D01*
G01X805638Y93463D02*
X803500Y95601D01*
G01X805638Y92068D02*
Y93463D01*
G01X804688Y91118D02*
X805638Y92068D01*
G01X804688Y86418D02*
Y91118D01*
G01X805288Y85818D02*
X804688Y86418D01*
G01X805288Y73087D02*
Y85818D01*
G01X804788Y72587D02*
X805288Y73087D01*
G01X804788Y66803D02*
Y72587D01*
G01X805588Y66003D02*
X804788Y66803D01*
G01X805588Y57819D02*
Y66003D01*
G01X803346Y55577D02*
X805588Y57819D01*
G01X803346Y54957D02*
Y55577D01*
G01X802225Y53836D02*
X803346Y54957D01*
G01X802225Y50900D02*
Y53836D01*
G01X805567Y47558D02*
X802225Y50900D01*
G01X805567Y46500D02*
Y47558D01*
G01X803767Y44700D02*
X805567Y46500D01*
G01X803767Y43125D02*
Y44700D01*
G01X804967Y41925D02*
X803767Y43125D01*
G01X804967Y40799D02*
Y41925D01*
G01X803767Y39599D02*
X804967Y40799D01*
G01X803767Y38226D02*
Y39599D01*
G01X805125Y36868D02*
X803767Y38226D01*
G01X805125Y35667D02*
Y36868D01*
G01X806692Y34100D02*
X805125Y35667D01*
G01X808081Y48525D02*
X806692Y49914D01*
G01X808081Y35512D02*
Y48525D01*
G01X808693Y34900D02*
X808081Y35512D01*
G01X808693Y33500D02*
Y34900D01*
G01X808138Y91668D02*
Y96089D01*
G01X808788Y91018D02*
X808138Y91668D01*
G01X808788Y86618D02*
Y91018D01*
G01X808088Y85918D02*
X808788Y86618D01*
G01X808088Y73111D02*
Y85918D01*
G01X808688Y72511D02*
X808088Y73111D01*
G01X808688Y67053D02*
Y72511D01*
G01X808138Y66503D02*
X808688Y67053D01*
G01X808138Y56768D02*
Y66503D01*
G01X804788Y53418D02*
X808138Y56768D01*
G01X804788Y51818D02*
Y53418D01*
G01X806692Y49914D02*
X804788Y51818D01*
G01X844892Y48525D02*
X843503Y49914D01*
G01X844892Y35512D02*
Y48525D01*
G01X845504Y34900D02*
X844892Y35512D01*
G01X845504Y33500D02*
Y34900D01*
G01X844949Y91668D02*
Y99920D01*
G01X845599Y91018D02*
X844949Y91668D01*
G01X845599Y86618D02*
Y91018D01*
G01X844899Y85918D02*
X845599Y86618D01*
G01X844899Y73001D02*
Y85918D01*
G01X845499Y72401D02*
X844899Y73001D01*
G01X845499Y67053D02*
Y72401D01*
G01X844949Y66503D02*
X845499Y67053D01*
G01X844949Y64100D02*
Y66503D01*
G01X843090Y62241D02*
X844949Y64100D01*
G01X843090Y54909D02*
Y62241D01*
G01X841599Y53418D02*
X843090Y54909D01*
G01X841599Y51818D02*
Y53418D01*
G01X843503Y49914D02*
X841599Y51818D01*
G01X814311Y48688D02*
X813085Y49914D01*
G01X814311Y35675D02*
Y48688D01*
G01X815086Y34900D02*
X814311Y35675D01*
G01X815086Y33276D02*
Y34900D01*
G01X814885Y93272D02*
X817256Y97488D01*
G01X814885Y86404D02*
Y93272D01*
G01X814782Y86301D02*
X814885Y86404D01*
G01X814782Y73020D02*
Y86301D01*
G01X814799Y73003D02*
X814782Y73020D01*
G01X814799Y64199D02*
Y73003D01*
G01X813040Y55259D02*
X814799Y64199D01*
G01X811235Y53454D02*
X813040Y55259D01*
G01X811235Y51764D02*
Y53454D01*
G01X813085Y49914D02*
X811235Y51764D01*
G01X815611Y53836D02*
X816732Y54957D01*
G01X815611Y50900D02*
Y53836D01*
G01X818511Y48000D02*
X815611Y50900D01*
G01X818511Y46032D02*
Y48000D01*
G01X816978Y44499D02*
X818511Y46032D01*
G01X816978Y43300D02*
Y44499D01*
G01X818228Y42050D02*
X816978Y43300D01*
G01X818228Y41150D02*
Y42050D01*
G01X816878Y39800D02*
X818228Y41150D01*
G01X816878Y38501D02*
Y39800D01*
G01X818511Y36868D02*
X816878Y38501D01*
G01X818511Y34567D02*
Y36868D01*
G01X819378Y33700D02*
X818511Y34567D01*
G01X818790Y92339D02*
Y94990D01*
G01X817449Y90998D02*
X818790Y92339D01*
G01X817449Y86718D02*
Y90998D01*
G01X818799Y85368D02*
X817449Y86718D01*
G01X818799Y73499D02*
Y85368D01*
G01X817449Y72149D02*
X818799Y73499D01*
G01X817449Y67401D02*
Y72149D01*
G01X818599Y66251D02*
X817449Y67401D01*
G01X818599Y64698D02*
Y66251D01*
G01X816732Y62831D02*
X818599Y64698D01*
G01X816732Y54957D02*
Y62831D01*
G01X845922Y54029D02*
X846850Y54957D01*
G01X845922Y50901D02*
Y54029D01*
G01X848722Y48101D02*
X845922Y50901D01*
G01X847339Y44849D02*
X848722Y46232D01*
G01X847339Y43450D02*
Y44849D01*
G01X848789Y42000D02*
X847339Y43450D01*
G01X847289Y39300D02*
X848789Y40800D01*
G01X847289Y38101D02*
Y39300D01*
G01X848722Y36668D02*
X847289Y38101D01*
G01X847910Y91218D02*
X848810Y92118D01*
G01X847910Y86418D02*
Y91218D01*
G01X848910Y85418D02*
X847910Y86418D01*
G01Y72103D02*
X848910Y73103D01*
G01X847910Y67191D02*
Y72103D01*
G01X848810Y66291D02*
X847910Y67191D01*
G01X846850Y61750D02*
X848810Y63710D01*
G01X846850Y59450D02*
Y61750D01*
G01X847884Y58416D02*
X846850Y59450D01*
G01X847884Y57283D02*
Y58416D01*
G01X846850Y56249D02*
X847884Y57283D01*
G01X846850Y54957D02*
Y56249D01*
G01X832536Y54029D02*
X833464Y54957D01*
G01X832536Y50901D02*
Y54029D01*
G01X835578Y47859D02*
X832536Y50901D01*
G01X835578Y46474D02*
Y47859D01*
G01X833903Y44799D02*
X835578Y46474D01*
G01X833903Y43676D02*
Y44799D01*
G01X835403Y42176D02*
X833903Y43676D01*
G01X835403Y40824D02*
Y42176D01*
G01X833903Y39324D02*
X835403Y40824D01*
G01X833903Y38101D02*
Y39324D01*
G01X835336Y36668D02*
X833903Y38101D01*
G01X835336Y35574D02*
Y36668D01*
G01X836810Y34100D02*
X835336Y35574D01*
G01X835100Y93999D02*
Y123050D01*
G01X835299Y93800D02*
X835100Y93999D01*
G01X835299Y91618D02*
Y93800D01*
G01X834899Y91218D02*
X835299Y91618D01*
G01X834899Y86518D02*
Y91218D01*
G01X835699Y85718D02*
X834899Y86518D01*
G01X835699Y73499D02*
Y85718D01*
G01X834899Y72699D02*
X835699Y73499D01*
G01X834899Y66903D02*
Y72699D01*
G01X835499Y66303D02*
X834899Y66903D01*
G01X835499Y59218D02*
Y66303D01*
G01X833464Y57183D02*
X835499Y59218D01*
G01X833464Y54957D02*
Y57183D01*
G01X847910Y51900D02*
X849896Y49914D01*
G01X847910Y53318D02*
Y51900D01*
G01X850530Y55938D02*
X847910Y53318D01*
G01X822500Y104600D02*
Y96164D01*
G01X825000Y107100D02*
X822500Y104600D01*
G01X825000Y126851D02*
Y107100D01*
G01X828970Y130821D02*
X825000Y126851D01*
G01X828970Y131683D02*
Y130821D01*
G01X827884Y132770D02*
X828970Y131683D01*
G01X827884Y133632D02*
Y132770D01*
G01X828868Y134616D02*
X827884Y133632D01*
G01X829730Y134616D02*
X828868D01*
G01X830816Y133529D02*
X829730Y134616D01*
G01X831678Y133529D02*
X830816D01*
G01X832650Y134501D02*
X831678Y133529D01*
G01X832650Y148150D02*
Y134501D01*
G01X902450Y217950D02*
X832650Y148150D01*
G01X800400Y142774D02*
X817355Y159729D01*
G01X800400Y138831D02*
Y142774D01*
G01X799790Y138221D02*
X800400Y138831D01*
G01X797660Y138221D02*
X799790D01*
G01X797050Y137611D02*
X797660Y138221D01*
G01X797050Y136221D02*
Y137611D01*
G01X797660Y135611D02*
X797050Y136221D01*
G01X799790Y135611D02*
X797660D01*
G01X800400Y135001D02*
X799790Y135611D01*
G01X800400Y133611D02*
Y135001D01*
G01X799790Y133001D02*
X800400Y133611D01*
G01X797560Y133001D02*
X799790D01*
G01X796950Y132391D02*
X797560Y133001D01*
G01X796950Y131001D02*
Y132391D01*
G01X797560Y130391D02*
X796950Y131001D01*
G01X799790Y130391D02*
X797560D01*
G01X800400Y129781D02*
X799790Y130391D01*
G01X800400Y128391D02*
Y129781D01*
G01X799790Y127781D02*
X800400Y128391D01*
G01X797560Y127781D02*
X799790D01*
G01X796950Y127171D02*
X797560Y127781D01*
G01X796950Y125781D02*
Y127171D01*
G01X797560Y125171D02*
X796950Y125781D01*
G01X799790Y125171D02*
X797560D01*
G01X800400Y124561D02*
X799790Y125171D01*
G01X800400Y123171D02*
Y124561D01*
G01X799790Y122561D02*
X800400Y123171D01*
G01X797560Y122561D02*
X799790D01*
G01X796950Y121951D02*
X797560Y122561D01*
G01X796950Y120561D02*
Y121951D01*
G01X797560Y119951D02*
X796950Y120561D01*
G01X799790Y119951D02*
X797560D01*
G01X800400Y119341D02*
X799790Y119951D01*
G01X800400Y113650D02*
Y119341D01*
G01X798488Y111738D02*
X800400Y113650D01*
G01X802550Y141388D02*
X830000Y168838D01*
G01X802550Y111800D02*
Y141388D01*
G01X801000Y110250D02*
X802550Y111800D01*
G01X840100Y119400D02*
Y95548D01*
G01X865592Y144892D02*
X840100Y119400D01*
G01X817500Y143608D02*
X894950Y221058D01*
G01X817500Y110950D02*
Y143608D01*
G01X814547Y107997D02*
X817500Y110950D01*
G01X814547Y97622D02*
Y107997D01*
G01X811999Y95074D02*
X814547Y97622D01*
G01X861364Y145114D02*
X837600Y121350D01*
G01X811400Y145950D02*
X855268Y189818D01*
G01X811400Y137231D02*
Y145950D01*
G01X810790Y136621D02*
X811400Y137231D01*
G01X806960Y136621D02*
X810790D01*
G01X806350Y136011D02*
X806960Y136621D01*
G01X806350Y134621D02*
Y136011D01*
G01X806960Y134011D02*
X806350Y134621D01*
G01X810790Y134011D02*
X806960D01*
G01X811400Y133401D02*
X810790Y134011D01*
G01X811400Y131650D02*
Y133401D01*
G01X810600Y130850D02*
X811400Y131650D01*
G01X805650Y130850D02*
X810600D01*
G01X805150Y130350D02*
X805650Y130850D01*
G01X805150Y110350D02*
Y130350D01*
G01X803500Y108700D02*
X805150Y110350D01*
G01X803500Y95601D02*
Y108700D01*
G01X814250Y145100D02*
X891700Y222550D01*
G01X814250Y129368D02*
Y145100D01*
G01X813640Y128758D02*
X814250Y129368D01*
G01X809260Y128758D02*
X813640D01*
G01X808650Y128148D02*
X809260Y128758D01*
G01X808650Y126758D02*
Y128148D01*
G01X809260Y126148D02*
X808650Y126758D01*
G01X813640Y126148D02*
X809260D01*
G01X814250Y125538D02*
X813640Y126148D01*
G01X814250Y124148D02*
Y125538D01*
G01X813640Y123538D02*
X814250Y124148D01*
G01X809260Y123538D02*
X813640D01*
G01X808650Y122928D02*
X809260Y123538D01*
G01X808650Y121538D02*
Y122928D01*
G01X809260Y120928D02*
X808650Y121538D01*
G01X813640Y120928D02*
X809260D01*
G01X814250Y120318D02*
X813640Y120928D01*
G01X814250Y118928D02*
Y120318D01*
G01X813640Y118318D02*
X814250Y118928D01*
G01X809260Y118318D02*
X813640D01*
G01X808650Y117708D02*
X809260Y118318D01*
G01X808650Y116318D02*
Y117708D01*
G01X809260Y115708D02*
X808650Y116318D01*
G01X813640Y115708D02*
X809260D01*
G01X814250Y115098D02*
X813640Y115708D01*
G01X814250Y112899D02*
Y115098D01*
G01X813126Y111775D02*
X814250Y112899D01*
G01X811000Y111775D02*
X813126D01*
G01X810500Y111275D02*
X811000Y111775D01*
G01X810500Y108376D02*
Y111275D01*
G01X809890Y107766D02*
X810500Y108376D01*
G01X806710Y107766D02*
X809890D01*
G01X806100Y107156D02*
X806710Y107766D01*
G01X806100Y105766D02*
Y107156D01*
G01X806710Y105156D02*
X806100Y105766D01*
G01X809890Y105156D02*
X806710D01*
G01X810500Y104546D02*
X809890Y105156D01*
G01X810500Y103156D02*
Y104546D01*
G01X809890Y102546D02*
X810500Y103156D01*
G01X806710Y102546D02*
X809890D01*
G01X806100Y101936D02*
X806710Y102546D01*
G01X806100Y100546D02*
Y101936D01*
G01X806710Y99936D02*
X806100Y100546D01*
G01X809140Y99936D02*
X806710D01*
G01X809750Y99326D02*
X809140Y99936D01*
G01X809750Y97701D02*
Y99326D01*
G01X808138Y96089D02*
X809750Y97701D01*
G01X847571Y122959D02*
X848834Y121696D01*
G01X846709Y122959D02*
X847571D01*
G01X842600Y118850D02*
X846709Y122959D01*
G01X842600Y116690D02*
Y118850D01*
G01X843210Y116080D02*
X842600Y116690D01*
G01X845400Y116080D02*
X843210D01*
G01X845900Y115580D02*
X845400Y116080D01*
G01X845900Y113970D02*
Y115580D01*
G01X845400Y113470D02*
X845900Y113970D01*
G01X843210Y113470D02*
X845400D01*
G01X842600Y112860D02*
X843210Y113470D01*
G01X842600Y111470D02*
Y112860D01*
G01X843210Y110860D02*
X842600Y111470D01*
G01X845690Y110860D02*
X843210D01*
G01X846300Y110250D02*
X845690Y110860D01*
G01X846300Y108860D02*
Y110250D01*
G01X845690Y108250D02*
X846300Y108860D01*
G01X843210Y108250D02*
X845690D01*
G01X842600Y107640D02*
X843210Y108250D01*
G01X842600Y106250D02*
Y107640D01*
G01X843210Y105640D02*
X842600Y106250D01*
G01X844840Y105640D02*
X843210D01*
G01X845450Y105030D02*
X844840Y105640D01*
G01X845450Y103640D02*
Y105030D01*
G01X844840Y103030D02*
X845450Y103640D01*
G01X843210Y103030D02*
X844840D01*
G01X842600Y102420D02*
X843210Y103030D01*
G01X842600Y101030D02*
Y102420D01*
G01X843210Y100420D02*
X842600Y101030D01*
G01X844449Y100420D02*
X843210D01*
G01X844949Y99920D02*
X844449Y100420D01*
G01X820000Y142572D02*
X897450Y220022D01*
G01X820000Y110150D02*
Y142572D01*
G01X817256Y107406D02*
X820000Y110150D01*
G01X817256Y97488D02*
Y107406D01*
G01X830600Y149636D02*
X899950Y218986D01*
G01X830600Y143110D02*
Y149636D01*
G01X829990Y142500D02*
X830600Y143110D01*
G01X825660Y142500D02*
X829990D01*
G01X825050Y141890D02*
X825660Y142500D01*
G01X825050Y140260D02*
Y141890D01*
G01X825660Y139650D02*
X825050Y140260D01*
G01X829990Y139650D02*
X825660D01*
G01X830600Y139040D02*
X829990Y139650D01*
G01X830600Y137700D02*
Y139040D01*
G01X830000Y137100D02*
X830600Y137700D01*
G01X825700Y137100D02*
X830000D01*
G01X824650Y136050D02*
X825700Y137100D01*
G01X824650Y130801D02*
Y136050D01*
G01X822500Y128651D02*
X824650Y130801D01*
G01X822500Y108900D02*
Y128651D01*
G01X820000Y106400D02*
X822500Y108900D01*
G01X820000Y96200D02*
Y106400D01*
G01X818790Y94990D02*
X820000Y96200D01*
G01X835100Y123050D02*
X856807Y144757D01*
G01X822504Y171104D02*
X867300Y215900D01*
G01X822504Y170396D02*
Y171104D01*
G01X824909Y167991D02*
X822504Y170396D01*
G01X824909Y167283D02*
Y167991D01*
G01X823755Y166129D02*
X824909Y167283D01*
G01X822893Y166129D02*
X823755D01*
G01X820340Y168682D02*
X822893Y166129D01*
G01X819632Y168682D02*
X820340D01*
G01X818494Y167544D02*
X819632Y168682D01*
G01X818494Y166836D02*
Y167544D01*
G01X821047Y164283D02*
X818494Y166836D01*
G01X821047Y163421D02*
Y164283D01*
G01X820063Y162437D02*
X821047Y163421D01*
G01X819201Y162437D02*
X820063D01*
G01X816673Y164965D02*
X819201Y162437D01*
G01X815965Y164965D02*
X816673D01*
G01X814827Y163827D02*
X815965Y164965D01*
G01X814827Y163119D02*
Y163827D01*
G01X817355Y160591D02*
X814827Y163119D01*
G01X817355Y159729D02*
Y160591D01*
G01X847329Y192329D02*
X867050Y212050D01*
G01X847329Y191621D02*
Y192329D01*
G01X849140Y189810D02*
X847329Y191621D01*
G01X847476Y186314D02*
X849140Y187978D01*
G01X846614Y186314D02*
X847476D01*
G01X845170Y187758D02*
X846614Y186314D01*
G01X844308Y187758D02*
X845170D01*
G01X843324Y186774D02*
X844308Y187758D01*
G01X843324Y185912D02*
Y186774D01*
G01X844768Y184468D02*
X843324Y185912D01*
G01X844768Y183606D02*
Y184468D01*
G01X843784Y182622D02*
X844768Y183606D01*
G01X842922Y182622D02*
X843784D01*
G01X841478Y184066D02*
X842922Y182622D01*
G01X840616Y184066D02*
X841478D01*
G01X839632Y183082D02*
X840616Y184066D01*
G01X839632Y182220D02*
Y183082D01*
G01X841076Y180776D02*
X839632Y182220D01*
G01X841076Y179914D02*
Y180776D01*
G01X840092Y178930D02*
X841076Y179914D01*
G01X839230Y178930D02*
X840092D01*
G01X837786Y180374D02*
X839230Y178930D01*
G01X836924Y180374D02*
X837786D01*
G01X835940Y179390D02*
X836924Y180374D01*
G01X835940Y178528D02*
Y179390D01*
G01X837384Y177084D02*
X835940Y178528D01*
G01X837384Y176222D02*
Y177084D01*
G01X836400Y175238D02*
X837384Y176222D01*
G01X835538Y175238D02*
X836400D01*
G01X834094Y176682D02*
X835538Y175238D01*
G01X833232Y176682D02*
X834094D01*
G01X832248Y175698D02*
X833232Y176682D01*
G01X832248Y174836D02*
Y175698D01*
G01X833692Y173392D02*
X832248Y174836D01*
G01X833692Y172530D02*
Y173392D01*
G01X832708Y171546D02*
X833692Y172530D01*
G01X831846Y171546D02*
X832708D01*
G01X830402Y172990D02*
X831846Y171546D01*
G01X829540Y172990D02*
X830402D01*
G01X828556Y172006D02*
X829540Y172990D01*
G01X828556Y171144D02*
Y172006D01*
G01X830000Y169700D02*
X828556Y171144D01*
G01X830000Y168838D02*
Y169700D01*
G01X797550Y159950D02*
X794300D01*
G01X800675Y163075D02*
X797550Y159950D01*
G01X800675Y166325D02*
Y163075D01*
G01X861750Y227400D02*
X800675Y166325D01*
G01X802675Y165475D02*
X862650Y225450D01*
G01X802675Y162275D02*
Y165475D01*
G01X797875Y157475D02*
X802675Y162275D01*
G01X794675Y157475D02*
X797875D01*
G01X865636Y381463D02*
X820399Y426700D01*
G01X861866Y379833D02*
X819099Y422600D01*
G01X857188Y381711D02*
X823816Y415083D01*
G01X863751Y380648D02*
X819799Y424600D01*
G01X799300Y460135D02*
Y501044D01*
G01X806947Y452488D02*
X799300Y460135D01*
G01X806947Y451356D02*
Y452488D01*
G01X806311Y450720D02*
X806947Y451356D01*
G01X806311Y449588D02*
Y450720D01*
G01X807442Y448457D02*
X806311Y449588D01*
G01X808574Y448457D02*
X807442D01*
G01X809210Y449093D02*
X808574Y448457D01*
G01X810342Y449093D02*
X809210D01*
G01X811473Y447962D02*
X810342Y449093D01*
G01X811473Y446830D02*
Y447962D01*
G01X810837Y446194D02*
X811473Y446830D01*
G01X810837Y445062D02*
Y446194D01*
G01X811968Y443931D02*
X810837Y445062D01*
G01X813100Y443931D02*
X811968D01*
G01X813736Y444567D02*
X813100Y443931D01*
G01X814868Y444567D02*
X813736D01*
G01X815999Y443436D02*
X814868Y444567D01*
G01X815999Y442304D02*
Y443436D01*
G01X815363Y441668D02*
X815999Y442304D01*
G01X815363Y440536D02*
Y441668D01*
G01X816494Y439405D02*
X815363Y440536D01*
G01X817626Y439405D02*
X816494D01*
G01X818262Y440041D02*
X817626Y439405D01*
G01X819394Y440041D02*
X818262D01*
G01X820525Y438910D02*
X819394Y440041D01*
G01X820525Y437778D02*
Y438910D01*
G01X819889Y437142D02*
X820525Y437778D01*
G01X819889Y436010D02*
Y437142D01*
G01X821020Y434879D02*
X819889Y436010D01*
G01X822152Y434879D02*
X821020D01*
G01X822788Y435515D02*
X822152Y434879D01*
G01X823920Y435515D02*
X822788D01*
G01X824767Y434668D02*
X823920Y435515D01*
G01X824767Y433432D02*
Y434668D01*
G01X873411Y384788D02*
X824767Y433432D01*
G01X810700Y456100D02*
Y493400D01*
G01X811500Y455300D02*
X810700Y456100D01*
G01X813100Y455300D02*
X811500D01*
G01X813900Y456100D02*
X813100Y455300D01*
G01X813900Y464100D02*
Y456100D01*
G01X814700Y464900D02*
X813900Y464100D01*
G01X817100D02*
X816300Y464900D01*
G01X817100Y449407D02*
Y464100D01*
G01X829767Y436740D02*
X817100Y449407D01*
G01X829767Y433932D02*
Y436740D01*
G01X877181Y386518D02*
X829767Y433932D01*
G01X826200Y452200D02*
X860785Y417615D01*
G01X826200Y491100D02*
Y452200D01*
G01X788418Y457380D02*
X787399Y458399D01*
G01X788419Y456588D02*
X788418Y457380D01*
G01X787671Y452219D02*
X786881Y452218D01*
G01X790229Y454777D02*
X787671Y452219D01*
G01X791021Y454777D02*
X790229D01*
G01X792000Y453798D02*
X791021Y454777D01*
G01X792000Y450599D02*
Y453798D01*
G01X815899Y426700D02*
X792000Y450599D01*
G01X820399Y426700D02*
X815899D01*
G01X790128Y444263D02*
X789336D01*
G01X790586Y444721D02*
X790128Y444263D01*
G01X791478Y444720D02*
X790586Y444721D01*
G01X792489Y443709D02*
X791478Y444720D01*
G01X792489Y443001D02*
Y443709D01*
G01X791939Y442451D02*
X792489Y443001D01*
G01X791938Y441661D02*
X791939Y442451D01*
G01X792958Y440641D02*
X791938Y441661D01*
G01X793750Y440641D02*
X792958D01*
G01X794808Y441699D02*
X793750Y440641D01*
G01X795600Y441698D02*
X794808Y441699D01*
G01X796619Y440679D02*
X795600Y441698D01*
G01X796619Y439887D02*
Y440679D01*
G01X795561Y438829D02*
X796619Y439887D01*
G01X795560Y438039D02*
X795561Y438829D01*
G01X796580Y437019D02*
X795560Y438039D01*
G01X797372Y437019D02*
X796580D01*
G01X798430Y438077D02*
X797372Y437019D01*
G01X799221Y438077D02*
X798430D01*
G01X814698Y422600D02*
X799221Y438077D01*
G01X819099Y422600D02*
X814698D01*
G01X823487Y415219D02*
X810255Y420700D01*
G01X823816Y415083D02*
X823487Y415219D01*
G01X819600Y450443D02*
Y487900D01*
G01X832300Y437743D02*
X819600Y450443D01*
G01X832300Y434183D02*
Y437743D01*
G01X833825Y432658D02*
X832300Y434183D01*
G01X834687Y432658D02*
X833825D01*
G01X835634Y433605D02*
X834687Y432658D01*
G01X836496Y433605D02*
X835634D01*
G01X837897Y432204D02*
X836496Y433605D01*
G01X837897Y431342D02*
Y432204D01*
G01X836950Y430395D02*
X837897Y431342D01*
G01X836950Y429533D02*
Y430395D01*
G01X838351Y428132D02*
X836950Y429533D01*
G01X839213Y428132D02*
X838351D01*
G01X840160Y429079D02*
X839213Y428132D01*
G01X841022Y429079D02*
X840160D01*
G01X842423Y427678D02*
X841022Y429079D01*
G01X842423Y426816D02*
Y427678D01*
G01X841476Y425869D02*
X842423Y426816D01*
G01X841476Y425007D02*
Y425869D01*
G01X842877Y423606D02*
X841476Y425007D01*
G01X843739Y423606D02*
X842877D01*
G01X844686Y424553D02*
X843739Y423606D01*
G01X845548Y424553D02*
X844686D01*
G01X846949Y423152D02*
X845548Y424553D01*
G01X846949Y422290D02*
Y423152D01*
G01X846002Y421343D02*
X846949Y422290D01*
G01X846002Y420481D02*
Y421343D01*
G01X879066Y387417D02*
X846002Y420481D01*
G01X831200Y463904D02*
Y493500D01*
G01X832000Y463104D02*
X831200Y463904D01*
G01X834300Y463104D02*
X832000D01*
G01X835100Y462304D02*
X834300Y463104D01*
G01X835100Y460704D02*
Y462304D01*
G01X834300Y459904D02*
X835100Y460704D01*
G01X832000Y459904D02*
X834300D01*
G01X831200Y459104D02*
X832000Y459904D01*
G01X831200Y457100D02*
Y459104D01*
G01X864555Y423745D02*
X831200Y457100D01*
G01X823600Y452100D02*
Y489800D01*
G01X858900Y416800D02*
X823600Y452100D01*
G01X793399Y446600D02*
X789799D01*
G01X815399Y424600D02*
X793399Y446600D01*
G01X819799Y424600D02*
X815399D01*
G01X808800Y464570D02*
Y466010D01*
G01X808240Y464010D02*
X808800Y464570D01*
G01X802360Y464010D02*
X808240D01*
G01X801800Y463450D02*
X802360Y464010D01*
G01X801800Y461171D02*
Y463450D01*
G01X802636Y460335D02*
X801800Y461171D01*
G01X805164Y460335D02*
X802636D01*
G01X808100Y457399D02*
X805164Y460335D01*
G01X808100Y454871D02*
Y457399D01*
G01X810235Y452736D02*
X808100Y454871D01*
G01X812964Y452736D02*
X810235D01*
G01X814600Y451100D02*
X812964Y452736D01*
G01X814600Y448371D02*
Y451100D01*
G01X827267Y435704D02*
X814600Y448371D01*
G01X827267Y433632D02*
Y435704D01*
G01X875296Y385603D02*
X827267Y433632D01*
G01X828700Y462868D02*
Y492500D01*
G01X829584Y461984D02*
X828700Y462868D01*
G01X829584Y461024D02*
Y461984D01*
G01X828700Y460140D02*
X829584Y461024D01*
G01X828700Y452400D02*
Y460140D01*
G01X862670Y418430D02*
X828700Y452400D01*
G01X845200Y519551D02*
Y527800D01*
G01X844949Y519300D02*
X845200Y519551D01*
G01X844949Y516951D02*
Y519300D01*
G01X845499Y516401D02*
X844949Y516951D01*
G01X845499Y512257D02*
Y516401D01*
G01X844800Y511558D02*
X845499Y512257D01*
G01X844800Y506200D02*
Y511558D01*
G01X850670Y500330D02*
X844800Y506200D01*
G01X847925Y497721D02*
X848630Y498426D01*
G01X847925Y496121D02*
Y497721D01*
G01X848553Y495493D02*
X847925Y496121D01*
G01X848322Y491493D02*
X849122Y492293D01*
G01X848322Y489893D02*
Y491493D01*
G01X849122Y489093D02*
X848322Y489893D01*
G01X848243Y485119D02*
X849017Y485893D01*
G01X848243Y483519D02*
Y485119D01*
G01X849069Y482693D02*
X848243Y483519D01*
G01X798300Y519388D02*
Y527600D01*
G01X798688Y519000D02*
X798300Y519388D01*
G01X798688Y517557D02*
Y519000D01*
G01X798088Y516957D02*
X798688Y517557D01*
G01X798088Y512057D02*
Y516957D01*
G01X798453Y511692D02*
X798088Y512057D01*
G01X798453Y507952D02*
Y511692D01*
G01X792900Y502399D02*
X798453Y507952D01*
G01X792900Y496700D02*
Y502399D01*
G01X793700Y495900D02*
X792900Y496700D01*
G01X795300Y495900D02*
X793700D01*
G01X796100Y496700D02*
X795300Y495900D01*
G01X796100Y501044D02*
Y496700D01*
G01X796900Y501844D02*
X796100Y501044D01*
G01X798500Y501844D02*
X796900D01*
G01X799300Y501044D02*
X798500Y501844D01*
G01X805022Y519566D02*
Y527322D01*
G01X805588Y519000D02*
X805022Y519566D01*
G01X805588Y517857D02*
Y519000D01*
G01X804788Y517057D02*
X805588Y517857D01*
G01X804788Y511657D02*
Y517057D01*
G01X805288Y511157D02*
X804788Y511657D01*
G01X805288Y508600D02*
Y511157D01*
G01X804300Y507612D02*
X805288Y508600D01*
G01X804300Y485300D02*
Y507612D01*
G01X805100Y484500D02*
X804300Y485300D01*
G01X806700Y484500D02*
X805100D01*
G01X807500Y485300D02*
X806700Y484500D01*
G01X807500Y493400D02*
Y485300D01*
G01X808300Y494200D02*
X807500Y493400D01*
G01X809900Y494200D02*
X808300D01*
G01X810700Y493400D02*
X809900Y494200D01*
G01X816300Y464900D02*
X814700D01*
G01X814600Y502700D02*
X826200Y491100D01*
G01X814600Y504195D02*
Y502700D01*
G01X815210Y504805D02*
X814600Y504195D01*
G01X816713Y504805D02*
X815210D01*
G01X817323Y505415D02*
X816713Y504805D01*
G01X817323Y506805D02*
Y505415D01*
G01X816713Y507415D02*
X817323Y506805D01*
G01X815210Y507415D02*
X816713D01*
G01X814600Y508025D02*
X815210Y507415D01*
G01X814600Y511100D02*
Y508025D01*
G01X814900Y511400D02*
X814600Y511100D01*
G01X814900Y517256D02*
Y511400D01*
G01X814301Y517855D02*
X814900Y517256D01*
G01X814301Y521883D02*
Y517855D01*
G01X814911Y522493D02*
X814301Y521883D01*
G01X816078Y522493D02*
X814911D01*
G01X816688Y523103D02*
X816078Y522493D01*
G01X816688Y524493D02*
Y523103D01*
G01X816078Y525103D02*
X816688Y524493D01*
G01X814911Y525103D02*
X816078D01*
G01X814301Y525713D02*
X814911Y525103D01*
G01X814301Y529799D02*
Y525713D01*
G01X841832Y520067D02*
Y527832D01*
G01X842800Y519099D02*
X841832Y520067D01*
G01X842800Y517800D02*
Y519099D01*
G01X840900Y515900D02*
X842800Y517800D01*
G01X840900Y512356D02*
Y515900D01*
G01X842300Y510956D02*
X840900Y512356D01*
G01X842300Y505164D02*
Y510956D01*
G01X846300Y501164D02*
X842300Y505164D01*
G01X846300Y481424D02*
Y501164D01*
G01X877146Y450578D02*
X846300Y481424D01*
G01X835100Y519599D02*
Y527700D01*
G01X835499Y519200D02*
X835100Y519599D01*
G01X835499Y517557D02*
Y519200D01*
G01X834500Y516558D02*
X835499Y517557D01*
G01X834500Y512456D02*
Y516558D01*
G01X835400Y511556D02*
X834500Y512456D01*
G01X835400Y504992D02*
Y511556D01*
G01X841300Y499092D02*
X835400Y504992D01*
G01X841300Y472536D02*
Y499092D01*
G01X844244Y469592D02*
X841300Y472536D01*
G01X845276Y469592D02*
X844244D01*
G01X846526Y470842D02*
X845276Y469592D01*
G01X847658Y470842D02*
X846526D01*
G01X848789Y469711D02*
X847658Y470842D01*
G01X847539Y467329D02*
X848789Y468579D01*
G01X847539Y466297D02*
Y467329D01*
G01X850600Y463236D02*
X847539Y466297D01*
G01X847978Y516557D02*
X848810Y517389D01*
G01X847978Y511689D02*
Y516557D01*
G01X848774Y510893D02*
X847978Y511689D01*
G01X808400Y520300D02*
Y527700D01*
G01X807800Y519700D02*
X808400Y520300D01*
G01X807800Y517399D02*
Y519700D01*
G01X809100Y516099D02*
X807800Y517399D01*
G01X809100Y512001D02*
Y516099D01*
G01X808200Y511101D02*
X809100Y512001D01*
G01X808200Y499543D02*
Y511101D01*
G01X813200Y494543D02*
X808200Y499543D01*
G01X813200Y468200D02*
Y494543D01*
G01X814000Y467400D02*
X813200Y468200D01*
G01X815600Y467400D02*
X814000D01*
G01X816400Y468200D02*
X815600Y467400D01*
G01X816400Y487900D02*
Y468200D01*
G01X817200Y488700D02*
X816400Y487900D01*
G01X818800Y488700D02*
X817200D01*
G01X819600Y487900D02*
X818800Y488700D01*
G01X822100Y526245D02*
Y527400D01*
G01X821490Y525635D02*
X822100Y526245D01*
G01X820710Y525635D02*
X821490D01*
G01X820100Y525025D02*
X820710Y525635D01*
G01X820100Y523045D02*
Y525025D01*
G01X820710Y522435D02*
X820100Y523045D01*
G01X821490Y522435D02*
X820710D01*
G01X822100Y521825D02*
X821490Y522435D01*
G01X822100Y519601D02*
Y521825D01*
G01X821299Y518800D02*
X822100Y519601D01*
G01X821299Y508900D02*
Y518800D01*
G01X821909Y508290D02*
X821299Y508900D01*
G01X823200Y508290D02*
X821909D01*
G01X823700Y507790D02*
X823200Y508290D01*
G01X823700Y505590D02*
Y507790D01*
G01X823200Y505090D02*
X823700Y505590D01*
G01X821909Y505090D02*
X823200D01*
G01X821299Y504480D02*
X821909Y505090D01*
G01X821299Y503401D02*
Y504480D01*
G01X831200Y493500D02*
X821299Y503401D01*
G01X811999Y517451D02*
Y529401D01*
G01X811277Y516729D02*
X811999Y517451D01*
G01X811277Y511579D02*
Y516729D01*
G01X812206Y510650D02*
X811277Y511579D01*
G01X812206Y501194D02*
Y510650D01*
G01X823600Y489800D02*
X812206Y501194D01*
G01X801700Y519612D02*
Y527700D01*
G01X801188Y519100D02*
X801700Y519612D01*
G01X801188Y517657D02*
Y519100D01*
G01X802288Y516557D02*
X801188Y517657D01*
G01X802288Y512157D02*
Y516557D01*
G01X801388Y511257D02*
X802288Y512157D01*
G01X801388Y509200D02*
Y511257D01*
G01X801800Y508788D02*
X801388Y509200D01*
G01X801800Y482490D02*
Y508788D01*
G01X802360Y481930D02*
X801800Y482490D01*
G01X808240Y481930D02*
X802360D01*
G01X808800Y481370D02*
X808240Y481930D01*
G01X808800Y479930D02*
Y481370D01*
G01X808240Y479370D02*
X808800Y479930D01*
G01X802360Y479370D02*
X808240D01*
G01X801800Y478810D02*
X802360Y479370D01*
G01X801800Y477370D02*
Y478810D01*
G01X802360Y476810D02*
X801800Y477370D01*
G01X808240Y476810D02*
X802360D01*
G01X808800Y476250D02*
X808240Y476810D01*
G01X808800Y474810D02*
Y476250D01*
G01X808240Y474250D02*
X808800Y474810D01*
G01X802360Y474250D02*
X808240D01*
G01X801800Y473690D02*
X802360Y474250D01*
G01X801800Y472250D02*
Y473690D01*
G01X802360Y471690D02*
X801800Y472250D01*
G01X808240Y471690D02*
X802360D01*
G01X808800Y471130D02*
X808240Y471690D01*
G01X808800Y469690D02*
Y471130D01*
G01X808240Y469130D02*
X808800Y469690D01*
G01X802360Y469130D02*
X808240D01*
G01X801800Y468570D02*
X802360Y469130D01*
G01X801800Y467130D02*
Y468570D01*
G01X802360Y466570D02*
X801800Y467130D01*
G01X808240Y466570D02*
X802360D01*
G01X808800Y466010D02*
X808240Y466570D01*
G01X838500Y520001D02*
Y528000D01*
G01X837999Y519500D02*
X838500Y520001D01*
G01X837999Y517401D02*
Y519500D01*
G01X839099Y516301D02*
X837999Y517401D01*
G01X839099Y512157D02*
Y516301D01*
G01X838199Y511257D02*
X839099Y512157D01*
G01X838199Y505729D02*
Y511257D01*
G01X843800Y500128D02*
X838199Y505729D01*
G01X843800Y480388D02*
Y500128D01*
G01X845635Y478553D02*
X843800Y480388D01*
G01X845635Y477691D02*
Y478553D01*
G01X843403Y475459D02*
X845635Y477691D01*
G01X843403Y474597D02*
Y475459D01*
G01X844804Y473196D02*
X843403Y474597D01*
G01X845666Y473196D02*
X844804D01*
G01X847898Y475428D02*
X845666Y473196D01*
G01X848760Y475428D02*
X847898D01*
G01X818400Y519599D02*
Y527900D01*
G01X818600Y519399D02*
X818400Y519599D01*
G01X818600Y517458D02*
Y519399D01*
G01X817449Y516307D02*
X818600Y517458D01*
G01X817449Y511851D02*
Y516307D01*
G01X819444Y509856D02*
X817449Y511851D01*
G01X819444Y501756D02*
Y509856D01*
G01X828700Y492500D02*
X819444Y501756D01*
G01X843503Y550966D02*
Y550914D01*
G01X844799Y549670D02*
X843503Y550966D01*
G01X844799Y546801D02*
Y549670D01*
G01X845200Y546400D02*
X844799Y546801D01*
G01X845200Y537901D02*
Y546400D01*
G01X844799Y537500D02*
X845200Y537901D01*
G01X844799Y536302D02*
Y537500D01*
G01X845799Y535302D02*
X844799Y536302D01*
G01X845799Y530547D02*
Y535302D01*
G01X844949Y529697D02*
X845799Y530547D01*
G01X844949Y528051D02*
Y529697D01*
G01X845200Y527800D02*
X844949Y528051D01*
G01X841229Y566699D02*
X840157D01*
G01X841929Y565999D02*
X841229Y566699D01*
G01X841929Y564725D02*
Y565999D01*
G01X840792Y563588D02*
X841929Y564725D01*
G01X840792Y562512D02*
Y563588D01*
G01X841804Y561500D02*
X840792Y562512D01*
G01X841804Y560300D02*
Y561500D01*
G01X840792Y559288D02*
X841804Y560300D01*
G01X840792Y558212D02*
Y559288D01*
G01X841904Y557100D02*
X840792Y558212D01*
G01X841904Y554467D02*
Y557100D01*
G01X841729Y554292D02*
X841904Y554467D01*
G01X841729Y552600D02*
Y554292D01*
G01X843415Y550914D02*
X841729Y552600D01*
G01X843503Y550914D02*
X843415D01*
G01X795988Y555292D02*
X796653Y555957D01*
G01X795988Y551457D02*
Y555292D01*
G01X798888Y548557D02*
X795988Y551457D01*
G01X798888Y547388D02*
Y548557D01*
G01X798322Y546822D02*
X798888Y547388D01*
G01X798322Y538166D02*
Y546822D01*
G01X798888Y537600D02*
X798322Y538166D01*
G01X798888Y536442D02*
Y537600D01*
G01X797615Y535169D02*
X798888Y536442D01*
G01X797615Y530548D02*
Y535169D01*
G01X798688Y529475D02*
X797615Y530548D01*
G01X798688Y527988D02*
Y529475D01*
G01X798300Y527600D02*
X798688Y527988D01*
G01X794948Y567849D02*
X799999Y572900D01*
G01X794948Y557662D02*
Y567849D01*
G01X796653Y555957D02*
X794948Y557662D01*
G01X801988Y554599D02*
X803346Y555957D01*
G01X801988Y552107D02*
Y554599D01*
G01X805388Y548707D02*
X801988Y552107D01*
G01X805388Y547388D02*
Y548707D01*
G01X805000Y547000D02*
X805388Y547388D01*
G01X805000Y538190D02*
Y547000D01*
G01X805388Y537802D02*
X805000Y538190D01*
G01X805388Y536242D02*
Y537802D01*
G01X804488Y535342D02*
X805388Y536242D01*
G01X804488Y530319D02*
Y535342D01*
G01X805588Y529219D02*
X804488Y530319D01*
G01X805588Y527888D02*
Y529219D01*
G01X805022Y527322D02*
X805588Y527888D01*
G01X801641Y567849D02*
X806692Y572900D01*
G01X801641Y557662D02*
Y567849D01*
G01X803346Y555957D02*
X801641Y557662D01*
G01X812997Y550914D02*
X813085D01*
G01X811311Y552600D02*
X812997Y550914D01*
G01X811311Y554800D02*
Y552600D01*
G01X811811Y555300D02*
X811311Y554800D01*
G01X811811Y557199D02*
Y555300D01*
G01X810674Y558336D02*
X811811Y557199D01*
G01X810674Y559664D02*
Y558336D01*
G01X811611Y560601D02*
X810674Y559664D01*
G01X811611Y561999D02*
Y560601D01*
G01X810674Y562936D02*
X811611Y561999D01*
G01X810674Y564164D02*
Y562936D01*
G01X811711Y565201D02*
X810674Y564164D01*
G01X811711Y566099D02*
Y565201D01*
G01X811111Y566699D02*
X811711Y566099D01*
G01X810039Y566699D02*
X811111D01*
G01X815199Y530697D02*
X814301Y529799D01*
G01X815199Y534856D02*
Y530697D01*
G01X814599Y535456D02*
X815199Y534856D01*
G01X814599Y537500D02*
Y535456D01*
G01X816100Y539001D02*
X814599Y537500D01*
G01X816100Y545500D02*
Y539001D01*
G01X814599Y547001D02*
X816100Y545500D01*
G01X814599Y549400D02*
Y547001D01*
G01X813085Y550914D02*
X814599Y549400D01*
G01X838799Y554599D02*
X840157Y555957D01*
G01X838799Y552107D02*
Y554599D01*
G01X842199Y548707D02*
X838799Y552107D01*
G01X842199Y547099D02*
Y548707D01*
G01X841800Y546700D02*
X842199Y547099D01*
G01X841800Y538099D02*
Y546700D01*
G01X842199Y537700D02*
X841800Y538099D01*
G01X842199Y536242D02*
Y537700D01*
G01X841299Y535342D02*
X842199Y536242D01*
G01X841299Y530447D02*
Y535342D01*
G01X842399Y529347D02*
X841299Y530447D01*
G01X842399Y528399D02*
Y529347D01*
G01X841832Y527832D02*
X842399Y528399D01*
G01X838452Y567849D02*
X843503Y572900D01*
G01X838452Y557662D02*
Y567849D01*
G01X840157Y555957D02*
X838452Y557662D01*
G01X832799Y555292D02*
X833464Y555957D01*
G01X832799Y551457D02*
Y555292D01*
G01X835699Y548557D02*
X832799Y551457D01*
G01X835699Y547099D02*
Y548557D01*
G01X835100Y546500D02*
X835699Y547099D01*
G01X835100Y538099D02*
Y546500D01*
G01X835699Y537500D02*
X835100Y538099D01*
G01X835699Y536442D02*
Y537500D01*
G01X834426Y535169D02*
X835699Y536442D01*
G01X834426Y530570D02*
Y535169D01*
G01X835499Y529497D02*
X834426Y530570D01*
G01X835499Y528099D02*
Y529497D01*
G01X835100Y527700D02*
X835499Y528099D01*
G01X831759Y567849D02*
X836810Y572900D01*
G01X831759Y557662D02*
Y567849D01*
G01X833464Y555957D02*
X831759Y557662D01*
G01X846307Y555414D02*
X846850Y555957D01*
G01X846307Y550894D02*
Y555414D01*
G01X848760Y548441D02*
X846307Y550894D01*
G01X847762Y535144D02*
X848760Y536142D01*
G01X847762Y530537D02*
Y535144D01*
G01X848810Y529489D02*
X847762Y530537D01*
G01X845767Y569445D02*
X848822Y572500D01*
G01X845767Y568257D02*
Y569445D01*
G01X845145Y567635D02*
X845767Y568257D01*
G01X845145Y557662D02*
Y567635D01*
G01X846850Y555957D02*
X845145Y557662D01*
G01X806692Y550966D02*
Y550914D01*
G01X807900Y549758D02*
X806692Y550966D01*
G01X807900Y546800D02*
Y549758D01*
G01X808400Y546300D02*
X807900Y546800D01*
G01X808400Y539100D02*
Y546300D01*
G01X807616Y538316D02*
X808400Y539100D01*
G01X807616Y536984D02*
Y538316D01*
G01X808988Y535612D02*
X807616Y536984D01*
G01X808988Y530697D02*
Y535612D01*
G01X807762Y529471D02*
X808988Y530697D01*
G01X807762Y528338D02*
Y529471D01*
G01X808400Y527700D02*
X807762Y528338D01*
G01X804418Y566699D02*
X803346D01*
G01X805118Y565999D02*
X804418Y566699D01*
G01X805118Y564725D02*
Y565999D01*
G01X803981Y563588D02*
X805118Y564725D01*
G01X803981Y562512D02*
Y563588D01*
G01X804993Y561500D02*
X803981Y562512D01*
G01X804993Y560300D02*
Y561500D01*
G01X803981Y559288D02*
X804993Y560300D01*
G01X803981Y558212D02*
Y559288D01*
G01X805093Y557100D02*
X803981Y558212D01*
G01X805093Y554467D02*
Y557100D01*
G01X804918Y554292D02*
X805093Y554467D01*
G01X804918Y552600D02*
Y554292D01*
G01X806604Y550914D02*
X804918Y552600D01*
G01X806692Y550914D02*
X806604D01*
G01X817712Y566699D02*
X816732D01*
G01X818311Y566100D02*
X817712Y566699D01*
G01X818311Y564900D02*
Y566100D01*
G01X817367Y563956D02*
X818311Y564900D01*
G01X817367Y562744D02*
Y563956D01*
G01X818211Y561900D02*
X817367Y562744D01*
G01X818211Y560200D02*
Y561900D01*
G01X817367Y559356D02*
X818211Y560200D01*
G01X817367Y557936D02*
Y559356D01*
G01X818511Y556792D02*
X817367Y557936D01*
G01X818511Y555199D02*
Y556792D01*
G01X817604Y554292D02*
X818511Y555199D01*
G01X817604Y552600D02*
Y554292D01*
G01X819290Y550914D02*
X817604Y552600D01*
G01X819378Y550914D02*
X819290D01*
G01X819378Y550564D02*
Y550914D01*
G01X821299Y548643D02*
X819378Y550564D01*
G01X821299Y546901D02*
Y548643D01*
G01X821800Y546400D02*
X821299Y546901D01*
G01X821800Y544656D02*
Y546400D01*
G01X820500Y543356D02*
X821800Y544656D01*
G01X820500Y541756D02*
Y543356D01*
G01X821800Y540456D02*
X820500Y541756D01*
G01X821800Y538201D02*
Y540456D01*
G01X821299Y537700D02*
X821800Y538201D01*
G01X821299Y528201D02*
Y537700D01*
G01X822100Y527400D02*
X821299Y528201D01*
G01X809659Y555577D02*
X810039Y555957D01*
G01X809659Y550947D02*
Y555577D01*
G01X811949Y548657D02*
X809659Y550947D01*
G01X811949Y536142D02*
Y548657D01*
G01X811250Y535443D02*
X811949Y536142D01*
G01X811250Y530150D02*
Y535443D01*
G01X811999Y529401D02*
X811250Y530150D01*
G01X812011Y572500D02*
X812999D01*
G01X808956Y569445D02*
X812011Y572500D01*
G01X808956Y568257D02*
Y569445D01*
G01X808334Y567635D02*
X808956Y568257D01*
G01X808334Y557662D02*
Y567635D01*
G01X810039Y555957D02*
X808334Y557662D01*
G01X801345Y549568D02*
X799999Y550914D01*
G01X801388Y549568D02*
X801345D01*
G01X801388Y547012D02*
Y549568D01*
G01X801700Y546700D02*
X801388Y547012D01*
G01X801700Y538000D02*
Y546700D01*
G01X801388Y537688D02*
X801700Y538000D01*
G01X801388Y536411D02*
Y537688D01*
G01X802054Y535745D02*
X801388Y536411D01*
G01X802054Y530249D02*
Y535745D01*
G01X801488Y529683D02*
X802054Y530249D01*
G01X801488Y527912D02*
Y529683D01*
G01X801700Y527700D02*
X801488Y527912D01*
G01X797725Y566699D02*
X796653D01*
G01X798425Y565999D02*
X797725Y566699D01*
G01X798425Y564725D02*
Y565999D01*
G01X797288Y563588D02*
X798425Y564725D01*
G01X797288Y562512D02*
Y563588D01*
G01X798300Y561500D02*
X797288Y562512D01*
G01X798300Y560300D02*
Y561500D01*
G01X797288Y559288D02*
X798300Y560300D01*
G01X797288Y558212D02*
Y559288D01*
G01X798400Y557100D02*
X797288Y558212D01*
G01X798400Y554467D02*
Y557100D01*
G01X798225Y554292D02*
X798400Y554467D01*
G01X798225Y552600D02*
Y554292D01*
G01X799911Y550914D02*
X798225Y552600D01*
G01X799999Y550914D02*
X799911D01*
G01X838156Y549568D02*
X836810Y550914D01*
G01X838199Y549568D02*
X838156D01*
G01X838199Y546700D02*
Y549568D01*
G01X838500Y546399D02*
X838199Y546700D01*
G01X838500Y538000D02*
Y546399D01*
G01X838199Y537699D02*
X838500Y538000D01*
G01X838199Y536301D02*
Y537699D01*
G01X838865Y535635D02*
X838199Y536301D01*
G01X838865Y530263D02*
Y535635D01*
G01X838299Y529697D02*
X838865Y530263D01*
G01X838299Y528201D02*
Y529697D01*
G01X838500Y528000D02*
X838299Y528201D01*
G01X834536Y566699D02*
X833464D01*
G01X835236Y565999D02*
X834536Y566699D01*
G01X835236Y564725D02*
Y565999D01*
G01X834099Y563588D02*
X835236Y564725D01*
G01X834099Y562512D02*
Y563588D01*
G01X835111Y561500D02*
X834099Y562512D01*
G01X835111Y560300D02*
Y561500D01*
G01X834099Y559288D02*
X835111Y560300D01*
G01X834099Y558212D02*
Y559288D01*
G01X835211Y557100D02*
X834099Y558212D01*
G01X835211Y554467D02*
Y557100D01*
G01X835036Y554292D02*
X835211Y554467D01*
G01X835036Y552600D02*
Y554292D01*
G01X836722Y550914D02*
X835036Y552600D01*
G01X836810Y550914D02*
X836722D01*
G01X847922Y566699D02*
X846850D01*
G01X848522Y566099D02*
X847922Y566699D01*
G01X847485Y564164D02*
X848522Y565201D01*
G01X847485Y562936D02*
Y564164D01*
G01X848422Y561999D02*
X847485Y562936D01*
G01Y559664D02*
X848422Y560601D01*
G01X847485Y558336D02*
Y559664D01*
G01X848622Y557199D02*
X847485Y558336D01*
G01X848122Y554800D02*
X848622Y555300D01*
G01X848122Y552600D02*
Y554800D01*
G01X849808Y550914D02*
X848122Y552600D01*
G01X815299Y554524D02*
X816732Y555957D01*
G01X815299Y552007D02*
Y554524D01*
G01X818649Y548657D02*
X815299Y552007D01*
G01X818649Y547149D02*
Y548657D01*
G01X818400Y546900D02*
X818649Y547149D01*
G01X818400Y538249D02*
Y546900D01*
G01X818649Y538000D02*
X818400Y538249D01*
G01X818649Y536449D02*
Y538000D01*
G01X817430Y535230D02*
X818649Y536449D01*
G01X817430Y530636D02*
Y535230D01*
G01X818599Y529467D02*
X817430Y530636D01*
G01X818599Y528099D02*
Y529467D01*
G01X818400Y527900D02*
X818599Y528099D01*
G01X818212Y572500D02*
X819378D01*
G01X815027Y569315D02*
X818212Y572500D01*
G01X815027Y557662D02*
Y569315D01*
G01X816732Y555957D02*
X815027Y557662D01*
G01X853543Y30021D02*
Y27899D01*
G01X855422Y31900D02*
X853543Y30021D01*
G01X856822Y31900D02*
X855422D01*
G01X858278Y33356D02*
X856822Y31900D01*
G01X880515Y31700D02*
X882315Y33500D01*
G01X879515Y31700D02*
X880515D01*
G01X878215Y30400D02*
X879515Y31700D01*
G01X878215Y29146D02*
Y30400D01*
G01X876968Y27899D02*
X878215Y29146D01*
G01X908333D02*
X907086Y27899D01*
G01X908333Y30400D02*
Y29146D01*
G01X909633Y31700D02*
X908333Y30400D01*
G01X910633Y31700D02*
X909633D01*
G01X873822D02*
X875622Y33500D01*
G01X872822Y31700D02*
X873822D01*
G01X871522Y30400D02*
X872822Y31700D01*
G01X871522Y29146D02*
Y30400D01*
G01X870275Y27899D02*
X871522Y29146D01*
G01X890354Y30021D02*
Y27899D01*
G01X892233Y31900D02*
X890354Y30021D01*
G01X893633Y31900D02*
X892233D01*
G01X895089Y33356D02*
X893633Y31900D01*
G01X887132Y31700D02*
X888708Y33276D01*
G01X885908Y31700D02*
X887132D01*
G01X883661Y29453D02*
X885908Y31700D01*
G01X883661Y27899D02*
Y29453D01*
G01X850321Y31700D02*
X849097D01*
G01X851897Y33276D02*
X850321Y31700D01*
G01X858278Y34700D02*
Y33356D01*
G01X857662Y35316D02*
X858278Y34700D01*
G01X857662Y48441D02*
Y35316D01*
G01X856189Y49914D02*
X857662Y48441D01*
G01X854116Y51987D02*
X856189Y49914D01*
G01X854116Y53116D02*
Y51987D01*
G01X855610Y54610D02*
X854116Y53116D01*
G01X855610Y61610D02*
Y54610D01*
G01X858110Y64110D02*
X855610Y61610D01*
G01X858110Y95744D02*
Y64110D01*
G01X881760Y91668D02*
Y114400D01*
G01X882410Y91018D02*
X881760Y91668D01*
G01X882410Y86618D02*
Y91018D01*
G01X881710Y85918D02*
X882410Y86618D01*
G01X881710Y73091D02*
Y85918D01*
G01X882310Y72491D02*
X881710Y73091D01*
G01X882310Y67053D02*
Y72491D01*
G01X881760Y66503D02*
X882310Y67053D01*
G01X881760Y56768D02*
Y66503D01*
G01X878410Y53418D02*
X881760Y56768D01*
G01X878410Y51818D02*
Y53418D01*
G01X880314Y49914D02*
X878410Y51818D01*
G01X881703Y48525D02*
X880314Y49914D01*
G01X881703Y35512D02*
Y48525D01*
G01X882315Y34900D02*
X881703Y35512D01*
G01X882315Y33500D02*
Y34900D01*
G01X852422Y53836D02*
X853543Y54957D01*
G01X852422Y50900D02*
Y53836D01*
G01X855322Y48000D02*
X852422Y50900D01*
G01X855322Y46032D02*
Y48000D01*
G01X853789Y44499D02*
X855322Y46032D01*
G01X853789Y43300D02*
Y44499D01*
G01X855039Y42050D02*
X853789Y43300D01*
G01X855039Y41150D02*
Y42050D01*
G01X853689Y39800D02*
X855039Y41150D01*
G01X853689Y38501D02*
Y39800D01*
G01X855322Y36868D02*
X853689Y38501D01*
G01X855322Y34567D02*
Y36868D01*
G01X856189Y33700D02*
X855322Y34567D01*
G01X855500Y93900D02*
X853310Y96090D01*
G01X855500Y92200D02*
Y93900D01*
G01X854260Y90960D02*
X855500Y92200D01*
G01X854260Y86718D02*
Y90960D01*
G01X855610Y85368D02*
X854260Y86718D01*
G01X855610Y73409D02*
Y85368D01*
G01X854260Y72059D02*
X855610Y73409D01*
G01X854260Y67417D02*
Y72059D01*
G01X855410Y66267D02*
X854260Y67417D01*
G01X855410Y64710D02*
Y66267D01*
G01X853543Y62843D02*
X855410Y64710D01*
G01X853543Y54957D02*
Y62843D01*
G01X890354Y62954D02*
Y54957D01*
G01X892263Y64863D02*
X890354Y62954D01*
G01X892263Y66225D02*
Y64863D01*
G01X891074Y67414D02*
X892263Y66225D01*
G01X891074Y72157D02*
Y67414D01*
G01X892274Y73357D02*
X891074Y72157D01*
G01X892274Y85363D02*
Y73357D01*
G01X890763Y86874D02*
X892274Y85363D01*
G01X890763Y90662D02*
Y86874D01*
G01X892163Y92062D02*
X890763Y90662D01*
G01X892163Y105024D02*
Y92062D01*
G01X892133Y34567D02*
X893000Y33700D01*
G01X892133Y36868D02*
Y34567D01*
G01X890500Y38501D02*
X892133Y36868D01*
G01X890500Y39800D02*
Y38501D01*
G01X891850Y41150D02*
X890500Y39800D01*
G01X891850Y42050D02*
Y41150D01*
G01X890600Y43300D02*
X891850Y42050D01*
G01X890600Y44499D02*
Y43300D01*
G01X892133Y46032D02*
X890600Y44499D01*
G01X892133Y48000D02*
Y46032D01*
G01X889233Y50900D02*
X892133Y48000D01*
G01X889233Y53836D02*
Y50900D01*
G01X890354Y54957D02*
X889233Y53836D01*
G01X908632Y51714D02*
X910432Y49914D01*
G01X908632Y53701D02*
Y51714D01*
G01X911263Y56332D02*
X908632Y53701D01*
G01X875010Y48525D02*
X873621Y49914D01*
G01X875010Y35512D02*
Y48525D01*
G01X875622Y34900D02*
X875010Y35512D01*
G01X875622Y33500D02*
Y34900D01*
G01X875110Y93610D02*
X876700Y95200D01*
G01X875110Y91718D02*
Y93610D01*
G01X875810Y91018D02*
X875110Y91718D01*
G01X875810Y86518D02*
Y91018D01*
G01X875010Y85718D02*
X875810Y86518D01*
G01X875010Y83990D02*
Y85718D01*
G01X876500Y82500D02*
X875010Y83990D01*
G01X876500Y76190D02*
Y82500D01*
G01X875010Y74700D02*
X876500Y76190D01*
G01X875010Y73191D02*
Y74700D01*
G01X875910Y72291D02*
X875010Y73191D01*
G01X875910Y67253D02*
Y72291D01*
G01X875100Y66443D02*
X875910Y67253D01*
G01X875100Y64700D02*
Y66443D01*
G01X876300Y63500D02*
X875100Y64700D01*
G01X876300Y59200D02*
Y63500D01*
G01X873260Y56160D02*
X876300Y59200D01*
G01X873260Y55030D02*
Y56160D01*
G01X871810Y53580D02*
X873260Y55030D01*
G01X871810Y51725D02*
Y53580D01*
G01X873621Y49914D02*
X871810Y51725D01*
G01X895089Y34700D02*
Y33356D01*
G01X894473Y35316D02*
X895089Y34700D01*
G01X894473Y48441D02*
Y35316D01*
G01X893000Y49914D02*
X894473Y48441D01*
G01X890974Y51940D02*
X893000Y49914D01*
G01X890974Y53074D02*
Y51940D01*
G01X892374Y54474D02*
X890974Y53074D01*
G01X892374Y61774D02*
Y54474D01*
G01X894913Y64313D02*
X892374Y61774D01*
G01X894913Y105021D02*
Y64313D01*
G01X869182Y56050D02*
X870275Y54957D01*
G01X869182Y57182D02*
Y56050D01*
G01X869950Y57950D02*
X869182Y57182D01*
G01X871450Y57950D02*
X869950D01*
G01X873400Y59900D02*
X871450Y57950D01*
G01X873400Y61600D02*
Y59900D01*
G01X872310Y62690D02*
X873400Y61600D01*
G01X872310Y66303D02*
Y62690D01*
G01X871710Y66903D02*
X872310Y66303D01*
G01X871710Y72611D02*
Y66903D01*
G01X872100Y73001D02*
X871710Y72611D01*
G01X872100Y76304D02*
Y73001D01*
G01X872900Y77104D02*
X872100Y76304D01*
G01X873400Y77104D02*
X872900D01*
G01X874200Y77904D02*
X873400Y77104D01*
G01X874200Y79504D02*
Y77904D01*
G01X873400Y80304D02*
X874200Y79504D01*
G01X872900Y80304D02*
X873400D01*
G01X872100Y81104D02*
X872900Y80304D01*
G01X872100Y86128D02*
Y81104D01*
G01X871710Y86518D02*
X872100Y86128D01*
G01X871710Y91218D02*
Y86518D01*
G01X872110Y91618D02*
X871710Y91218D01*
G01X872110Y93890D02*
Y91618D01*
G01X871732Y94268D02*
X872110Y93890D01*
G01X871732Y95400D02*
Y94268D01*
G01X872147Y35574D02*
X873621Y34100D01*
G01X872147Y36668D02*
Y35574D01*
G01X870714Y38101D02*
X872147Y36668D01*
G01X870714Y39324D02*
Y38101D01*
G01X872214Y40824D02*
X870714Y39324D01*
G01X872214Y42176D02*
Y40824D01*
G01X870714Y43676D02*
X872214Y42176D01*
G01X870714Y44799D02*
Y43676D01*
G01X872389Y46474D02*
X870714Y44799D01*
G01X872389Y47859D02*
Y46474D01*
G01X869347Y50901D02*
X872389Y47859D01*
G01X869347Y54029D02*
Y50901D01*
G01X870275Y54957D02*
X869347Y54029D01*
G01X875847Y53836D02*
X876968Y54957D01*
G01X875847Y50900D02*
Y53836D01*
G01X879189Y47558D02*
X875847Y50900D01*
G01X879189Y46500D02*
Y47558D01*
G01X877389Y44700D02*
X879189Y46500D01*
G01X877389Y43125D02*
Y44700D01*
G01X878589Y41925D02*
X877389Y43125D01*
G01X878589Y40799D02*
Y41925D01*
G01X877389Y39599D02*
X878589Y40799D01*
G01X877389Y38226D02*
Y39599D01*
G01X878747Y36868D02*
X877389Y38226D01*
G01X878747Y35667D02*
Y36868D01*
G01X880314Y34100D02*
X878747Y35667D01*
G01X879260Y92068D02*
Y115436D01*
G01X878310Y91118D02*
X879260Y92068D01*
G01X878310Y86418D02*
Y91118D01*
G01X878910Y85818D02*
X878310Y86418D01*
G01X878910Y73111D02*
Y85818D01*
G01X878410Y72611D02*
X878910Y73111D01*
G01X878410Y66803D02*
Y72611D01*
G01X879210Y66003D02*
X878410Y66803D01*
G01X879210Y58411D02*
Y66003D01*
G01X876968Y56169D02*
X879210Y58411D01*
G01X876968Y54957D02*
Y56169D01*
G01X883661Y61457D02*
Y54957D01*
G01X885563Y63359D02*
X883661Y61457D01*
G01X885563Y66237D02*
Y63359D01*
G01X884674Y67126D02*
X885563Y66237D01*
G01X884674Y72070D02*
Y67126D01*
G01X885563Y72959D02*
X884674Y72070D01*
G01X885563Y85574D02*
Y72959D01*
G01X884674Y86463D02*
X885563Y85574D01*
G01X884674Y91173D02*
Y86463D01*
G01X885563Y92062D02*
X884674Y91173D01*
G01X885563Y105286D02*
Y92062D01*
G01X885533Y34788D02*
X886621Y33700D01*
G01X885533Y36668D02*
Y34788D01*
G01X884100Y38101D02*
X885533Y36668D01*
G01X884100Y39300D02*
Y38101D01*
G01X885600Y40800D02*
X884100Y39300D01*
G01X885600Y42000D02*
Y40800D01*
G01X884150Y43450D02*
X885600Y42000D01*
G01X884150Y44849D02*
Y43450D01*
G01X885533Y46232D02*
X884150Y44849D01*
G01X885533Y48101D02*
Y46232D01*
G01X882733Y50901D02*
X885533Y48101D01*
G01X882733Y54029D02*
Y50901D01*
G01X883661Y54957D02*
X882733Y54029D01*
G01X909363Y92174D02*
Y104775D01*
G01X908263Y91074D02*
X909363Y92174D01*
G01X908263Y86774D02*
Y91074D01*
G01X909074Y85963D02*
X908263Y86774D01*
G01X909074Y73174D02*
Y85963D01*
G01X908263Y72363D02*
X909074Y73174D01*
G01X908263Y67071D02*
Y72363D01*
G01X909063Y66271D02*
X908263Y67071D01*
G01X909063Y56934D02*
Y66271D01*
G01X907086Y54957D02*
X909063Y56934D01*
G01X906158Y54029D02*
X907086Y54957D01*
G01X906158Y50901D02*
Y54029D01*
G01X909200Y47859D02*
X906158Y50901D01*
G01X909200Y46474D02*
Y47859D01*
G01X907525Y44799D02*
X909200Y46474D01*
G01X907525Y43676D02*
Y44799D01*
G01X909025Y42176D02*
X907525Y43676D01*
G01X909025Y40824D02*
Y42176D01*
G01X907525Y39324D02*
X909025Y40824D01*
G01X907525Y38101D02*
Y39324D01*
G01X908958Y36668D02*
X907525Y38101D01*
G01X908958Y35574D02*
Y36668D01*
G01X910432Y34100D02*
X908958Y35574D01*
G01X887933Y48688D02*
X886707Y49914D01*
G01X887933Y35675D02*
Y48688D01*
G01X888708Y34900D02*
X887933Y35675D01*
G01X888708Y33276D02*
Y34900D01*
G01X888363Y91474D02*
Y105628D01*
G01X888663Y91174D02*
X888363Y91474D01*
G01X888663Y86474D02*
Y91174D01*
G01X888263Y86074D02*
X888663Y86474D01*
G01X888263Y72959D02*
Y86074D01*
G01X888563Y72659D02*
X888263Y72959D01*
G01X888563Y67359D02*
Y72659D01*
G01X888263Y67059D02*
X888563Y67359D01*
G01X888263Y56833D02*
Y67059D01*
G01X884674Y53244D02*
X888263Y56833D01*
G01X884674Y51443D02*
Y53244D01*
G01X886203Y49914D02*
X884674Y51443D01*
G01X886707Y49914D02*
X886203D01*
G01X848722Y46232D02*
Y48101D01*
G01X848789Y40800D02*
Y42000D01*
G01X848722Y34788D02*
Y36668D01*
G01X849810Y33700D02*
X848722Y34788D01*
G01X848500Y93900D02*
Y105264D01*
G01X848810Y93590D02*
X848500Y93900D01*
G01X848810Y92118D02*
Y93590D01*
G01X848910Y82490D02*
Y85418D01*
G01X850200Y81200D02*
X848910Y82490D01*
G01X850200Y77190D02*
Y81200D01*
G01X848910Y75900D02*
X850200Y77190D01*
G01X848910Y73103D02*
Y75900D01*
G01X848810Y63710D02*
Y66291D01*
G01X851897Y34900D02*
Y33276D01*
G01X851122Y35675D02*
X851897Y34900D01*
G01X851122Y48688D02*
Y35675D01*
G01X849896Y49914D02*
X851122Y48688D01*
G01X850530Y59170D02*
Y55938D01*
G01X849600Y60100D02*
X850530Y59170D01*
G01X849600Y61356D02*
Y60100D01*
G01X851510Y63266D02*
X849600Y61356D01*
G01X851510Y66403D02*
Y63266D01*
G01X851760Y66653D02*
X851510Y66403D01*
G01X851760Y72853D02*
Y66653D01*
G01X851410Y73203D02*
X851760Y72853D01*
G01X851410Y74709D02*
Y73203D01*
G01X852800Y76099D02*
X851410Y74709D01*
G01X852800Y82301D02*
Y76099D01*
G01X851410Y83691D02*
X852800Y82301D01*
G01X851410Y86118D02*
Y83691D01*
G01X851760Y86468D02*
X851410Y86118D01*
G01X851760Y91418D02*
Y86468D01*
G01X851510Y91668D02*
X851760Y91418D01*
G01X851510Y94590D02*
Y91668D01*
G01X851100Y95000D02*
X851510Y94590D01*
G01X856250Y97604D02*
X858110Y95744D01*
G01X856250Y99804D02*
Y97604D01*
G01X859200Y102754D02*
X856250Y99804D01*
G01X859200Y115949D02*
Y102754D01*
G01X880724Y137473D02*
X859200Y115949D01*
G01X880724Y141425D02*
Y137473D01*
G01X899600Y160301D02*
X880724Y141425D01*
G01X897379Y117779D02*
X922400Y142800D01*
G01X895711Y117779D02*
X897379D01*
G01X895101Y118389D02*
X895711Y117779D01*
G01X895101Y120690D02*
Y118389D01*
G01X894491Y121300D02*
X895101Y120690D01*
G01X893101Y121300D02*
X894491D01*
G01X892491Y120690D02*
X893101Y121300D01*
G01X892491Y118389D02*
Y120690D01*
G01X891881Y117779D02*
X892491Y118389D01*
G01X885139Y117779D02*
X891881D01*
G01X881760Y114400D02*
X885139Y117779D01*
G01X877656Y141893D02*
X897100Y161337D01*
G01X877656Y137757D02*
Y141893D01*
G01X875798Y135899D02*
X877656Y137757D01*
G01X874935Y135899D02*
X875798D01*
G01X873988Y136846D02*
X874935Y135899D01*
G01X873196Y136846D02*
X873988D01*
G01X872142Y135792D02*
X873196Y136846D01*
G01X872142Y135000D02*
Y135792D01*
G01X873090Y134052D02*
X872142Y135000D01*
G01X873090Y133191D02*
Y134052D01*
G01X872106Y132207D02*
X873090Y133191D01*
G01X871244Y132207D02*
X872106D01*
G01X869832Y133618D02*
X871244Y132207D01*
G01X868970Y133618D02*
X869832D01*
G01X867986Y132634D02*
X868970Y133618D01*
G01X867986Y131772D02*
Y132634D01*
G01X869398Y130361D02*
X867986Y131772D01*
G01X869398Y129499D02*
Y130361D01*
G01X868414Y128515D02*
X869398Y129499D01*
G01X867551Y128515D02*
X868414D01*
G01X866587Y129479D02*
X867551Y128515D01*
G01X865879Y129479D02*
X866587D01*
G01X864741Y128341D02*
X865879Y129479D01*
G01X864741Y127633D02*
Y128341D01*
G01X865706Y126668D02*
X864741Y127633D01*
G01X865706Y125807D02*
Y126668D01*
G01X857000Y117101D02*
X865706Y125807D01*
G01X857000Y105036D02*
Y117101D01*
G01X853310Y101346D02*
X857000Y105036D01*
G01X853310Y96090D02*
Y101346D01*
G01X891063Y106124D02*
X892163Y105024D01*
G01X891063Y111618D02*
Y106124D01*
G01X890354Y112327D02*
X891063Y111618D01*
G01X865592Y145754D02*
Y144892D01*
G01X863405Y147941D02*
X865592Y145754D01*
G01X863405Y148803D02*
Y147941D01*
G01X864389Y149787D02*
X863405Y148803D01*
G01X865251Y149787D02*
X864389D01*
G01X867438Y147600D02*
X865251Y149787D01*
G01X868300Y147600D02*
X867438D01*
G01X869284Y148584D02*
X868300Y147600D01*
G01X869284Y149446D02*
Y148584D01*
G01X867097Y151633D02*
X869284Y149446D01*
G01X867097Y152495D02*
Y151633D01*
G01X868081Y153479D02*
X867097Y152495D01*
G01X868943Y153479D02*
X868081D01*
G01X871130Y151292D02*
X868943Y153479D01*
G01X871992Y151292D02*
X871130D01*
G01X872976Y152276D02*
X871992Y151292D01*
G01X872976Y153138D02*
Y152276D01*
G01X870789Y155325D02*
X872976Y153138D01*
G01X870789Y156187D02*
Y155325D01*
G01X871773Y157171D02*
X870789Y156187D01*
G01X874822Y154984D02*
X872635Y157171D01*
G01X875684Y154984D02*
X874822D01*
G01X876668Y155968D02*
X875684Y154984D01*
G01X876668Y156830D02*
Y155968D01*
G01X892000Y126850D02*
X910641Y145491D01*
G01X887137Y126850D02*
X892000D01*
G01X876700Y116413D02*
X887137Y126850D01*
G01X876700Y95200D02*
Y116413D01*
G01X861364Y150236D02*
Y145114D01*
G01X872623Y161495D02*
X861364Y150236D01*
G01X893000Y106934D02*
X894913Y105021D01*
G01X853109Y129359D02*
X888150Y164400D01*
G01X853109Y128497D02*
Y129359D01*
G01X854372Y127234D02*
X853109Y128497D01*
G01X854372Y126372D02*
Y127234D01*
G01X853388Y125388D02*
X854372Y126372D01*
G01X852526Y125388D02*
X853388D01*
G01X851263Y126651D02*
X852526Y125388D01*
G01X850401Y126651D02*
X851263D01*
G01X849417Y125667D02*
X850401Y126651D01*
G01X849417Y124805D02*
Y125667D01*
G01X850680Y123542D02*
X849417Y124805D01*
G01X850680Y122680D02*
Y123542D01*
G01X849696Y121696D02*
X850680Y122680D01*
G01X848834Y121696D02*
X849696D01*
G01X872532Y96200D02*
X871732Y95400D01*
G01X873111Y96200D02*
X872532D01*
G01X874100Y97189D02*
X873111Y96200D01*
G01X874100Y98789D02*
Y97189D01*
G01X873300Y99589D02*
X874100Y98789D01*
G01X871800Y99589D02*
X873300D01*
G01X871000Y100389D02*
X871800Y99589D01*
G01X871000Y101989D02*
Y100389D01*
G01X871800Y102789D02*
X871000Y101989D01*
G01X873300Y102789D02*
X871800D01*
G01X874100Y103589D02*
X873300Y102789D01*
G01X874100Y105189D02*
Y103589D01*
G01X873300Y105989D02*
X874100Y105189D01*
G01X871800Y105989D02*
X873300D01*
G01X871000Y106789D02*
X871800Y105989D01*
G01X871000Y108389D02*
Y106789D01*
G01X871800Y109189D02*
X871000Y108389D01*
G01X873300Y109189D02*
X871800D01*
G01X874100Y109989D02*
X873300Y109189D01*
G01X874100Y111589D02*
Y109989D01*
G01X873300Y112389D02*
X874100Y111589D01*
G01X872260Y112389D02*
X873300D01*
G01X871700Y112949D02*
X872260Y112389D01*
G01X871700Y114948D02*
Y112949D01*
G01X888766Y132014D02*
X871700Y114948D01*
G01X889628Y132014D02*
X888766D01*
G01X890340Y131302D02*
X889628Y132014D01*
G01X891202Y131302D02*
X890340D01*
G01X892186Y132286D02*
X891202Y131302D01*
G01X892186Y133148D02*
Y132286D01*
G01X891474Y133860D02*
X892186Y133148D01*
G01X891474Y134722D02*
Y133860D01*
G01X913300Y156548D02*
X891474Y134722D01*
G01X909525Y136925D02*
X910387D01*
G01X908541Y135941D02*
X909525Y136925D01*
G01X908541Y135079D02*
Y135941D01*
G01X909529Y134091D02*
X908541Y135079D01*
G01X909529Y133229D02*
Y134091D01*
G01X908545Y132245D02*
X909529Y133229D01*
G01X907683Y132245D02*
X908545D01*
G01X906695Y133233D02*
X907683Y132245D01*
G01X905833Y133233D02*
X906695D01*
G01X904849Y132249D02*
X905833Y133233D01*
G01X904849Y131387D02*
Y132249D01*
G01X905837Y130399D02*
X904849Y131387D01*
G01X905837Y129537D02*
Y130399D01*
G01X904853Y128553D02*
X905837Y129537D01*
G01X903991Y128553D02*
X904853D01*
G01X903318Y129226D02*
X903991Y128553D01*
G01X902526Y129226D02*
X903318D01*
G01X901472Y128172D02*
X902526Y129226D01*
G01X901472Y127380D02*
Y128172D01*
G01X902145Y126707D02*
X901472Y127380D01*
G01X902145Y125845D02*
Y126707D01*
G01X899900Y123600D02*
X902145Y125845D01*
G01X887424Y123600D02*
X899900D01*
G01X879260Y115436D02*
X887424Y123600D01*
G01X884663Y106186D02*
X885563Y105286D01*
G01X884663Y111325D02*
Y106186D01*
G01X883661Y112327D02*
X884663Y111325D01*
G01X908463Y110950D02*
X907086Y112327D01*
G01X908463Y105675D02*
Y110950D01*
G01X909363Y104775D02*
X908463Y105675D01*
G01X888363Y105628D02*
X886707Y107284D01*
G01X857800Y129109D02*
X892100Y163409D01*
G01X857800Y125065D02*
Y129109D01*
G01X851390Y118655D02*
X857800Y125065D01*
G01X849860Y118655D02*
X851390D01*
G01X849250Y118045D02*
X849860Y118655D01*
G01X849250Y116655D02*
Y118045D01*
G01X849860Y116045D02*
X849250Y116655D01*
G01X851390Y116045D02*
X849860D01*
G01X852000Y115435D02*
X851390Y116045D01*
G01X852000Y114045D02*
Y115435D01*
G01X851390Y113435D02*
X852000Y114045D01*
G01X850210Y113435D02*
X851390D01*
G01X849650Y112875D02*
X850210Y113435D01*
G01X849650Y111385D02*
Y112875D01*
G01X850210Y110825D02*
X849650Y111385D01*
G01X851390Y110825D02*
X850210D01*
G01X852000Y110215D02*
X851390Y110825D01*
G01X852000Y108764D02*
Y110215D01*
G01X848500Y105264D02*
X852000Y108764D01*
G01X861794Y155256D02*
X858461Y158589D01*
G01X861794Y154394D02*
Y155256D01*
G01X860810Y153410D02*
X861794Y154394D01*
G01X859948Y153410D02*
X860810D01*
G01X856615Y156743D02*
X859948Y153410D01*
G01X854100Y155090D02*
X855753Y156743D01*
G01X854100Y153150D02*
Y155090D01*
G01X856807Y150443D02*
X854100Y153150D01*
G01X856807Y144757D02*
Y150443D01*
G01X851100Y104450D02*
Y95000D01*
G01X854650Y108000D02*
X851100Y104450D01*
G01X854650Y117650D02*
Y108000D01*
G01X860950Y123950D02*
X854650Y117650D01*
G01X860950Y128723D02*
Y123950D01*
G01X894600Y162373D02*
X860950Y128723D01*
G01X899600Y170675D02*
Y160301D01*
G01X912152Y183227D02*
X899600Y170675D01*
G01X869618Y215900D02*
X873684Y219966D01*
G01X867300Y215900D02*
X869618D01*
G01X909350Y186812D02*
X910394Y187856D01*
G01X909350Y183961D02*
Y186812D01*
G01X897100Y171711D02*
X909350Y183961D01*
G01X897100Y161337D02*
Y171711D01*
G01X874600Y212050D02*
X885137Y222587D01*
G01X867050Y212050D02*
X874600D01*
G01X849140Y187978D02*
Y189810D01*
G01X872635Y157171D02*
X871773D01*
G01X874481Y159017D02*
X876668Y156830D01*
G01X874481Y159879D02*
Y159017D01*
G01X875465Y160863D02*
X874481Y159879D01*
G01X876327Y160863D02*
X875465D01*
G01X878514Y158676D02*
X876327Y160863D01*
G01X879376Y158676D02*
X878514D01*
G01X880360Y159660D02*
X879376Y158676D01*
G01X880360Y160522D02*
Y159660D01*
G01X877122Y163760D02*
X880360Y160522D01*
G01X877122Y164622D02*
Y163760D01*
G01X878106Y165606D02*
X877122Y164622D01*
G01X878968Y165606D02*
X878106D01*
G01X882206Y162368D02*
X878968Y165606D01*
G01X883068Y162368D02*
X882206D01*
G01X885600Y164900D02*
X883068Y162368D01*
G01X885600Y179337D02*
Y164900D01*
G01X915300Y209037D02*
X885600Y179337D01*
G01X872623Y162627D02*
Y161495D01*
G01X869591Y165659D02*
X872623Y162627D01*
G01X869591Y166892D02*
Y165659D01*
G01X871265Y168566D02*
X869591Y166892D01*
G01X872127Y168566D02*
X871265D01*
G01X874190Y166504D02*
X872127Y168566D01*
G01X875052Y166504D02*
X874190D01*
G01X876036Y167488D02*
X875052Y166504D01*
G01X876036Y168350D02*
Y167488D01*
G01X875578Y168808D02*
X876036Y168350D01*
G01X873973Y170412D02*
X875578Y168808D01*
G01X873973Y171274D02*
Y170412D01*
G01X874957Y172258D02*
X873973Y171274D01*
G01X875819Y172258D02*
X874957D01*
G01X877882Y170196D02*
X875819Y172258D01*
G01X878744Y170196D02*
X877882D01*
G01X879728Y171180D02*
X878744Y170196D01*
G01X879728Y172042D02*
Y171180D01*
G01X877665Y174104D02*
X879728Y172042D01*
G01X877665Y174966D02*
Y174104D01*
G01X878649Y175950D02*
X877665Y174966D01*
G01X879511Y175950D02*
X878649D01*
G01X879961Y175500D02*
X879511Y175950D01*
G01X881574Y173888D02*
X879961Y175500D01*
G01X882436Y173888D02*
X881574D01*
G01X883420Y174872D02*
X882436Y173888D01*
G01X883420Y175734D02*
Y174872D01*
G01X881357Y177796D02*
X883420Y175734D01*
G01X881357Y178658D02*
Y177796D01*
G01X920310Y217611D02*
X881357Y178658D01*
G01X872744Y207294D02*
X888400Y222950D01*
G01X871882Y207294D02*
X872744D01*
G01X869619Y209557D02*
X871882Y207294D01*
G01X868757Y209557D02*
X869619D01*
G01X867773Y208573D02*
X868757Y209557D01*
G01X867773Y207711D02*
Y208573D01*
G01X870036Y205448D02*
X867773Y207711D01*
G01X870036Y204586D02*
Y205448D01*
G01X869052Y203602D02*
X870036Y204586D01*
G01X868190Y203602D02*
X869052D01*
G01X865927Y205865D02*
X868190Y203602D01*
G01X865065Y205865D02*
X865927D01*
G01X864081Y204881D02*
X865065Y205865D01*
G01X864081Y204019D02*
Y204881D01*
G01X866344Y201756D02*
X864081Y204019D01*
G01X866344Y200894D02*
Y201756D01*
G01X865360Y199910D02*
X866344Y200894D01*
G01X864498Y199910D02*
X865360D01*
G01X862235Y202173D02*
X864498Y199910D01*
G01X861373Y202173D02*
X862235D01*
G01X860389Y201189D02*
X861373Y202173D01*
G01X860389Y200327D02*
Y201189D01*
G01X862652Y198064D02*
X860389Y200327D01*
G01X862652Y197202D02*
Y198064D01*
G01X861668Y196218D02*
X862652Y197202D01*
G01X860806Y196218D02*
X861668D01*
G01X858543Y198481D02*
X860806Y196218D01*
G01X857681Y198481D02*
X858543D01*
G01X856697Y197497D02*
X857681Y198481D01*
G01X856697Y196635D02*
Y197497D01*
G01X858960Y194372D02*
X856697Y196635D01*
G01X858960Y193510D02*
Y194372D01*
G01X857976Y192526D02*
X858960Y193510D01*
G01X857114Y192526D02*
X857976D01*
G01X854851Y194789D02*
X857114Y192526D01*
G01X853989Y194789D02*
X854851D01*
G01X853005Y193805D02*
X853989Y194789D01*
G01X853005Y192943D02*
Y193805D01*
G01X855268Y190680D02*
X853005Y192943D01*
G01X855268Y189818D02*
Y190680D01*
G01X903000Y192200D02*
X919800Y209000D01*
G01X901910Y192200D02*
X903000D01*
G01X901300Y191590D02*
X901910Y192200D01*
G01X901300Y191501D02*
Y191590D01*
G01X897154Y187355D02*
X901300Y191501D01*
G01X897154Y186493D02*
Y187355D01*
G01X898366Y185280D02*
X897154Y186493D01*
G01X898366Y184418D02*
Y185280D01*
G01X897382Y183434D02*
X898366Y184418D01*
G01X896520Y183434D02*
X897382D01*
G01X895308Y184647D02*
X896520Y183434D01*
G01X894446Y184647D02*
X895308D01*
G01X893462Y183663D02*
X894446Y184647D01*
G01X893462Y182801D02*
Y183663D01*
G01X894674Y181588D02*
X893462Y182801D01*
G01X894674Y180726D02*
Y181588D01*
G01X893690Y179742D02*
X894674Y180726D01*
G01X892828Y179742D02*
X893690D01*
G01X891616Y180955D02*
X892828Y179742D01*
G01X890754Y180955D02*
X891616D01*
G01X888150Y178351D02*
X890754Y180955D01*
G01X888150Y164400D02*
Y178351D01*
G01X904900Y186583D02*
Y190501D01*
G01X892100Y173783D02*
X904900Y186583D01*
G01X892100Y163409D02*
Y173783D01*
G01X865845Y166835D02*
X919121Y220111D01*
G01X865845Y165973D02*
Y166835D01*
G01X869178Y162640D02*
X865845Y165973D01*
G01X869178Y161778D02*
Y162640D01*
G01X868194Y160794D02*
X869178Y161778D01*
G01X867332Y160794D02*
X868194D01*
G01X863999Y164127D02*
X867332Y160794D01*
G01X863137Y164127D02*
X863999D01*
G01X862153Y163143D02*
X863137Y164127D01*
G01X862153Y162281D02*
Y163143D01*
G01X865486Y158948D02*
X862153Y162281D01*
G01X865486Y158086D02*
Y158948D01*
G01X864502Y157102D02*
X865486Y158086D01*
G01X863640Y157102D02*
X864502D01*
G01X860307Y160435D02*
X863640Y157102D01*
G01X859445Y160435D02*
X860307D01*
G01X858461Y159451D02*
X859445Y160435D01*
G01X858461Y158589D02*
Y159451D01*
G01X855753Y156743D02*
X856615D01*
G01X894600Y172747D02*
Y162373D01*
G01X906950Y185097D02*
X894600Y172747D01*
G01X906950Y187500D02*
Y185097D01*
G01X907817Y188367D02*
X906950Y187500D01*
G01X902450Y222550D02*
Y217950D01*
G01X912175Y232275D02*
X902450Y222550D01*
G01X879284Y225566D02*
X903303Y249585D01*
G01X879284Y222684D02*
Y225566D01*
G01X876566Y219966D02*
X879284Y222684D01*
G01X873684Y219966D02*
X876566D01*
G01X885137Y227863D02*
X905281Y248007D01*
G01X885137Y222587D02*
Y227863D01*
G01X904300Y271650D02*
X915019D01*
G01X862100Y229450D02*
X904300Y271650D01*
G01X861000Y229450D02*
X862100D01*
G01X909133Y239841D02*
X909886D01*
G01X894950Y225658D02*
X909133Y239841D01*
G01X894950Y221058D02*
Y225658D01*
G01X863050Y227400D02*
X861750D01*
G01X904971Y269321D02*
X863050Y227400D01*
G01X911506Y269321D02*
X904971D01*
G01X888400Y227590D02*
X905849Y245039D01*
G01X888400Y222950D02*
Y227590D01*
G01X891700Y227354D02*
X908017Y243671D01*
G01X891700Y222550D02*
Y227354D01*
G01X905050Y275400D02*
X914647D01*
G01X861650Y232000D02*
X905050Y275400D01*
G01X860600Y232000D02*
X861650D01*
G01X910097Y236500D02*
X911081Y237484D01*
G01X909328Y236500D02*
X910097D01*
G01X897450Y224622D02*
X909328Y236500D01*
G01X897450Y220022D02*
Y224622D01*
G01X905371Y266821D02*
X911506D01*
G01X864000Y225450D02*
X905371Y266821D01*
G01X862650Y225450D02*
X864000D01*
G01X899950Y223586D02*
X910907Y234543D01*
G01X899950Y218986D02*
Y223586D01*
G01X903360Y340941D02*
X873411Y370890D01*
G01X905056Y340941D02*
X903360D01*
G01X900257Y329880D02*
X865636Y364501D01*
G01X908816Y329880D02*
X900257D01*
G01X898785Y324280D02*
X861866Y361199D01*
G01X909426Y324280D02*
X898785D01*
G01X897749Y321780D02*
X859981Y359548D01*
G01X909426Y321780D02*
X897749D01*
G01X899221Y327380D02*
X863751Y362850D01*
G01X908696Y327380D02*
X899221D01*
G01X910900Y389300D02*
X889300Y410900D01*
G01X873411Y370890D02*
Y384788D01*
G01X877181Y372885D02*
Y386518D01*
G01X901966Y348100D02*
X877181Y372885D01*
G01X884985Y380187D02*
X906556Y358616D01*
G01X884985Y388421D02*
Y380187D01*
G01X860785Y412621D02*
X884985Y388421D01*
G01X908400Y387632D02*
X883114Y412918D01*
G01X908400Y385260D02*
Y387632D01*
G01X912787Y380873D02*
X908400Y385260D01*
G01X865636Y364501D02*
Y381463D01*
G01X861866Y361199D02*
Y379833D01*
G01X859981Y374967D02*
X857188Y381711D01*
G01X859981Y359548D02*
Y374967D01*
G01X898200Y392500D02*
X877700Y413000D01*
G01X898200Y388388D02*
Y392500D01*
G01X906947Y379641D02*
X898200Y388388D01*
G01X911958Y398644D02*
X901300Y409302D01*
G01X879066Y373667D02*
Y387417D01*
G01X902716Y350017D02*
X879066Y373667D01*
G01X888755Y389983D02*
X864555Y414183D01*
G01X888755Y383489D02*
Y389983D01*
G01X909800Y362444D02*
X888755Y383489D01*
G01X883100Y387640D02*
X858900Y411840D01*
G01X883100Y377700D02*
Y387640D01*
G01X901200Y359600D02*
X883100Y377700D01*
G01X902036Y359600D02*
X901200D01*
G01X904895Y356741D02*
X902036Y359600D01*
G01X863751Y362850D02*
Y380648D01*
G01X875296Y372105D02*
Y385603D01*
G01X903960Y343441D02*
X875296Y372105D01*
G01X905056Y343441D02*
X903960D01*
G01X900085Y393281D02*
X880400Y412966D01*
G01X900085Y390039D02*
Y393281D01*
G01X908656Y381468D02*
X900085Y390039D01*
G01X886870Y389202D02*
X862670Y413402D01*
G01X886870Y381838D02*
Y389202D01*
G01X908067Y360641D02*
X886870Y381838D01*
G01X889609Y442490D02*
X851100Y480999D01*
G01X889609Y441358D02*
Y442490D01*
G01X888478Y440227D02*
X889609Y441358D01*
G01X887346Y440227D02*
X888478D01*
G01X880682Y446891D02*
X887346Y440227D01*
G01X879550Y446891D02*
X880682D01*
G01X878419Y445760D02*
X879550Y446891D01*
G01X878419Y444628D02*
Y445760D01*
G01X889300Y433747D02*
X878419Y444628D01*
G01X889300Y421922D02*
Y433747D01*
G01X888690Y421312D02*
X889300Y421922D01*
G01X886164Y421312D02*
X888690D01*
G01X885554Y420702D02*
X886164Y421312D01*
G01X885554Y419312D02*
Y420702D01*
G01X886164Y418702D02*
X885554Y419312D01*
G01X888690Y418702D02*
X886164D01*
G01X889300Y418092D02*
X888690Y418702D01*
G01X889300Y416702D02*
Y418092D01*
G01X888690Y416092D02*
X889300Y416702D01*
G01X886164Y416092D02*
X888690D01*
G01X885554Y415482D02*
X886164Y416092D01*
G01X885554Y414092D02*
Y415482D01*
G01X886164Y413482D02*
X885554Y414092D01*
G01X888690Y413482D02*
X886164D01*
G01X889300Y412872D02*
X888690Y413482D01*
G01X889300Y410900D02*
Y412872D01*
G01X860785Y417615D02*
Y412621D01*
G01X877146Y449446D02*
Y450578D01*
G01X876015Y448315D02*
X877146Y449446D01*
G01X874883Y448315D02*
X876015D01*
G01X868115Y455083D02*
X874883Y448315D01*
G01X866983Y455083D02*
X868115D01*
G01X866305Y454405D02*
X866983Y455083D01*
G01X866305Y453697D02*
Y454405D01*
G01X886403Y433599D02*
X866305Y453697D01*
G01X886403Y431150D02*
Y433599D01*
G01X885793Y430540D02*
X886403Y431150D01*
G01X883087Y430540D02*
X885793D01*
G01X882477Y429930D02*
X883087Y430540D01*
G01X882477Y428540D02*
Y429930D01*
G01X883087Y427930D02*
X882477Y428540D01*
G01X885793Y427930D02*
X883087D01*
G01X886403Y427320D02*
X885793Y427930D01*
G01X886403Y424947D02*
Y427320D01*
G01X883114Y421658D02*
X886403Y424947D01*
G01X883114Y412918D02*
Y421658D01*
G01X900800Y447641D02*
X862600Y485841D01*
G01X900800Y429001D02*
Y447641D01*
G01X913397Y416404D02*
X900800Y429001D01*
G01X908729Y464098D02*
X889438Y483389D01*
G01X908729Y463236D02*
Y464098D01*
G01X907745Y462252D02*
X908729Y463236D01*
G01X906883Y462252D02*
X907745D01*
G01X902547Y466588D02*
X906883Y462252D01*
G01X900701Y464742D02*
Y465604D01*
G01X913400Y452043D02*
X900701Y464742D01*
G01X898300Y446605D02*
X860100Y484805D01*
G01X898300Y427901D02*
Y446605D01*
G01X908624Y417577D02*
X898300Y427901D01*
G01X908624Y411144D02*
Y417577D01*
G01X916533Y403235D02*
X908624Y411144D01*
G01X850600Y461000D02*
Y463236D01*
G01X874846Y436754D02*
X850600Y461000D01*
G01X874846Y434949D02*
Y436754D01*
G01X873715Y433818D02*
X874846Y434949D01*
G01X872583Y433818D02*
X873715D01*
G01X864244Y442157D02*
X872583Y433818D01*
G01X863212Y442157D02*
X864244D01*
G01X862081Y441026D02*
X863212Y442157D01*
G01X862081Y439794D02*
Y441026D01*
G01X877700Y424175D02*
X862081Y439794D01*
G01X877700Y413000D02*
Y424175D01*
G01X893300Y444533D02*
X855100Y482733D01*
G01X893300Y424899D02*
Y444533D01*
G01X901300Y416899D02*
X893300Y424899D01*
G01X901300Y409302D02*
Y416899D01*
G01X898654Y463766D02*
Y470623D01*
G01X910900Y451520D02*
X898654Y463766D01*
G01X864555Y420445D02*
Y423745D01*
G01X865500Y419500D02*
X864555Y420445D01*
G01X867900Y419500D02*
X865500D01*
G01X868800Y418600D02*
X867900Y419500D01*
G01X868800Y417400D02*
Y418600D01*
G01X868100Y416700D02*
X868800Y417400D01*
G01X865055Y416700D02*
X868100D01*
G01X864555Y416200D02*
X865055Y416700D01*
G01X864555Y414183D02*
Y416200D01*
G01X858900Y411840D02*
Y416800D01*
G01X865428Y458760D02*
X855551Y468637D01*
G01X865428Y457628D02*
Y458760D01*
G01X864297Y456497D02*
X865428Y457628D01*
G01X863165Y456497D02*
X864297D01*
G01X855363Y464299D02*
X863165Y456497D01*
G01X854231Y464299D02*
X855363D01*
G01X853100Y463168D02*
X854231Y464299D01*
G01X853100Y462036D02*
Y463168D01*
G01X880400Y434736D02*
X853100Y462036D01*
G01X880400Y432476D02*
Y434736D01*
G01X879790Y431866D02*
X880400Y432476D01*
G01X877147Y431866D02*
X879790D01*
G01X876537Y431256D02*
X877147Y431866D01*
G01X876537Y429866D02*
Y431256D01*
G01X877147Y429256D02*
X876537Y429866D01*
G01X879790Y429256D02*
X877147D01*
G01X880400Y428646D02*
X879790Y429256D01*
G01X880400Y412966D02*
Y428646D01*
G01X895800Y445569D02*
X857600Y483769D01*
G01X895800Y427699D02*
Y445569D01*
G01X898595Y424904D02*
X895800Y427699D01*
G01X898595Y424042D02*
Y424904D01*
G01X898158Y423605D02*
X898595Y424042D01*
G01X898158Y422744D02*
Y423605D01*
G01X899559Y421343D02*
X898158Y422744D01*
G01X900421Y421343D02*
X899559D01*
G01X900858Y421779D02*
X900421Y421343D01*
G01X901720Y421779D02*
X900858D01*
G01X903121Y420378D02*
X901720Y421779D01*
G01X903121Y419516D02*
Y420378D01*
G01X902683Y419078D02*
X903121Y419516D01*
G01X902683Y418216D02*
Y419078D01*
G01X903903Y416996D02*
X902683Y418216D01*
G01X903903Y415240D02*
Y416996D01*
G01X904513Y414630D02*
X903903Y415240D01*
G01X906104Y414630D02*
X904513D01*
G01X906714Y414020D02*
X906104Y414630D01*
G01X906714Y412630D02*
Y414020D01*
G01X906104Y412020D02*
X906714Y412630D01*
G01X904513Y412020D02*
X906104D01*
G01X903903Y411410D02*
X904513Y412020D01*
G01X903903Y410235D02*
Y411410D01*
G01X913826Y400312D02*
X903903Y410235D01*
G01X862670Y413402D02*
Y418430D01*
G01X888700Y519579D02*
Y527700D01*
G01X888321Y519200D02*
X888700Y519579D01*
G01X888321Y517457D02*
Y519200D01*
G01X888571Y517207D02*
X888321Y517457D01*
G01X888571Y511007D02*
Y517207D01*
G01X888221Y510657D02*
X888571Y511007D01*
G01X888221Y503800D02*
Y510657D01*
G01X886600Y502179D02*
X888221Y503800D01*
G01X886600Y495701D02*
Y502179D01*
G01X888221Y494080D02*
X886600Y495701D01*
G01X888221Y492521D02*
Y494080D01*
G01X886500Y490800D02*
X888221Y492521D01*
G01X850670Y498969D02*
Y500330D01*
G01X850127Y498426D02*
X850670Y498969D01*
G01X848630Y498426D02*
X850127D01*
G01X850300Y495493D02*
X848553D01*
G01X851100Y494693D02*
X850300Y495493D01*
G01X851100Y493093D02*
Y494693D01*
G01X850300Y492293D02*
X851100Y493093D01*
G01X849122Y492293D02*
X850300D01*
G01Y489093D02*
X849122D01*
G01X851100Y488293D02*
X850300Y489093D01*
G01X851100Y486693D02*
Y488293D01*
G01X850300Y485893D02*
X851100Y486693D01*
G01X849017Y485893D02*
X850300D01*
G01Y482693D02*
X849069D01*
G01X851100Y481893D02*
X850300Y482693D01*
G01X851100Y480999D02*
Y481893D01*
G01X882000Y519540D02*
Y527600D01*
G01X881760Y519300D02*
X882000Y519540D01*
G01X881760Y517357D02*
Y519300D01*
G01X882310Y516807D02*
X881760Y517357D01*
G01X882310Y512257D02*
Y516807D01*
G01X881100Y511047D02*
X882310Y512257D01*
G01X881100Y492900D02*
Y511047D01*
G01X885500Y488500D02*
X881100Y492900D01*
G01X890467Y488500D02*
X885500D01*
G01X893377Y485590D02*
X890467Y488500D01*
G01X894239Y485590D02*
X893377D01*
G01X895896Y487247D02*
X894239Y485590D01*
G01X896758Y487247D02*
X895896D01*
G01X897742Y486263D02*
X896758Y487247D01*
G01X897742Y485401D02*
Y486263D01*
G01X896085Y483744D02*
X897742Y485401D01*
G01X896085Y482882D02*
Y483744D01*
G01X913180Y465787D02*
X896085Y482882D01*
G01X908800Y519521D02*
Y527500D01*
G01X909121Y519200D02*
X908800Y519521D01*
G01X909121Y517557D02*
Y519200D01*
G01X908521Y516957D02*
X909121Y517557D01*
G01X908521Y512057D02*
Y516957D01*
G01X909321Y511257D02*
X908521Y512057D01*
G01X909321Y503022D02*
Y511257D01*
G01X907086Y500787D02*
X909321Y503022D01*
G01X907086Y498487D02*
Y500787D01*
G01X859600Y525885D02*
Y527100D01*
G01X858990Y525275D02*
X859600Y525885D01*
G01X857510Y525275D02*
X858990D01*
G01X856900Y524665D02*
X857510Y525275D01*
G01X856900Y522685D02*
Y524665D01*
G01X857510Y522075D02*
X856900Y522685D01*
G01X858990Y522075D02*
X857510D01*
G01X859600Y521465D02*
X858990Y522075D01*
G01X859600Y520400D02*
Y521465D01*
G01X858110Y518910D02*
X859600Y520400D01*
G01X858110Y508790D02*
Y518910D01*
G01X864100Y502800D02*
X858110Y508790D01*
G01X864100Y500941D02*
Y502800D01*
G01X862600Y499441D02*
X864100Y500941D01*
G01X862600Y497741D02*
Y499441D01*
G01X864100Y496241D02*
X862600Y497741D01*
G01X864100Y495101D02*
Y496241D01*
G01X862600Y493601D02*
X864100Y495101D01*
G01X862600Y492301D02*
Y493601D01*
G01X864100Y490801D02*
X862600Y492301D01*
G01X864100Y490101D02*
Y490801D01*
G01X862600Y488601D02*
X864100Y490101D01*
G01X862600Y485841D02*
Y488601D01*
G01X885477Y517213D02*
Y529523D01*
G01X884721Y516457D02*
X885477Y517213D01*
G01X884721Y511757D02*
Y516457D01*
G01X885721Y510757D02*
X884721Y511757D01*
G01X885721Y504421D02*
Y510757D01*
G01X882900Y501600D02*
X885721Y504421D01*
G01X882900Y498500D02*
Y501600D01*
G01X875300Y519990D02*
Y527900D01*
G01X874810Y519500D02*
X875300Y519990D01*
G01X874810Y517589D02*
Y519500D01*
G01X875910Y516489D02*
X874810Y517589D01*
G01X875910Y512157D02*
Y516489D01*
G01X875010Y511257D02*
X875910Y512157D01*
G01X875010Y509190D02*
Y511257D01*
G01X876700Y507500D02*
X875010Y509190D01*
G01X876700Y490677D02*
Y507500D01*
G01X883988Y483389D02*
X876700Y490677D01*
G01X889438Y483389D02*
X883988D01*
G01X901685Y466588D02*
X902547D01*
G01X900701Y465604D02*
X901685Y466588D01*
G01X878644Y519966D02*
Y527844D01*
G01X879210Y519400D02*
X878644Y519966D01*
G01X879210Y517809D02*
Y519400D01*
G01X878410Y517009D02*
X879210Y517809D01*
G01X878410Y511657D02*
Y517009D01*
G01X879200Y510867D02*
X878410Y511657D01*
G01X879200Y491977D02*
Y510867D01*
G01X885288Y485889D02*
X879200Y491977D01*
G01X889788Y485889D02*
X885288D01*
G01X910852Y464825D02*
X889788Y485889D01*
G01X854899Y520011D02*
Y527499D01*
G01X855376Y519534D02*
X854899Y520011D01*
G01X855376Y517575D02*
Y519534D01*
G01X854100Y516299D02*
X855376Y517575D01*
G01X854100Y512217D02*
Y516299D01*
G01X855592Y510725D02*
X854100Y512217D01*
G01X855592Y508008D02*
Y510725D01*
G01X860100Y503500D02*
X855592Y508008D01*
G01X860100Y484805D02*
Y503500D01*
G01X848789Y468579D02*
Y469711D01*
G01X848810Y517389D02*
Y529489D01*
G01X848774Y508226D02*
Y510893D01*
G01X855100Y501900D02*
X848774Y508226D01*
G01X855100Y482733D02*
Y501900D01*
G01X895400Y519599D02*
Y529300D01*
G01X894921Y519120D02*
X895400Y519599D01*
G01X894921Y505999D02*
Y519120D01*
G01X893000Y504078D02*
X894921Y505999D01*
G01X893000Y495694D02*
Y504078D01*
G01X871900Y520010D02*
Y527800D01*
G01X872310Y519600D02*
X871900Y520010D01*
G01X872310Y517557D02*
Y519600D01*
G01X871710Y516957D02*
X872310Y517557D01*
G01X871710Y512057D02*
Y516957D01*
G01X872510Y511257D02*
X871710Y512057D01*
G01X872510Y508591D02*
Y511257D01*
G01X874200Y506901D02*
X872510Y508591D01*
G01X874200Y489377D02*
Y506901D01*
G01X882688Y480889D02*
X874200Y489377D01*
G01X888388Y480889D02*
X882688D01*
G01X898654Y470623D02*
X888388Y480889D01*
G01X852426Y471762D02*
X848760Y475428D01*
G01X852426Y470900D02*
Y471762D01*
G01X850894Y469368D02*
X852426Y470900D01*
G01X850894Y468506D02*
Y469368D01*
G01X852295Y467105D02*
X850894Y468506D01*
G01X853157Y467105D02*
X852295D01*
G01X854689Y468637D02*
X853157Y467105D01*
G01X855551Y468637D02*
X854689D01*
G01X851900Y519590D02*
Y527600D01*
G01X851205Y518895D02*
X851900Y519590D01*
G01X851205Y517194D02*
Y518895D01*
G01X852300Y516099D02*
X851205Y517194D01*
G01X852300Y511799D02*
Y516099D01*
G01X851300Y510799D02*
X852300Y511799D01*
G01X851300Y508700D02*
Y510799D01*
G01X857600Y502400D02*
X851300Y508700D01*
G01X857600Y483769D02*
Y502400D01*
G01X908800Y499399D02*
X911821Y502420D01*
G01X908800Y495100D02*
Y499399D01*
G01X907846Y494146D02*
X908800Y495100D01*
G01X907846Y493354D02*
Y494146D01*
G01X908243Y492957D02*
X907846Y493354D01*
G01X909645Y492957D02*
X908243D01*
G01X910432Y493744D02*
X909645Y492957D01*
G01X892000Y519321D02*
Y527900D01*
G01X892221Y519100D02*
X892000Y519321D01*
G01X892221Y517457D02*
Y519100D01*
G01X891071Y516307D02*
X892221Y517457D01*
G01X891071Y512057D02*
Y516307D01*
G01X892421Y510707D02*
X891071Y512057D01*
G01X892421Y508498D02*
Y510707D01*
G01X890900Y506977D02*
X892421Y508498D01*
G01X890900Y497600D02*
Y506977D01*
G01X889200Y495900D02*
X890900Y497600D01*
G01X884733Y566699D02*
X883661D01*
G01X885333Y566099D02*
X884733Y566699D01*
G01X885333Y565201D02*
Y566099D01*
G01X884296Y564164D02*
X885333Y565201D01*
G01X884296Y562936D02*
Y564164D01*
G01X885233Y561999D02*
X884296Y562936D01*
G01X885233Y560601D02*
Y561999D01*
G01X884296Y559664D02*
X885233Y560601D01*
G01X884296Y558336D02*
Y559664D01*
G01X885433Y557199D02*
X884296Y558336D01*
G01X885433Y555300D02*
Y557199D01*
G01X884933Y554800D02*
X885433Y555300D01*
G01X884933Y552600D02*
Y554800D01*
G01X886619Y550914D02*
X884933Y552600D01*
G01X886707Y550914D02*
X886619D01*
G01X888221Y549400D02*
X886707Y550914D01*
G01X888221Y546879D02*
Y549400D01*
G01X888700Y546400D02*
X888221Y546879D01*
G01X888700Y537879D02*
Y546400D01*
G01X888221Y537400D02*
X888700Y537879D01*
G01X888221Y535456D02*
Y537400D01*
G01X888821Y534856D02*
X888221Y535456D01*
G01X888821Y530697D02*
Y534856D01*
G01X888321Y530197D02*
X888821Y530697D01*
G01X888321Y528079D02*
Y530197D01*
G01X888700Y527700D02*
X888321Y528079D01*
G01X878040Y566699D02*
X876968D01*
G01X878740Y565999D02*
X878040Y566699D01*
G01X878740Y564725D02*
Y565999D01*
G01X877603Y563588D02*
X878740Y564725D01*
G01X877603Y562512D02*
Y563588D01*
G01X878615Y561500D02*
X877603Y562512D01*
G01X878615Y560300D02*
Y561500D01*
G01X877603Y559288D02*
X878615Y560300D01*
G01X877603Y558212D02*
Y559288D01*
G01X878715Y557100D02*
X877603Y558212D01*
G01X878715Y554467D02*
Y557100D01*
G01X878540Y554292D02*
X878715Y554467D01*
G01X878540Y552600D02*
Y554292D01*
G01X880226Y550914D02*
X878540Y552600D01*
G01X880314Y550914D02*
X880226D01*
G01X880314Y550966D02*
Y550914D01*
G01X881610Y549670D02*
X880314Y550966D01*
G01X881610Y546790D02*
Y549670D01*
G01X882000Y546400D02*
X881610Y546790D01*
G01X882000Y537900D02*
Y546400D01*
G01X881610Y537510D02*
X882000Y537900D01*
G01X881610Y536390D02*
Y537510D01*
G01X882610Y535390D02*
X881610Y536390D01*
G01X882610Y530697D02*
Y535390D01*
G01X881760Y529847D02*
X882610Y530697D01*
G01X881760Y527840D02*
Y529847D01*
G01X882000Y527600D02*
X881760Y527840D01*
G01X905381Y567849D02*
X910432Y572900D01*
G01X905381Y557662D02*
Y567849D01*
G01X907086Y555957D02*
X905381Y557662D01*
G01X906421Y555292D02*
X907086Y555957D01*
G01X906421Y551457D02*
Y555292D01*
G01X909321Y548557D02*
X906421Y551457D01*
G01X909321Y546721D02*
Y548557D01*
G01X908800Y546200D02*
X909321Y546721D01*
G01X908800Y538121D02*
Y546200D01*
G01X909321Y537600D02*
X908800Y538121D01*
G01X909321Y536442D02*
Y537600D01*
G01X908048Y535169D02*
X909321Y536442D01*
G01X908048Y530670D02*
Y535169D01*
G01X909121Y529597D02*
X908048Y530670D01*
G01X909121Y527821D02*
Y529597D01*
G01X908800Y527500D02*
X909121Y527821D01*
G01X858110Y548993D02*
X856189Y550914D01*
G01X858110Y546890D02*
Y548993D01*
G01X858900Y546100D02*
X858110Y546890D01*
G01X858900Y544747D02*
Y546100D01*
G01X858290Y544137D02*
X858900Y544747D01*
G01X857210Y544137D02*
X858290D01*
G01X856600Y543527D02*
X857210Y544137D01*
G01X856600Y541547D02*
Y543527D01*
G01X857210Y540937D02*
X856600Y541547D01*
G01X858290Y540937D02*
X857210D01*
G01X858900Y540327D02*
X858290Y540937D01*
G01X858900Y538600D02*
Y540327D01*
G01X858110Y537810D02*
X858900Y538600D01*
G01X858110Y528590D02*
Y537810D01*
G01X859600Y527100D02*
X858110Y528590D01*
G01X854523Y566699D02*
X853543D01*
G01X855122Y566100D02*
X854523Y566699D01*
G01X855122Y564900D02*
Y566100D01*
G01X854178Y563956D02*
X855122Y564900D01*
G01X854178Y562744D02*
Y563956D01*
G01X855022Y561900D02*
X854178Y562744D01*
G01X855022Y560200D02*
Y561900D01*
G01X854178Y559356D02*
X855022Y560200D01*
G01X854178Y557936D02*
Y559356D01*
G01X855322Y556792D02*
X854178Y557936D01*
G01X855322Y555199D02*
Y556792D01*
G01X854415Y554292D02*
X855322Y555199D01*
G01X854415Y552600D02*
Y554292D01*
G01X856101Y550914D02*
X854415Y552600D01*
G01X856189Y550914D02*
X856101D01*
G01X885633Y572500D02*
X886621D01*
G01X882578Y569445D02*
X885633Y572500D01*
G01X882578Y568257D02*
Y569445D01*
G01X881956Y567635D02*
X882578Y568257D01*
G01X881956Y557662D02*
Y567635D01*
G01X883661Y555957D02*
X881956Y557662D01*
G01X883157Y555453D02*
X883661Y555957D01*
G01X883157Y551071D02*
Y555453D01*
G01X885501Y548727D02*
X883157Y551071D01*
G01X885501Y536072D02*
Y548727D01*
G01X884695Y535266D02*
X885501Y536072D01*
G01X884695Y530305D02*
Y535266D01*
G01X885477Y529523D02*
X884695Y530305D01*
G01X874967Y549568D02*
X873621Y550914D01*
G01X875010Y549568D02*
X874967D01*
G01X875010Y546890D02*
Y549568D01*
G01X875300Y546600D02*
X875010Y546890D01*
G01X875300Y538000D02*
Y546600D01*
G01X875010Y537710D02*
X875300Y538000D01*
G01X875010Y536091D02*
Y537710D01*
G01X875676Y535425D02*
X875010Y536091D01*
G01X875676Y530363D02*
Y535425D01*
G01X875110Y529797D02*
X875676Y530363D01*
G01X875110Y528090D02*
Y529797D01*
G01X875300Y527900D02*
X875110Y528090D01*
G01X871347Y566699D02*
X870275D01*
G01X872047Y565999D02*
X871347Y566699D01*
G01X872047Y564725D02*
Y565999D01*
G01X870910Y563588D02*
X872047Y564725D01*
G01X870910Y562512D02*
Y563588D01*
G01X871922Y561500D02*
X870910Y562512D01*
G01X871922Y560300D02*
Y561500D01*
G01X870910Y559288D02*
X871922Y560300D01*
G01X870910Y558212D02*
Y559288D01*
G01X872022Y557100D02*
X870910Y558212D01*
G01X872022Y554467D02*
Y557100D01*
G01X871847Y554292D02*
X872022Y554467D01*
G01X871847Y552600D02*
Y554292D01*
G01X873533Y550914D02*
X871847Y552600D01*
G01X873621Y550914D02*
X873533D01*
G01X875610Y554599D02*
X876968Y555957D01*
G01X875610Y552107D02*
Y554599D01*
G01X879010Y548707D02*
X875610Y552107D01*
G01X879010Y547110D02*
Y548707D01*
G01X878700Y546800D02*
X879010Y547110D01*
G01X878700Y537910D02*
Y546800D01*
G01X879010Y537600D02*
X878700Y537910D01*
G01X879010Y536242D02*
Y537600D01*
G01X878110Y535342D02*
X879010Y536242D01*
G01X878110Y530369D02*
Y535342D01*
G01X879073Y529406D02*
X878110Y530369D01*
G01X879073Y528273D02*
Y529406D01*
G01X878644Y527844D02*
X879073Y528273D01*
G01X875263Y567849D02*
X880314Y572900D01*
G01X875263Y557662D02*
Y567849D01*
G01X876968Y555957D02*
X875263Y557662D01*
G01X852750Y555164D02*
X853543Y555957D01*
G01X852750Y551367D02*
Y555164D01*
G01X855243Y548874D02*
X852750Y551367D01*
G01X855243Y546043D02*
Y548874D01*
G01X854713Y545513D02*
X855243Y546043D01*
G01X854713Y538547D02*
Y545513D01*
G01X855455Y537805D02*
X854713Y538547D01*
G01X855455Y536549D02*
Y537805D01*
G01X854260Y535354D02*
X855455Y536549D01*
G01X854260Y530617D02*
Y535354D01*
G01X855410Y529467D02*
X854260Y530617D01*
G01X855410Y528010D02*
Y529467D01*
G01X854899Y527499D02*
X855410Y528010D01*
G01X855023Y572500D02*
X856189D01*
G01X851838Y569315D02*
X855023Y572500D01*
G01X851838Y557662D02*
Y569315D01*
G01X853543Y555957D02*
X851838Y557662D01*
G01X848760Y536142D02*
Y548441D01*
G01X848822Y572500D02*
X849810D01*
G01X893000Y550564D02*
Y550914D01*
G01X894921Y548643D02*
X893000Y550564D01*
G01X894921Y546979D02*
Y548643D01*
G01X895400Y546500D02*
X894921Y546979D01*
G01X895400Y538179D02*
Y546500D01*
G01X894921Y537700D02*
X895400Y538179D01*
G01X894921Y529779D02*
Y537700D01*
G01X895400Y529300D02*
X894921Y529779D01*
G01X891334Y566699D02*
X890354D01*
G01X891933Y566100D02*
X891334Y566699D01*
G01X891933Y564900D02*
Y566100D01*
G01X890989Y563956D02*
X891933Y564900D01*
G01X890989Y562744D02*
Y563956D01*
G01X891833Y561900D02*
X890989Y562744D01*
G01X891833Y560200D02*
Y561900D01*
G01X890989Y559356D02*
X891833Y560200D01*
G01X890989Y557936D02*
Y559356D01*
G01X892133Y556792D02*
X890989Y557936D01*
G01X892133Y555199D02*
Y556792D01*
G01X891226Y554292D02*
X892133Y555199D01*
G01X891226Y552600D02*
Y554292D01*
G01X892912Y550914D02*
X891226Y552600D01*
G01X893000Y550914D02*
X892912D01*
G01X868570Y557662D02*
X870275Y555957D01*
G01X868570Y567849D02*
Y557662D01*
G01X873621Y572900D02*
X868570Y567849D01*
G01X869610Y555292D02*
X870275Y555957D01*
G01X869610Y551457D02*
Y555292D01*
G01X872510Y548557D02*
X869610Y551457D01*
G01X872510Y547410D02*
Y548557D01*
G01X871900Y546800D02*
X872510Y547410D01*
G01X871900Y538210D02*
Y546800D01*
G01X872510Y537600D02*
X871900Y538210D01*
G01X872510Y536442D02*
Y537600D01*
G01X871237Y535169D02*
X872510Y536442D01*
G01X871237Y530670D02*
Y535169D01*
G01X872310Y529597D02*
X871237Y530670D01*
G01X872310Y528210D02*
Y529597D01*
G01X871900Y527800D02*
X872310Y528210D01*
G01X870275Y555957D02*
Y555961D01*
G01X850600Y550210D02*
X849896Y550914D01*
G01X850600Y547600D02*
Y550210D01*
G01X851900Y546300D02*
X850600Y547600D01*
G01X851900Y537990D02*
Y546300D01*
G01X851410Y537500D02*
X851900Y537990D01*
G01X851410Y535456D02*
Y537500D01*
G01X852010Y534856D02*
X851410Y535456D01*
G01X852010Y530697D02*
Y534856D01*
G01X851510Y530197D02*
X852010Y530697D01*
G01X851510Y527990D02*
Y530197D01*
G01X851900Y527600D02*
X851510Y527990D01*
G01X848522Y565201D02*
Y566099D01*
G01X848422Y560601D02*
Y561999D01*
G01X848622Y555300D02*
Y557199D01*
G01X849896Y550914D02*
X849808D01*
G01X908158Y566699D02*
X907086D01*
G01X908858Y565999D02*
X908158Y566699D01*
G01X908858Y564725D02*
Y565999D01*
G01X907721Y563588D02*
X908858Y564725D01*
G01X907721Y562512D02*
Y563588D01*
G01X908733Y561500D02*
X907721Y562512D01*
G01X908733Y560300D02*
Y561500D01*
G01X907721Y559288D02*
X908733Y560300D01*
G01X907721Y558212D02*
Y559288D01*
G01X908833Y557100D02*
X907721Y558212D01*
G01X908833Y554467D02*
Y557100D01*
G01X908658Y554292D02*
X908833Y554467D01*
G01X908658Y552600D02*
Y554292D01*
G01X910344Y550914D02*
X908658Y552600D01*
G01X891834Y572500D02*
X893000D01*
G01X888649Y569315D02*
X891834Y572500D01*
G01X888649Y557662D02*
Y569315D01*
G01X890354Y555957D02*
X888649Y557662D01*
G01X888921Y554524D02*
X890354Y555957D01*
G01X888921Y552007D02*
Y554524D01*
G01X892271Y548657D02*
X888921Y552007D01*
G01X892271Y547071D02*
Y548657D01*
G01X892000Y546800D02*
X892271Y547071D01*
G01X892000Y538071D02*
Y546800D01*
G01X892271Y537800D02*
X892000Y538071D01*
G01X892271Y536471D02*
Y537800D01*
G01X891121Y535321D02*
X892271Y536471D01*
G01X891121Y530567D02*
Y535321D01*
G01X892221Y529467D02*
X891121Y530567D01*
G01X892221Y528121D02*
Y529467D01*
G01X892000Y527900D02*
X892221Y528121D01*
G01X920472Y25272D02*
Y17157D01*
G01X922300Y27100D02*
X920472Y25272D01*
G01X922300Y28499D02*
Y27100D01*
G01X921532Y29267D02*
X922300Y28499D01*
G01X921532Y34299D02*
Y29267D01*
G01X927738Y14187D02*
X929811Y12114D01*
G01X927738Y15238D02*
Y14187D01*
G01X929232Y16732D02*
X927738Y15238D01*
G01X929232Y23533D02*
Y16732D01*
G01X931732Y26033D02*
X929232Y23533D01*
G01X931732Y118832D02*
Y26033D01*
G01X912433Y33500D02*
X910633Y31700D01*
G01X952032Y28999D02*
Y34831D01*
G01X952832Y28199D02*
X952032Y28999D01*
G01X952832Y19399D02*
Y28199D01*
G01X950590Y17157D02*
X952832Y19399D01*
G01X963976Y32554D02*
X965700Y34278D01*
G01X963976Y28014D02*
Y32554D01*
G01X943897Y17897D02*
Y17157D01*
G01X945932Y19932D02*
X943897Y17897D01*
G01X945932Y28499D02*
Y19932D01*
G01X945332Y29099D02*
X945932Y28499D01*
G01X945332Y34731D02*
Y29099D01*
G01X915026Y29146D02*
X913779Y27899D01*
G01X915026Y30400D02*
Y29146D01*
G01X916326Y31700D02*
X915026Y30400D01*
G01X917326Y31700D02*
X916326D01*
G01X919126Y33500D02*
X917326Y31700D01*
G01X921600Y14032D02*
X923518Y12114D01*
G01X921600Y15600D02*
Y14032D01*
G01X923800Y17800D02*
X921600Y15600D01*
G01X923800Y24900D02*
Y17800D01*
G01X925132Y26232D02*
X923800Y24900D01*
G01X925132Y28599D02*
Y26232D01*
G01X925382Y28849D02*
X925132Y28599D01*
G01X925382Y35049D02*
Y28849D01*
G01X969432Y31000D02*
X970669Y28014D01*
G01X968950Y32165D02*
X969432Y31000D01*
G01X968950Y39613D02*
Y32165D01*
G01X926732Y17590D02*
X927165Y17157D01*
G01X926732Y24333D02*
Y17590D01*
G01X929032Y26633D02*
X926732Y24333D01*
G01X929032Y28467D02*
Y26633D01*
G01X927882Y29617D02*
X929032Y28467D01*
G01X927882Y34183D02*
Y29617D01*
G01X949532Y29499D02*
Y34367D01*
G01X948432Y28399D02*
X949532Y29499D01*
G01X948432Y25399D02*
Y28399D01*
G01X948732Y25099D02*
X948432Y25399D01*
G01X948732Y19072D02*
Y25099D01*
G01X945332Y15672D02*
X948732Y19072D01*
G01X945332Y14025D02*
Y15672D01*
G01X947243Y12114D02*
X945332Y14025D01*
G01X955932Y29249D02*
Y34769D01*
G01X955382Y28699D02*
X955932Y29249D01*
G01X955382Y18882D02*
Y28699D01*
G01X952032Y15532D02*
X955382Y18882D01*
G01X952032Y14018D02*
Y15532D01*
G01X953936Y12114D02*
X952032Y14018D01*
G01X922532Y35299D02*
X921532Y34299D01*
G01X922532Y40882D02*
Y35299D01*
G01X921600Y41814D02*
X922532Y40882D01*
G01X921600Y44082D02*
Y41814D01*
G01X922532Y45014D02*
X921600Y44082D01*
G01X922532Y47614D02*
Y45014D01*
G01X921532Y48614D02*
X922532Y47614D01*
G01X921532Y53414D02*
Y48614D01*
G01X922432Y54314D02*
X921532Y53414D01*
G01X922432Y59853D02*
Y54314D01*
G01X921600Y60685D02*
X922432Y59853D01*
G01X921600Y63053D02*
Y60685D01*
G01X922432Y63885D02*
X921600Y63053D01*
G01X922432Y66267D02*
Y63885D01*
G01X921532Y67167D02*
X922432Y66267D01*
G01X921532Y72099D02*
Y67167D01*
G01X922532Y73099D02*
X921532Y72099D01*
G01X922532Y78377D02*
Y73099D01*
G01X921700Y79209D02*
X922532Y78377D01*
G01X921700Y81577D02*
Y79209D01*
G01X922532Y82409D02*
X921700Y81577D01*
G01X922532Y85414D02*
Y82409D01*
G01X921532Y86414D02*
X922532Y85414D01*
G01X921532Y91214D02*
Y86414D01*
G01X922432Y92114D02*
X921532Y91214D01*
G01X922432Y98712D02*
Y92114D01*
G01X911263Y65747D02*
Y56332D01*
G01X912463Y66947D02*
X911263Y65747D01*
G01X912463Y72537D02*
Y66947D01*
G01X911874Y73126D02*
X912463Y72537D01*
G01X911874Y85985D02*
Y73126D01*
G01X912563Y86674D02*
X911874Y85985D01*
G01X912563Y91012D02*
Y86674D01*
G01X911863Y91712D02*
X912563Y91012D01*
G01X911863Y105853D02*
Y91712D01*
G01X912433Y34900D02*
Y33500D01*
G01X911821Y35512D02*
X912433Y34900D01*
G01X911821Y48525D02*
Y35512D01*
G01X910432Y49914D02*
X911821Y48525D01*
G01X952932Y92164D02*
Y103168D01*
G01X951932Y91164D02*
X952932Y92164D01*
G01X951932Y86414D02*
Y91164D01*
G01X952532Y85814D02*
X951932Y86414D01*
G01X952532Y73131D02*
Y85814D01*
G01X952032Y72631D02*
X952532Y73131D01*
G01X952032Y66799D02*
Y72631D01*
G01X952882Y65949D02*
X952032Y66799D01*
G01X952882Y54264D02*
Y65949D01*
G01X951932Y53314D02*
X952882Y54264D01*
G01X951932Y48614D02*
Y53314D01*
G01X952532Y48014D02*
X951932Y48614D01*
G01X952532Y35331D02*
Y48014D01*
G01X952032Y34831D02*
X952532Y35331D01*
G01X913779Y59379D02*
Y54957D01*
G01X915674Y61274D02*
X913779Y59379D01*
G01X915674Y66460D02*
Y61274D01*
G01X915063Y67071D02*
X915674Y66460D01*
G01X915063Y72463D02*
Y67071D01*
G01X915863Y73263D02*
X915063Y72463D01*
G01X915863Y85774D02*
Y73263D01*
G01X915174Y86463D02*
X915863Y85774D01*
G01X915174Y91285D02*
Y86463D01*
G01X915763Y91874D02*
X915174Y91285D01*
G01X915763Y105286D02*
Y91874D01*
G01X915558Y35667D02*
X917125Y34100D01*
G01X915558Y36868D02*
Y35667D01*
G01X914200Y38226D02*
X915558Y36868D01*
G01X914200Y39599D02*
Y38226D01*
G01X915400Y40799D02*
X914200Y39599D01*
G01X915400Y41925D02*
Y40799D01*
G01X914200Y43125D02*
X915400Y41925D01*
G01X914200Y44700D02*
Y43125D01*
G01X916000Y46500D02*
X914200Y44700D01*
G01X916000Y47558D02*
Y46500D01*
G01X912658Y50900D02*
X916000Y47558D01*
G01X912658Y53836D02*
Y50900D01*
G01X913779Y54957D02*
X912658Y53836D01*
G01X968674Y94417D02*
X971938Y97681D01*
G01X968674Y91574D02*
Y94417D01*
G01X969274Y90974D02*
X968674Y91574D01*
G01X969274Y88974D02*
Y90974D01*
G01X968674Y88374D02*
X969274Y88974D01*
G01X968674Y86174D02*
Y88374D01*
G01X969274Y85574D02*
X968674Y86174D01*
G01X969274Y83774D02*
Y85574D01*
G01X968950Y83450D02*
X969274Y83774D01*
G01X968950Y69635D02*
Y83450D01*
G01X968474Y69159D02*
X968950Y69635D01*
G01X968474Y67859D02*
Y69159D01*
G01X969056Y67277D02*
X968474Y67859D01*
G01X969056Y64957D02*
Y67277D01*
G01X968000Y63901D02*
X969056Y64957D01*
G01X968000Y58060D02*
Y63901D01*
G01X965600Y55660D02*
X968000Y58060D01*
G01X965600Y49840D02*
Y55660D01*
G01X965700Y49740D02*
X965600Y49840D01*
G01X965700Y34278D02*
Y49740D01*
G01X946132Y35531D02*
X945332Y34731D01*
G01X946132Y47914D02*
Y35531D01*
G01X945332Y48714D02*
X946132Y47914D01*
G01X945332Y53414D02*
Y48714D01*
G01X945732Y53814D02*
X945332Y53414D01*
G01X945732Y66499D02*
Y53814D01*
G01X945332Y66899D02*
X945732Y66499D01*
G01X945332Y72531D02*
Y66899D01*
G01X946132Y73331D02*
X945332Y72531D01*
G01X946132Y85714D02*
Y73331D01*
G01X945332Y86514D02*
X946132Y85714D01*
G01X945332Y91214D02*
Y86514D01*
G01X945874Y91756D02*
X945332Y91214D01*
G01X945874Y97347D02*
Y91756D01*
G01X962356Y48641D02*
X960629Y46914D01*
G01X962356Y55615D02*
Y48641D01*
G01X961440Y56531D02*
X962356Y55615D01*
G01X961440Y61020D02*
Y56531D01*
G01X962356Y61936D02*
X961440Y61020D01*
G01X962356Y66977D02*
Y61936D01*
G01X961974Y67359D02*
X962356Y66977D01*
G01X961974Y69359D02*
Y67359D01*
G01X962574Y69959D02*
X961974Y69359D01*
G01X962574Y72459D02*
Y69959D01*
G01X962253Y72780D02*
X962574Y72459D01*
G01X962253Y74753D02*
Y72780D01*
G01X962574Y75074D02*
X962253Y74753D01*
G01X962574Y85874D02*
Y75074D01*
G01X962074Y86374D02*
X962574Y85874D01*
G01X962074Y88274D02*
Y86374D01*
G01X962774Y88974D02*
X962074Y88274D01*
G01X962774Y91074D02*
Y88974D01*
G01X962043Y91805D02*
X962774Y91074D01*
G01X962043Y93444D02*
Y91805D01*
G01X967618Y99019D02*
X962043Y93444D01*
G01X959000Y37586D02*
X960629Y35957D01*
G01X959000Y49000D02*
Y37586D01*
G01X959600Y49600D02*
X959000Y49000D01*
G01X959600Y51610D02*
Y49600D01*
G01X958924Y52286D02*
X959600Y51610D01*
G01X958924Y66809D02*
Y52286D01*
G01X959674Y67559D02*
X958924Y66809D01*
G01X959674Y72051D02*
Y67559D01*
G01X959020Y72705D02*
X959674Y72051D01*
G01X959020Y74781D02*
Y72705D01*
G01X958674Y75127D02*
X959020Y74781D01*
G01X958674Y85474D02*
Y75127D01*
G01X959674Y86474D02*
X958674Y85474D01*
G01X959674Y88224D02*
Y86474D01*
G01X958674Y89224D02*
X959674Y88224D01*
G01X958674Y91274D02*
Y89224D01*
G01X959674Y92274D02*
X958674Y91274D01*
G01X959674Y93904D02*
Y92274D01*
G01X965629Y99859D02*
X959674Y93904D01*
G01X919263Y52052D02*
X917125Y49914D01*
G01X919263Y53344D02*
Y52052D01*
G01X918463Y54144D02*
X919263Y53344D01*
G01X918463Y66359D02*
Y54144D01*
G01X919074Y66970D02*
X918463Y66359D01*
G01X919074Y72526D02*
Y66970D01*
G01X918363Y73237D02*
X919074Y72526D01*
G01X918363Y85862D02*
Y73237D01*
G01X919063Y86562D02*
X918363Y85862D01*
G01X919063Y91286D02*
Y86562D01*
G01X918363Y91986D02*
X919063Y91286D01*
G01X918363Y106046D02*
Y91986D01*
G01X919126Y34900D02*
Y33500D01*
G01X918514Y35512D02*
X919126Y34900D01*
G01X918514Y48525D02*
Y35512D01*
G01X917125Y49914D02*
X918514Y48525D01*
G01X963976Y56385D02*
Y54857D01*
G01X965974Y58383D02*
X963976Y56385D01*
G01X965974Y64527D02*
Y58383D01*
G01X965609Y64892D02*
X965974Y64527D01*
G01X965609Y67094D02*
Y64892D01*
G01X965974Y67459D02*
X965609Y67094D01*
G01X965974Y69459D02*
Y67459D01*
G01X965374Y70059D02*
X965974Y69459D01*
G01X965374Y72359D02*
Y70059D01*
G01X965699Y72684D02*
X965374Y72359D01*
G01X965699Y75034D02*
Y72684D01*
G01X965374Y75359D02*
X965699Y75034D01*
G01X965374Y85674D02*
Y75359D01*
G01X965974Y86274D02*
X965374Y85674D01*
G01X965974Y88174D02*
Y86274D01*
G01X965274Y88874D02*
X965974Y88174D01*
G01X965274Y90974D02*
Y88874D01*
G01X965974Y91674D02*
X965274Y90974D01*
G01X965974Y94546D02*
Y91674D01*
G01X969705Y98277D02*
X965974Y94546D01*
G01X925032Y35399D02*
X925382Y35049D01*
G01X925032Y48314D02*
Y35399D01*
G01X925382Y48664D02*
X925032Y48314D01*
G01X925382Y53614D02*
Y48664D01*
G01X925132Y53864D02*
X925382Y53614D01*
G01X925132Y66399D02*
Y53864D01*
G01X925382Y66649D02*
X925132Y66399D01*
G01X925382Y72849D02*
Y66649D01*
G01X925032Y73199D02*
X925382Y72849D01*
G01X925032Y86114D02*
Y73199D01*
G01X925382Y86464D02*
X925032Y86114D01*
G01X925382Y91414D02*
Y86464D01*
G01X925032Y91764D02*
X925382Y91414D01*
G01X925032Y105332D02*
Y91764D01*
G01X970669Y58799D02*
Y54857D01*
G01X972400Y60530D02*
X970669Y58799D01*
G01X969560Y40223D02*
X968950Y39613D01*
G01X970483Y40223D02*
X969560D01*
G01X971093Y40833D02*
X970483Y40223D01*
G01X971093Y42733D02*
Y40833D01*
G01X970483Y43343D02*
X971093Y42733D01*
G01X969560Y43343D02*
X970483D01*
G01X968950Y43953D02*
X969560Y43343D01*
G01X968950Y53238D02*
Y43953D01*
G01X970569Y54857D02*
X968950Y53238D01*
G01X970669Y54857D02*
X970569D01*
G01X929232Y35533D02*
X927882Y34183D01*
G01X929232Y47564D02*
Y35533D01*
G01X927882Y48914D02*
X929232Y47564D01*
G01X927882Y53182D02*
Y48914D01*
G01X929232Y54532D02*
X927882Y53182D01*
G01X929232Y66067D02*
Y54532D01*
G01X927882Y67417D02*
X929232Y66067D01*
G01X927882Y72083D02*
Y67417D01*
G01X929232Y73433D02*
X927882Y72083D01*
G01X929232Y85364D02*
Y73433D01*
G01X927882Y86714D02*
X929232Y85364D01*
G01X927882Y90982D02*
Y86714D01*
G01X929232Y92332D02*
X927882Y90982D01*
G01X929232Y104816D02*
Y92332D01*
G01X948674Y91772D02*
Y103774D01*
G01X949432Y91014D02*
X948674Y91772D01*
G01X949432Y86514D02*
Y91014D01*
G01X948632Y85714D02*
X949432Y86514D01*
G01X948632Y73167D02*
Y85714D01*
G01X949532Y72267D02*
X948632Y73167D01*
G01X949532Y67299D02*
Y72267D01*
G01X948732Y66499D02*
X949532Y67299D01*
G01X948732Y53914D02*
Y66499D01*
G01X949432Y53214D02*
X948732Y53914D01*
G01X949432Y48714D02*
Y53214D01*
G01X948632Y47914D02*
X949432Y48714D01*
G01X948632Y35267D02*
Y47914D01*
G01X949532Y34367D02*
X948632Y35267D01*
G01X955000Y92306D02*
Y102900D01*
G01X955832Y91474D02*
X955000Y92306D01*
G01X955832Y86414D02*
Y91474D01*
G01X955332Y85914D02*
X955832Y86414D01*
G01X955332Y73067D02*
Y85914D01*
G01X955882Y72517D02*
X955332Y73067D01*
G01X955882Y66999D02*
Y72517D01*
G01X955382Y66499D02*
X955882Y66999D01*
G01X955382Y53914D02*
Y66499D01*
G01X955843Y53453D02*
X955382Y53914D01*
G01X955843Y48575D02*
Y53453D01*
G01X955332Y48064D02*
X955843Y48575D01*
G01X955332Y35369D02*
Y48064D01*
G01X955932Y34769D02*
X955332Y35369D01*
G01X922400Y142800D02*
Y168434D01*
G01X921600Y99544D02*
X922432Y98712D01*
G01X921600Y101912D02*
Y99544D01*
G01X922432Y102744D02*
X921600Y101912D01*
G01X922432Y105316D02*
Y102744D01*
G01X921474Y106274D02*
X922432Y105316D01*
G01X921474Y110716D02*
Y106274D01*
G01X922432Y111674D02*
X921474Y110716D01*
G01X922432Y114132D02*
Y111674D01*
G01X923000Y114700D02*
X922432Y114132D01*
G01X923000Y121849D02*
Y114700D01*
G01X931150Y129999D02*
X923000Y121849D01*
G01X931150Y143149D02*
Y129999D01*
G01X931800Y143799D02*
X931150Y143149D01*
G01X931800Y154171D02*
Y143799D01*
G01X932360Y154731D02*
X931800Y154171D01*
G01X933740Y154731D02*
X932360D01*
G01X934300Y155291D02*
X933740Y154731D01*
G01X934300Y156731D02*
Y155291D01*
G01X938500Y125600D02*
X931732Y118832D01*
G01X938500Y136649D02*
Y125600D01*
G01X944350Y142499D02*
X938500Y136649D01*
G01X944350Y172987D02*
Y142499D01*
G01X910432Y107284D02*
X911863Y105853D01*
G01X962245Y153190D02*
Y169072D01*
G01X962805Y152630D02*
X962245Y153190D01*
G01X963540Y152630D02*
X962805D01*
G01X964100Y152070D02*
X963540Y152630D01*
G01X964100Y150630D02*
Y152070D01*
G01X963540Y150070D02*
X964100Y150630D01*
G01X962805Y150070D02*
X963540D01*
G01X962245Y149510D02*
X962805Y150070D01*
G01X962245Y148070D02*
Y149510D01*
G01X962805Y147510D02*
X962245Y148070D01*
G01X963540Y147510D02*
X962805D01*
G01X964100Y146950D02*
X963540Y147510D01*
G01X964100Y145510D02*
Y146950D01*
G01X963540Y144950D02*
X964100Y145510D01*
G01X962805Y144950D02*
X963540D01*
G01X962245Y144390D02*
X962805Y144950D01*
G01X962245Y142950D02*
Y144390D01*
G01X962805Y142390D02*
X962245Y142950D01*
G01X963540Y142390D02*
X962805D01*
G01X964100Y141830D02*
X963540Y142390D01*
G01X964100Y140390D02*
Y141830D01*
G01X963540Y139830D02*
X964100Y140390D01*
G01X962805Y139830D02*
X963540D01*
G01X962245Y139270D02*
X962805Y139830D01*
G01X962245Y137830D02*
Y139270D01*
G01X962805Y137270D02*
X962245Y137830D01*
G01X963540Y137270D02*
X962805D01*
G01X964100Y136710D02*
X963540Y137270D01*
G01X964100Y135270D02*
Y136710D01*
G01X963540Y134710D02*
X964100Y135270D01*
G01X962805Y134710D02*
X963540D01*
G01X962245Y134150D02*
X962805Y134710D01*
G01X962245Y132710D02*
Y134150D01*
G01X962805Y132150D02*
X962245Y132710D01*
G01X963540Y132150D02*
X962805D01*
G01X964100Y131590D02*
X963540Y132150D01*
G01X964100Y130150D02*
Y131590D01*
G01X963540Y129590D02*
X964100Y130150D01*
G01X962805Y129590D02*
X963540D01*
G01X962245Y129030D02*
X962805Y129590D01*
G01X962245Y125845D02*
Y129030D01*
G01X952500Y116100D02*
X962245Y125845D01*
G01X952500Y109000D02*
Y116100D01*
G01X951974Y108474D02*
X952500Y109000D01*
G01X951974Y104126D02*
Y108474D01*
G01X952932Y103168D02*
X951974Y104126D01*
G01X913779Y107270D02*
X915763Y105286D01*
G01X913779Y112327D02*
Y107270D01*
G01X915750Y150600D02*
Y168856D01*
G01X913349Y148199D02*
X915750Y150600D01*
G01X913349Y147337D02*
Y148199D01*
G01X914712Y145974D02*
X913349Y147337D01*
G01X914712Y145112D02*
Y145974D01*
G01X913728Y144128D02*
X914712Y145112D01*
G01X912866Y144128D02*
X913728D01*
G01X911503Y145491D02*
X912866Y144128D01*
G01X910641Y145491D02*
X911503D01*
G01X945000Y98221D02*
X945874Y97347D01*
G01X945000Y100547D02*
Y98221D01*
G01X945874Y101421D02*
X945000Y100547D01*
G01X945874Y103526D02*
Y101421D01*
G01X945166Y104234D02*
X945874Y103526D01*
G01X945166Y108366D02*
Y104234D01*
G01X946300Y109500D02*
X945166Y108366D01*
G01X946300Y117416D02*
Y109500D01*
G01X954950Y126066D02*
X946300Y117416D01*
G01X954950Y136896D02*
Y126066D01*
G01X955560Y137506D02*
X954950Y136896D01*
G01X956881Y137506D02*
X955560D01*
G01X957491Y138116D02*
X956881Y137506D01*
G01X957491Y139336D02*
Y138116D01*
G01X956881Y139946D02*
X957491Y139336D01*
G01X955560Y139946D02*
X956881D01*
G01X954950Y140556D02*
X955560Y139946D01*
G01X954950Y141776D02*
Y140556D01*
G01X955560Y142386D02*
X954950Y141776D01*
G01X956881Y142386D02*
X955560D01*
G01X957491Y142996D02*
X956881Y142386D01*
G01X957491Y144216D02*
Y142996D01*
G01X956881Y144826D02*
X957491Y144216D01*
G01X955560Y144826D02*
X956881D01*
G01X954950Y145436D02*
X955560Y144826D01*
G01X954950Y146656D02*
Y145436D01*
G01X955560Y147266D02*
X954950Y146656D01*
G01X956881Y147266D02*
X955560D01*
G01X957491Y147876D02*
X956881Y147266D01*
G01X957491Y149096D02*
Y147876D01*
G01X956881Y149706D02*
X957491Y149096D01*
G01X955560Y149706D02*
X956881D01*
G01X954950Y150316D02*
X955560Y149706D01*
G01X954950Y169159D02*
Y150316D01*
G01X967618Y108578D02*
Y99019D01*
G01X991268Y132228D02*
X967618Y108578D01*
G01X965629Y109636D02*
Y99859D01*
G01X989709Y133716D02*
X965629Y109636D01*
G01X917125Y107284D02*
X918363Y106046D01*
G01X969705Y107302D02*
Y98277D01*
G01X993094Y130691D02*
X969705Y107302D01*
G01X919000Y142700D02*
Y168570D01*
G01X912237Y135937D02*
X919000Y142700D01*
G01X911375Y135937D02*
X912237D01*
G01X910387Y136925D02*
X911375Y135937D01*
G01X925374Y105674D02*
X925032Y105332D01*
G01X925374Y110732D02*
Y105674D01*
G01X925032Y111074D02*
X925374Y110732D01*
G01X925032Y113200D02*
Y111074D01*
G01X925500Y113668D02*
X925032Y113200D01*
G01X925500Y119901D02*
Y113668D01*
G01X933900Y128301D02*
X925500Y119901D01*
G01X933900Y141400D02*
Y128301D01*
G01X936700Y144200D02*
X933900Y141400D01*
G01X936700Y165974D02*
Y144200D01*
G01X927874Y106174D02*
X929232Y104816D01*
G01X927874Y110316D02*
Y106174D01*
G01X929200Y111642D02*
X927874Y110316D01*
G01X929200Y119801D02*
Y111642D01*
G01X936100Y126701D02*
X929200Y119801D01*
G01X936100Y138749D02*
Y126701D01*
G01X941850Y144499D02*
X936100Y138749D01*
G01X941850Y146425D02*
Y144499D01*
G01X941240Y147035D02*
X941850Y146425D01*
G01X939460Y147035D02*
X941240D01*
G01X938850Y147645D02*
X939460Y147035D01*
G01X938850Y149035D02*
Y147645D01*
G01X939460Y149645D02*
X938850Y149035D01*
G01X941240Y149645D02*
X939460D01*
G01X941850Y150255D02*
X941240Y149645D01*
G01X941850Y151645D02*
Y150255D01*
G01X941240Y152255D02*
X941850Y151645D01*
G01X939460Y152255D02*
X941240D01*
G01X938850Y152865D02*
X939460Y152255D01*
G01X938850Y154255D02*
Y152865D01*
G01X939460Y154865D02*
X938850Y154255D01*
G01X941240Y154865D02*
X939460D01*
G01X941850Y155475D02*
X941240Y154865D01*
G01X941850Y156865D02*
Y155475D01*
G01X960050Y135950D02*
Y170723D01*
G01X957300Y133200D02*
X960050Y135950D01*
G01X957300Y125000D02*
Y133200D01*
G01X948732Y116432D02*
X957300Y125000D01*
G01X948732Y108768D02*
Y116432D01*
G01X949474Y108026D02*
X948732Y108768D01*
G01X949474Y104574D02*
Y108026D01*
G01X948674Y103774D02*
X949474Y104574D01*
G01X966200Y122850D02*
Y169414D01*
G01X955974Y112624D02*
X966200Y122850D01*
G01X955974Y103874D02*
Y112624D01*
G01X955000Y102900D02*
X955974Y103874D01*
G01X912152Y186099D02*
Y183227D01*
G01X934727Y180761D02*
Y182551D01*
G01X922400Y168434D02*
X934727Y180761D01*
G01X933740Y157291D02*
X934300Y156731D01*
G01X932360Y157291D02*
X933740D01*
G01X931800Y157851D02*
X932360Y157291D01*
G01X931800Y159291D02*
Y157851D01*
G01X932360Y159851D02*
X931800Y159291D01*
G01X933740Y159851D02*
X932360D01*
G01X934300Y160411D02*
X933740Y159851D01*
G01X934300Y161851D02*
Y160411D01*
G01X933740Y162411D02*
X934300Y161851D01*
G01X932360Y162411D02*
X933740D01*
G01X931800Y162971D02*
X932360Y162411D01*
G01X931800Y171750D02*
Y162971D01*
G01X953150Y193100D02*
X931800Y171750D01*
G01X953150Y197247D02*
Y193100D01*
G01X953056Y197341D02*
X953150Y197247D01*
G01X960556Y189193D02*
X944350Y172987D01*
G01X960556Y197341D02*
Y189193D01*
G01X915300Y209600D02*
Y209037D01*
G01X920700Y215000D02*
X915300Y209600D01*
G01X925005Y215000D02*
X920700D01*
G01X971338Y177438D02*
X977756Y183856D01*
G01X970611Y177438D02*
X971338D01*
G01X962245Y169072D02*
X970611Y177438D01*
G01X929050Y183953D02*
X931242Y186145D01*
G01X929050Y182156D02*
Y183953D01*
G01X915750Y168856D02*
X929050Y182156D01*
G01X967390Y181599D02*
X954950Y169159D01*
G01X969399Y181599D02*
X967390D01*
G01X972700Y184900D02*
X969399Y181599D01*
G01X922216Y217611D02*
X920310D01*
G01X929400Y215365D02*
X929407Y215372D01*
G01X929400Y214200D02*
Y215365D01*
G01X928000Y212800D02*
X929400Y214200D01*
G01X926700Y212800D02*
X928000D01*
G01X924900Y211000D02*
X926700Y212800D01*
G01X923300Y211000D02*
X924900D01*
G01X921300Y209000D02*
X923300Y211000D01*
G01X919800Y209000D02*
X921300D01*
G01X913300Y169942D02*
Y156548D01*
G01X926250Y182892D02*
X913300Y169942D01*
G01X926250Y184689D02*
Y182892D01*
G01X929519Y187958D02*
X926250Y184689D01*
G01X931550Y182917D02*
X933025Y184392D01*
G01X931550Y181120D02*
Y182917D01*
G01X919000Y168570D02*
X931550Y181120D01*
G01X936140Y166534D02*
X936700Y165974D01*
G01X934460Y166534D02*
X936140D01*
G01X933900Y167094D02*
X934460Y166534D01*
G01X933900Y168534D02*
Y167094D01*
G01X934460Y169094D02*
X933900Y168534D01*
G01X936140Y169094D02*
X934460D01*
G01X936700Y169654D02*
X936140Y169094D01*
G01X936700Y173000D02*
Y169654D01*
G01X955556Y191856D02*
X936700Y173000D01*
G01X955556Y197341D02*
Y191856D01*
G01X940800Y157915D02*
X941850Y156865D01*
G01X940800Y159645D02*
Y157915D01*
G01X941850Y160695D02*
X940800Y159645D01*
G01X941850Y174800D02*
Y160695D01*
G01X958056Y191006D02*
X941850Y174800D01*
G01X958056Y197341D02*
Y191006D01*
G01X970204Y179404D02*
X975475Y184675D01*
G01X968731Y179404D02*
X970204D01*
G01X960050Y170723D02*
X968731Y179404D01*
G01X966200Y169414D02*
X971847Y175061D01*
G01X912972Y232275D02*
X912175D01*
G01X914572Y233875D02*
X912972Y232275D01*
G01X915019Y271650D02*
X915898Y272529D01*
G01X914647Y275400D02*
X915786Y274261D01*
G01X911690Y234543D02*
X913532Y236385D01*
G01X910907Y234543D02*
X911690D01*
G01X919121Y220111D02*
X922216D01*
G01X956633Y400312D02*
Y410367D01*
G01X910900Y386318D02*
Y389300D01*
G01X914566Y382652D02*
X910900Y386318D01*
G01X954133Y400162D02*
Y409167D01*
G01X961933Y400312D02*
Y412368D01*
G01X959433Y400464D02*
Y411195D01*
G01X956904Y442516D02*
Y477096D01*
G01X980512Y418908D02*
X956904Y442516D01*
G01X925800Y441200D02*
Y469239D01*
G01X956633Y410367D02*
X925800Y441200D01*
G01X913180Y457933D02*
Y465787D01*
G01X913790Y457323D02*
X913180Y457933D01*
G01X915180Y457323D02*
X913790D01*
G01X915790Y457933D02*
X915180Y457323D01*
G01X915790Y462679D02*
Y457933D01*
G01X916400Y463289D02*
X915790Y462679D01*
G01X917790Y463289D02*
X916400D01*
G01X918400Y462679D02*
X917790Y463289D01*
G01X918400Y436537D02*
Y462679D01*
G01X944781Y410156D02*
X918400Y436537D01*
G01X944781Y407266D02*
Y410156D01*
G01X923200Y440100D02*
Y465816D01*
G01X954133Y409167D02*
X923200Y440100D01*
G01X930800Y444577D02*
Y486800D01*
G01X931717Y443660D02*
X930800Y444577D01*
G01X933317Y443660D02*
X931717D01*
G01X934000Y444343D02*
X933317Y443660D01*
G01X934000Y449858D02*
Y444343D01*
G01X934682Y450540D02*
X934000Y449858D01*
G01X936282Y450540D02*
X934682D01*
G01X937200Y449622D02*
X936282Y450540D01*
G01X937200Y437101D02*
Y449622D01*
G01X961933Y412368D02*
X937200Y437101D01*
G01X913397Y415080D02*
Y416404D01*
G01X912787Y414470D02*
X913397Y415080D01*
G01X911382Y414470D02*
X912787D01*
G01X910772Y413860D02*
X911382Y414470D01*
G01X910772Y412470D02*
Y413860D01*
G01X911382Y411860D02*
X910772Y412470D01*
G01X912681Y411860D02*
X911382D01*
G01X913291Y411250D02*
X912681Y411860D01*
G01X913291Y410013D02*
Y411250D01*
G01X918356Y404948D02*
X913291Y410013D01*
G01X913400Y434465D02*
Y452043D01*
G01X932561Y415304D02*
X913400Y434465D01*
G01X932561Y409796D02*
Y415304D01*
G01X947552Y441260D02*
Y465226D01*
G01X972712Y416100D02*
X947552Y441260D01*
G01X910852Y457509D02*
Y464825D01*
G01X915900Y452461D02*
X910852Y457509D01*
G01X915900Y435501D02*
Y452461D01*
G01X940800Y410601D02*
X915900Y435501D01*
G01X940800Y407897D02*
Y410601D01*
G01X943315Y405382D02*
X940800Y407897D01*
G01X928300Y442328D02*
Y487900D01*
G01X929905Y440723D02*
X928300Y442328D01*
G01X931037Y440723D02*
X929905D01*
G01X931834Y441520D02*
X931037Y440723D01*
G01X932860Y441520D02*
X931834D01*
G01X933991Y440389D02*
X932860Y441520D01*
G01X933991Y439151D02*
Y440389D01*
G01X933300Y438460D02*
X933991Y439151D01*
G01X933300Y437328D02*
Y438460D01*
G01X959433Y411195D02*
X933300Y437328D01*
G01X949902Y462986D02*
Y464966D01*
G01X950459Y462429D02*
X949902Y462986D01*
G01X951614Y462429D02*
X950459D01*
G01X952224Y461819D02*
X951614Y462429D01*
G01X952224Y459839D02*
Y461819D01*
G01X951614Y459229D02*
X952224Y459839D01*
G01X950406Y459229D02*
X951614D01*
G01X949796Y458619D02*
X950406Y459229D01*
G01X949796Y456639D02*
Y458619D01*
G01X950406Y456029D02*
X949796Y456639D01*
G01X951773Y456029D02*
X950406D01*
G01X952383Y455419D02*
X951773Y456029D01*
G01X952383Y453439D02*
Y455419D01*
G01X951773Y452829D02*
X952383Y453439D01*
G01X950935Y452829D02*
X951773D01*
G01X950325Y452219D02*
X950935Y452829D01*
G01X950325Y450239D02*
Y452219D01*
G01X950935Y449629D02*
X950325Y450239D01*
G01X951773Y449629D02*
X950935D01*
G01X952383Y449019D02*
X951773Y449629D01*
G01X952383Y447039D02*
Y449019D01*
G01X951773Y446429D02*
X952383Y447039D01*
G01X950910Y446429D02*
X951773D01*
G01X949992Y445511D02*
X950910Y446429D01*
G01X949992Y442356D02*
Y445511D01*
G01X975212Y417136D02*
X949992Y442356D01*
G01X910900Y433376D02*
Y451520D01*
G01X929800Y414476D02*
X910900Y433376D01*
G01X929800Y409007D02*
Y414476D01*
G01X930606Y408201D02*
X929800Y409007D01*
G01X954372Y441512D02*
Y469622D01*
G01X978216Y417668D02*
X954372Y441512D01*
G01X961450Y517750D02*
Y527050D01*
G01X962600Y516600D02*
X961450Y517750D01*
G01X962600Y514200D02*
Y516600D01*
G01X962000Y513600D02*
X962600Y514200D01*
G01X962000Y512000D02*
Y513600D01*
G01X963100Y510900D02*
X962000Y512000D01*
G01X963100Y498800D02*
Y510900D01*
G01X988354Y473546D02*
X963100Y498800D01*
G01X955900Y520300D02*
Y535800D01*
G01X955382Y519782D02*
X955900Y520300D01*
G01X955382Y517357D02*
Y519782D01*
G01X955848Y516891D02*
X955382Y517357D01*
G01X955848Y512173D02*
Y516891D01*
G01X955332Y511657D02*
X955848Y512173D01*
G01X955332Y507907D02*
Y511657D01*
G01X954532Y507107D02*
X955332Y507907D01*
G01X953300Y507107D02*
X954532D01*
G01X952500Y506307D02*
X953300Y507107D01*
G01X952500Y504707D02*
Y506307D01*
G01X953300Y503907D02*
X952500Y504707D01*
G01X954532Y503907D02*
X953300D01*
G01X955332Y503107D02*
X954532Y503907D01*
G01X955332Y500868D02*
Y503107D01*
G01X956800Y499400D02*
X955332Y500868D01*
G01X956800Y493120D02*
Y499400D01*
G01X955332Y491652D02*
X956800Y493120D01*
G01X955332Y490580D02*
Y491652D01*
G01X955942Y489970D02*
X955332Y490580D01*
G01X959042Y489970D02*
X955942D01*
G01X959652Y489360D02*
X959042Y489970D01*
G01X959652Y487380D02*
Y489360D01*
G01X959042Y486770D02*
X959652Y487380D01*
G01X955942Y486770D02*
X959042D01*
G01X955332Y486160D02*
X955942Y486770D01*
G01X955332Y482737D02*
Y486160D01*
G01X954451Y481856D02*
X955332Y482737D01*
G01X951975Y481856D02*
X954451D01*
G01X951017Y480898D02*
X951975Y481856D01*
G01X951017Y478758D02*
Y480898D01*
G01X951835Y477940D02*
X951017Y478758D01*
G01X956060Y477940D02*
X951835D01*
G01X956904Y477096D02*
X956060Y477940D01*
G01X925500Y519468D02*
Y527600D01*
G01X925132Y519100D02*
X925500Y519468D01*
G01X925132Y517457D02*
Y519100D01*
G01X925382Y517207D02*
X925132Y517457D01*
G01X925382Y511747D02*
Y517207D01*
G01X925174Y511539D02*
X925382Y511747D01*
G01X925174Y506426D02*
Y511539D01*
G01X925400Y506200D02*
X925174Y506426D01*
G01X925400Y495200D02*
Y506200D01*
G01X926100Y494500D02*
X925400Y495200D01*
G01X926100Y484744D02*
Y494500D01*
G01X925488Y484132D02*
X926100Y484744D01*
G01X921843Y484132D02*
X925488D01*
G01X920990Y483279D02*
X921843Y484132D01*
G01X920990Y481679D02*
Y483279D01*
G01X921737Y480932D02*
X920990Y481679D01*
G01X925000Y480932D02*
X921737D01*
G01X925800Y480132D02*
X925000Y480932D01*
G01X925800Y473659D02*
Y480132D01*
G01X925190Y473049D02*
X925800Y473659D01*
G01X922521Y473049D02*
X925190D01*
G01X921911Y472439D02*
X922521Y473049D01*
G01X921911Y470459D02*
Y472439D01*
G01X922521Y469849D02*
X921911Y470459D01*
G01X925190Y469849D02*
X922521D01*
G01X925800Y469239D02*
X925190Y469849D01*
G01X915500Y519721D02*
Y527800D01*
G01X916000Y519221D02*
X915500Y519721D01*
G01X916000Y517836D02*
Y519221D01*
G01X915221Y517057D02*
X916000Y517836D01*
G01X915221Y511657D02*
Y517057D01*
G01X915721Y511157D02*
X915221Y511657D01*
G01X915721Y500429D02*
Y511157D01*
G01X913779Y498487D02*
X915721Y500429D01*
G01X922432Y517405D02*
Y529468D01*
G01X921532Y516505D02*
X922432Y517405D01*
G01X921532Y511797D02*
Y516505D01*
G01X922274Y511055D02*
X921532Y511797D01*
G01X922274Y502726D02*
Y511055D01*
G01X922400Y502600D02*
X922274Y502726D01*
G01X922400Y495200D02*
Y502600D01*
G01X921644Y494444D02*
X922400Y495200D01*
G01X921644Y488443D02*
Y494444D01*
G01X919100Y485899D02*
X921644Y488443D01*
G01X919100Y478822D02*
Y485899D01*
G01X919900Y478022D02*
X919100Y478822D01*
G01X920676Y478022D02*
X919900D01*
G01X921476Y477222D02*
X920676Y478022D01*
G01X921476Y475622D02*
Y477222D01*
G01X920676Y474822D02*
X921476Y475622D01*
G01X919900Y474822D02*
X920676D01*
G01X919100Y474022D02*
X919900Y474822D01*
G01X919100Y469916D02*
Y474022D01*
G01X923200Y465816D02*
X919100Y469916D01*
G01X932200Y519900D02*
Y527900D01*
G01X931732Y519432D02*
X932200Y519900D01*
G01X931732Y487732D02*
Y519432D01*
G01X930800Y486800D02*
X931732Y487732D01*
G01X965800Y516900D02*
Y527700D01*
G01X965400Y516500D02*
X965800Y516900D01*
G01X965400Y514300D02*
Y516500D01*
G01X965900Y513800D02*
X965400Y514300D01*
G01X965900Y511800D02*
Y513800D01*
G01X965400Y511300D02*
X965900Y511800D01*
G01X965400Y499500D02*
Y511300D01*
G01X990354Y474546D02*
X965400Y499500D01*
G01X945732Y517357D02*
Y529842D01*
G01X945332Y516957D02*
X945732Y517357D01*
G01X945332Y512057D02*
Y516957D01*
G01X945776Y511613D02*
X945332Y512057D01*
G01X945776Y501376D02*
Y511613D01*
G01X945600Y501200D02*
X945776Y501376D01*
G01X945600Y494400D02*
Y501200D01*
G01X946132Y493868D02*
X945600Y494400D01*
G01X946132Y487432D02*
Y493868D01*
G01X941100Y482400D02*
X946132Y487432D01*
G01X941100Y471678D02*
Y482400D01*
G01X947552Y465226D02*
X941100Y471678D01*
G01X918800Y519429D02*
Y527800D01*
G01X918571Y519200D02*
X918800Y519429D01*
G01X918571Y517357D02*
Y519200D01*
G01X919121Y516807D02*
X918571Y517357D01*
G01X919121Y512257D02*
Y516807D01*
G01X918521Y511657D02*
X919121Y512257D01*
G01X918521Y495248D02*
Y511657D01*
G01X917192Y493919D02*
X918521Y495248D01*
G01X928963Y517388D02*
Y529513D01*
G01X927882Y516307D02*
X928963Y517388D01*
G01X927882Y512057D02*
Y516307D01*
G01X929016Y510923D02*
X927882Y512057D01*
G01X929016Y494916D02*
Y510923D01*
G01X927974Y493874D02*
X929016Y494916D01*
G01X927974Y488226D02*
Y493874D01*
G01X928300Y487900D02*
X927974Y488226D01*
G01X948732Y517357D02*
Y529842D01*
G01X949532Y516557D02*
X948732Y517357D01*
G01X949532Y512157D02*
Y516557D01*
G01X948632Y511257D02*
X949532Y512157D01*
G01X948632Y499368D02*
Y511257D01*
G01X949900Y498100D02*
X948632Y499368D01*
G01X949900Y495000D02*
Y498100D01*
G01X948632Y493732D02*
X949900Y495000D01*
G01X948632Y486592D02*
Y493732D01*
G01X943800Y481760D02*
X948632Y486592D01*
G01X943800Y472500D02*
Y481760D01*
G01X947471Y468829D02*
X943800Y472500D01*
G01X951773Y468829D02*
X947471D01*
G01X952383Y468219D02*
X951773Y468829D01*
G01X952383Y466239D02*
Y468219D01*
G01X951773Y465629D02*
X952383Y466239D01*
G01X950565Y465629D02*
X951773D01*
G01X949902Y464966D02*
X950565Y465629D01*
G01X912700Y525800D02*
Y527400D01*
G01X911800Y524900D02*
X912700Y525800D01*
G01X911800Y523300D02*
Y524900D01*
G01X912700Y522400D02*
X911800Y523300D01*
G01X912700Y520379D02*
Y522400D01*
G01X911621Y519300D02*
X912700Y520379D01*
G01X911621Y517657D02*
Y519300D01*
G01X912721Y516557D02*
X911621Y517657D01*
G01X912721Y512157D02*
Y516557D01*
G01X911821Y511257D02*
X912721Y512157D01*
G01X911821Y502420D02*
Y511257D01*
G01X968700Y517000D02*
Y527500D01*
G01X969200Y516500D02*
X968700Y517000D01*
G01X969200Y514200D02*
Y516500D01*
G01X968800Y513800D02*
X969200Y514200D01*
G01X968800Y511800D02*
Y513800D01*
G01X969500Y511100D02*
X968800Y511800D01*
G01X969500Y498300D02*
Y511100D01*
G01X992354Y475446D02*
X969500Y498300D01*
G01X952300Y519782D02*
Y528000D01*
G01X952882Y519200D02*
X952300Y519782D01*
G01X952882Y517823D02*
Y519200D01*
G01X951891Y516832D02*
X952882Y517823D01*
G01X951891Y511798D02*
Y516832D01*
G01X952532Y511157D02*
X951891Y511798D01*
G01X952532Y509432D02*
Y511157D01*
G01X950600Y507500D02*
X952532Y509432D01*
G01X950600Y501800D02*
Y507500D01*
G01X952300Y500100D02*
X950600Y501800D01*
G01X952300Y494000D02*
Y500100D01*
G01X952800Y493500D02*
X952300Y494000D01*
G01X952800Y487153D02*
Y493500D01*
G01X948242Y482595D02*
X952800Y487153D01*
G01X948242Y475752D02*
Y482595D01*
G01X954372Y469622D02*
X948242Y475752D01*
G01X960629Y545372D02*
Y547914D01*
G01X962242Y543759D02*
X960629Y545372D01*
G01X962242Y535458D02*
Y543759D01*
G01X962347Y535353D02*
X962242Y535458D01*
G01X962347Y527947D02*
Y535353D01*
G01X961450Y527050D02*
X962347Y527947D01*
G01X954532Y588118D02*
X953936Y588714D01*
G01X954532Y574868D02*
Y588118D01*
G01X955874Y573526D02*
X954532Y574868D01*
G01X955874Y557873D02*
Y573526D01*
G01X955382Y557381D02*
X955874Y557873D01*
G01X955382Y555157D02*
Y557381D01*
G01X955932Y554607D02*
X955382Y555157D01*
G01X955932Y550057D02*
Y554607D01*
G01X955332Y549457D02*
X955932Y550057D01*
G01X955332Y547068D02*
Y549457D01*
G01X955900Y546500D02*
X955332Y547068D01*
G01X955900Y538368D02*
Y546500D01*
G01X955332Y537800D02*
X955900Y538368D01*
G01X955332Y536368D02*
Y537800D01*
G01X955900Y535800D02*
X955332Y536368D01*
G01X925032Y587200D02*
X923518Y588714D01*
G01X925032Y584868D02*
Y587200D01*
G01X925500Y584400D02*
X925032Y584868D01*
G01X925500Y576200D02*
Y584400D01*
G01X925032Y575732D02*
X925500Y576200D01*
G01X925032Y573256D02*
Y575732D01*
G01X925632Y572656D02*
X925032Y573256D01*
G01X925632Y568497D02*
Y572656D01*
G01X925132Y567997D02*
X925632Y568497D01*
G01X925132Y566068D02*
Y567997D01*
G01X925500Y565700D02*
X925132Y566068D01*
G01X925500Y557268D02*
Y565700D01*
G01X925132Y556900D02*
X925500Y557268D01*
G01X925132Y555257D02*
Y556900D01*
G01X925382Y555007D02*
X925132Y555257D01*
G01X925382Y549235D02*
Y555007D01*
G01X925032Y548885D02*
X925382Y549235D01*
G01X925032Y547068D02*
Y548885D01*
G01X925500Y546600D02*
X925032Y547068D01*
G01X925500Y537968D02*
Y546600D01*
G01X925032Y537500D02*
X925500Y537968D01*
G01X925032Y535542D02*
Y537500D01*
G01X925382Y535192D02*
X925032Y535542D01*
G01X925382Y530242D02*
Y535192D01*
G01X925132Y529992D02*
X925382Y530242D01*
G01X925132Y527968D02*
Y529992D01*
G01X925500Y527600D02*
X925132Y527968D01*
G01X912074Y567849D02*
X917125Y572900D01*
G01X912074Y557662D02*
Y567849D01*
G01X913779Y555957D02*
X912074Y557662D01*
G01X912421Y554599D02*
X913779Y555957D01*
G01X912421Y552107D02*
Y554599D01*
G01X915821Y548707D02*
X912421Y552107D01*
G01X915821Y547121D02*
Y548707D01*
G01X915500Y546800D02*
X915821Y547121D01*
G01X915500Y537921D02*
Y546800D01*
G01X915821Y537600D02*
X915500Y537921D01*
G01X915821Y536242D02*
Y537600D01*
G01X914921Y535342D02*
X915821Y536242D01*
G01X914921Y530597D02*
Y535342D01*
G01X916021Y529497D02*
X914921Y530597D01*
G01X916021Y528321D02*
Y529497D01*
G01X915500Y527800D02*
X916021Y528321D01*
G01X963976Y564640D02*
Y566814D01*
G01X969059Y559557D02*
X963976Y564640D01*
G01X969059Y553061D02*
Y559557D01*
G01X968600Y552602D02*
X969059Y553061D01*
G01X968600Y549900D02*
Y552602D01*
G01X968957Y549543D02*
X968600Y549900D01*
G01X968957Y546201D02*
Y549543D01*
G01X971700Y543458D02*
X968957Y546201D01*
G01X971700Y538800D02*
Y543458D01*
G01X972395Y538105D02*
X971700Y538800D01*
G01X922382Y586457D02*
X920472Y588367D01*
G01X922382Y573942D02*
Y586457D01*
G01X921384Y572944D02*
X922382Y573942D01*
G01X921384Y568217D02*
Y572944D01*
G01X922432Y567169D02*
X921384Y568217D01*
G01X922432Y555209D02*
Y567169D01*
G01X921532Y554309D02*
X922432Y555209D01*
G01X921532Y549557D02*
Y554309D01*
G01X922532Y548557D02*
X921532Y549557D01*
G01X922532Y536242D02*
Y548557D01*
G01X921532Y535242D02*
X922532Y536242D01*
G01X921532Y530368D02*
Y535242D01*
G01X922432Y529468D02*
X921532Y530368D01*
G01X931732Y586443D02*
X929811Y588364D01*
G01X931732Y584268D02*
Y586443D01*
G01X932200Y583800D02*
X931732Y584268D01*
G01X932200Y576068D02*
Y583800D01*
G01X931732Y575600D02*
X932200Y576068D01*
G01X931732Y563068D02*
Y575600D01*
G01X932200Y562600D02*
X931732Y563068D01*
G01X932200Y556968D02*
Y562600D01*
G01X931732Y556500D02*
X932200Y556968D01*
G01X931732Y546768D02*
Y556500D01*
G01X932200Y546300D02*
X931732Y546768D01*
G01X932200Y538168D02*
Y546300D01*
G01X931732Y537700D02*
X932200Y538168D01*
G01X931732Y528368D02*
Y537700D01*
G01X932200Y527900D02*
X931732Y528368D01*
G01X970669Y555857D02*
Y566814D01*
G01X972601Y553925D02*
X970669Y555857D01*
G01X960629Y569571D02*
Y574757D01*
G01X962360Y567840D02*
X960629Y569571D01*
G01X962360Y551860D02*
Y567840D01*
G01X962257Y551757D02*
X962360Y551860D01*
G01X962257Y546843D02*
Y551757D01*
G01X965695Y543405D02*
X962257Y546843D01*
G01X965695Y535895D02*
Y543405D01*
G01X965607Y535807D02*
X965695Y535895D01*
G01X965607Y527893D02*
Y535807D01*
G01X965800Y527700D02*
X965607Y527893D01*
G01X946132Y586357D02*
X943400Y589089D01*
G01X946132Y584932D02*
Y586357D01*
G01X945600Y584400D02*
X946132Y584932D01*
G01X945600Y575700D02*
Y584400D01*
G01X946029Y575271D02*
X945600Y575700D01*
G01X946029Y574139D02*
Y575271D01*
G01X944859Y572969D02*
X946029Y574139D01*
G01X944859Y568470D02*
Y572969D01*
G01X945932Y567397D02*
X944859Y568470D01*
G01X945932Y565932D02*
Y567397D01*
G01X945600Y565600D02*
X945932Y565932D01*
G01X945600Y557532D02*
Y565600D01*
G01X945932Y557200D02*
X945600Y557532D01*
G01X945932Y555357D02*
Y557200D01*
G01X945332Y554757D02*
X945932Y555357D01*
G01X945332Y549857D02*
Y554757D01*
G01X945775Y549414D02*
X945332Y549857D01*
G01X945775Y536275D02*
Y549414D01*
G01X945332Y535832D02*
X945775Y536275D01*
G01X945332Y530242D02*
Y535832D01*
G01X945732Y529842D02*
X945332Y530242D01*
G01X914851Y566699D02*
X913779D01*
G01X915551Y565999D02*
X914851Y566699D01*
G01X915551Y564725D02*
Y565999D01*
G01X914414Y563588D02*
X915551Y564725D01*
G01X914414Y562512D02*
Y563588D01*
G01X915426Y561500D02*
X914414Y562512D01*
G01X915426Y560300D02*
Y561500D01*
G01X914414Y559288D02*
X915426Y560300D01*
G01X914414Y558212D02*
Y559288D01*
G01X915526Y557100D02*
X914414Y558212D01*
G01X915526Y554467D02*
Y557100D01*
G01X915351Y554292D02*
X915526Y554467D01*
G01X915351Y552600D02*
Y554292D01*
G01X917037Y550914D02*
X915351Y552600D01*
G01X917125Y550914D02*
X917037D01*
G01X917125Y550966D02*
Y550914D01*
G01X918400Y549691D02*
X917125Y550966D01*
G01X918400Y546300D02*
Y549691D01*
G01X917504Y545404D02*
X918400Y546300D01*
G01X917504Y543896D02*
Y545404D01*
G01X918400Y543000D02*
X917504Y543896D01*
G01X918400Y541899D02*
Y543000D01*
G01X917300Y540799D02*
X918400Y541899D01*
G01X917300Y539401D02*
Y540799D01*
G01X918421Y538280D02*
X917300Y539401D01*
G01X918421Y536478D02*
Y538280D01*
G01X919421Y535478D02*
X918421Y536478D01*
G01X919421Y530697D02*
Y535478D01*
G01X918571Y529847D02*
X919421Y530697D01*
G01X918571Y528029D02*
Y529847D01*
G01X918800Y527800D02*
X918571Y528029D01*
G01X929082Y586457D02*
X927165Y588374D01*
G01X929082Y574183D02*
Y586457D01*
G01X927932Y573033D02*
X929082Y574183D01*
G01X927932Y568367D02*
Y573033D01*
G01X929032Y567267D02*
X927932Y568367D01*
G01X929032Y555257D02*
Y567267D01*
G01X927882Y554107D02*
X929032Y555257D01*
G01X927882Y549857D02*
Y554107D01*
G01X929232Y548507D02*
X927882Y549857D01*
G01X929232Y536632D02*
Y548507D01*
G01X927882Y535282D02*
X929232Y536632D01*
G01X927882Y530594D02*
Y535282D01*
G01X928963Y529513D02*
X927882Y530594D01*
G01X948589Y587368D02*
X947243Y588714D01*
G01X948632Y587368D02*
X948589D01*
G01X948632Y584768D02*
Y587368D01*
G01X948900Y584500D02*
X948632Y584768D01*
G01X948900Y575900D02*
Y584500D01*
G01X948632Y575632D02*
X948900Y575900D01*
G01X948632Y574067D02*
Y575632D01*
G01X949298Y573401D02*
X948632Y574067D01*
G01X949298Y568163D02*
Y573401D01*
G01X948732Y567597D02*
X949298Y568163D01*
G01X948732Y566168D02*
Y567597D01*
G01X948900Y566000D02*
X948732Y566168D01*
G01X948900Y557499D02*
Y566000D01*
G01X948432Y557031D02*
X948900Y557499D01*
G01X948432Y555457D02*
Y557031D01*
G01X949532Y554357D02*
X948432Y555457D01*
G01X949532Y549957D02*
Y554357D01*
G01X948632Y549057D02*
X949532Y549957D01*
G01X948632Y546468D02*
Y549057D01*
G01X948900Y546200D02*
X948632Y546468D01*
G01X948900Y538100D02*
Y546200D01*
G01X948632Y537832D02*
X948900Y538100D01*
G01X948632Y536268D02*
Y537832D01*
G01X949432Y535468D02*
X948632Y536268D01*
G01X949432Y530542D02*
Y535468D01*
G01X948732Y529842D02*
X949432Y530542D01*
G01X910432Y550914D02*
X910344D01*
G01X911778Y549568D02*
X910432Y550914D01*
G01X911821Y549568D02*
X911778D01*
G01X911821Y547179D02*
Y549568D01*
G01X912900Y546100D02*
X911821Y547179D01*
G01X912900Y544700D02*
Y546100D01*
G01X911600Y543400D02*
X912900Y544700D01*
G01X911600Y542100D02*
Y543400D01*
G01X912900Y540800D02*
X911600Y542100D01*
G01X912900Y538779D02*
Y540800D01*
G01X911821Y537700D02*
X912900Y538779D01*
G01X911821Y536179D02*
Y537700D01*
G01X912487Y535513D02*
X911821Y536179D01*
G01X912487Y530363D02*
Y535513D01*
G01X911921Y529797D02*
X912487Y530363D01*
G01X911921Y528179D02*
Y529797D01*
G01X912700Y527400D02*
X911921Y528179D01*
G01X965200Y554633D02*
X963976Y555857D01*
G01X965200Y552100D02*
Y554633D01*
G01X965900Y551400D02*
X965200Y552100D01*
G01X965900Y549700D02*
Y551400D01*
G01X965710Y549510D02*
X965900Y549700D01*
G01X965710Y546690D02*
Y549510D01*
G01X968957Y543443D02*
X965710Y546690D01*
G01X968957Y530643D02*
Y543443D01*
G01X969045Y530555D02*
X968957Y530643D01*
G01X969045Y527845D02*
Y530555D01*
G01X968700Y527500D02*
X969045Y527845D01*
G01X952632Y586507D02*
X950100Y589039D01*
G01X952632Y584832D02*
Y586507D01*
G01X952300Y584500D02*
X952632Y584832D01*
G01X952300Y576032D02*
Y584500D01*
G01X952632Y575700D02*
X952300Y576032D01*
G01X952632Y574042D02*
Y575700D01*
G01X951732Y573142D02*
X952632Y574042D01*
G01X951732Y568397D02*
Y573142D01*
G01X952832Y567297D02*
X951732Y568397D01*
G01X952832Y566232D02*
Y567297D01*
G01X952266Y565666D02*
X952832Y566232D01*
G01X952266Y557666D02*
Y565666D01*
G01X952832Y557100D02*
X952266Y557666D01*
G01X952832Y555657D02*
Y557100D01*
G01X952032Y554857D02*
X952832Y555657D01*
G01X952032Y549457D02*
Y554857D01*
G01X952532Y548957D02*
X952032Y549457D01*
G01X952532Y546532D02*
Y548957D01*
G01X952300Y546300D02*
X952532Y546532D01*
G01X952300Y538132D02*
Y546300D01*
G01X952532Y537900D02*
X952300Y538132D01*
G01X952532Y536532D02*
Y537900D01*
G01X951932Y535932D02*
X952532Y536532D01*
G01X951932Y530366D02*
Y535932D01*
G01X952882Y529416D02*
X951932Y530366D01*
G01X952882Y528582D02*
Y529416D01*
G01X952300Y528000D02*
X952882Y528582D01*
G01X920472Y588367D02*
Y593757D01*
G01X929811Y588364D02*
Y588714D01*
G01X943400Y593260D02*
X943897Y593757D01*
G01X943400Y589089D02*
Y593260D01*
G01X927165Y588374D02*
Y593757D01*
G01X950100Y593267D02*
X950590Y593757D01*
G01X950100Y589039D02*
Y593267D01*
G01X989600Y31840D02*
Y34401D01*
G01X990748Y30692D02*
X989600Y31840D01*
G01X990748Y28022D02*
Y30692D01*
G01X1004134Y28023D02*
X1004133Y28022D01*
G01X1004134Y32865D02*
Y28023D01*
G01X1002500Y34499D02*
X1004134Y32865D01*
G01X1000787Y29892D02*
Y28022D01*
G01X999067Y31612D02*
X1000787Y29892D01*
G01X999067Y36958D02*
Y31612D01*
G01X978970Y32969D02*
X974015Y28014D01*
G01X993501Y31000D02*
X994094Y28022D01*
G01X993340Y31811D02*
X993501Y31000D01*
G01X992487Y33870D02*
X993340Y31811D01*
G01X1005790Y94392D02*
X1014235Y102837D01*
G01X1005790Y91332D02*
Y94392D01*
G01X1005432Y90974D02*
X1005790Y91332D01*
G01X1005432Y88874D02*
Y90974D01*
G01X1005775Y88531D02*
X1005432Y88874D01*
G01X1005775Y85917D02*
Y88531D01*
G01X1005532Y85674D02*
X1005775Y85917D01*
G01X1005532Y83530D02*
Y85674D01*
G01X1006132Y82930D02*
X1005532Y83530D01*
G01X1006132Y73455D02*
Y82930D01*
G01X1005236Y72559D02*
X1006132Y73455D01*
G01X1005236Y67155D02*
Y72559D01*
G01X1005761Y66630D02*
X1005236Y67155D01*
G01X1005761Y64641D02*
Y66630D01*
G01X1006371Y64031D02*
X1005761Y64641D01*
G01X1008364Y64031D02*
X1006371D01*
G01X1008974Y63421D02*
X1008364Y64031D01*
G01X1008974Y61521D02*
Y63421D01*
G01X1008364Y60911D02*
X1008974Y61521D01*
G01X1006082Y60911D02*
X1008364D01*
G01X1005582Y60411D02*
X1006082Y60911D01*
G01X1005582Y58938D02*
Y60411D01*
G01X1006441Y58079D02*
X1005582Y58938D01*
G01X1006441Y54541D02*
Y58079D01*
G01X1004133Y52233D02*
X1006441Y54541D01*
G01X1004133Y46922D02*
Y52233D01*
G01Y42066D02*
Y46922D01*
G01X1005807Y40392D02*
X1004133Y42066D01*
G01X1005807Y37630D02*
Y40392D01*
G01X1004134Y35957D02*
X1005807Y37630D01*
G01X995315Y46922D02*
X994094D01*
G01X995815Y46422D02*
X995315Y46922D01*
G01X995815Y45398D02*
Y46422D01*
G01X995185Y44768D02*
X995815Y45398D01*
G01X993332Y44768D02*
X995185D01*
G01X992670Y44106D02*
X993332Y44768D01*
G01X992670Y43116D02*
Y44106D01*
G01X993228Y42558D02*
X992670Y43116D01*
G01X996379Y42558D02*
X993228D01*
G01X996989Y41948D02*
X996379Y42558D01*
G01X996989Y40958D02*
Y41948D01*
G01X996379Y40348D02*
X996989Y40958D01*
G01X993281Y40348D02*
X996379D01*
G01X992671Y39738D02*
X993281Y40348D01*
G01X992671Y38748D02*
Y39738D01*
G01X993281Y38138D02*
X992671Y38748D01*
G01X995164Y38138D02*
X993281D01*
G01X995763Y37539D02*
X995164Y38138D01*
G01X995763Y36523D02*
Y37539D01*
G01X995197Y35957D02*
X995763Y36523D01*
G01X994094Y35957D02*
X995197D01*
G01X992548Y91476D02*
Y98237D01*
G01X992337Y91265D02*
X992548Y91476D01*
G01X992337Y88583D02*
Y91265D01*
G01X992746Y88174D02*
X992337Y88583D01*
G01X992746Y86274D02*
Y88174D01*
G01X992146Y85674D02*
X992746Y86274D01*
G01X992146Y75155D02*
Y85674D01*
G01X992481Y74820D02*
X992146Y75155D01*
G01X992481Y72694D02*
Y74820D01*
G01X992428Y72641D02*
X992481Y72694D01*
G01X992428Y59971D02*
Y72641D01*
G01X995724Y56675D02*
X992428Y59971D01*
G01X995724Y51630D02*
Y56675D01*
G01X994094Y50000D02*
X995724Y51630D01*
G01X994094Y46922D02*
Y50000D01*
G01X986900Y93600D02*
X985116Y95384D01*
G01X986900Y92728D02*
Y93600D01*
G01X985446Y91274D02*
X986900Y92728D01*
G01X985446Y89224D02*
Y91274D01*
G01X986446Y88224D02*
X985446Y89224D01*
G01X986446Y86474D02*
Y88224D01*
G01X985446Y85474D02*
X986446Y86474D01*
G01X985446Y83300D02*
Y85474D01*
G01X985700Y83046D02*
X985446Y83300D01*
G01X985700Y72613D02*
Y83046D01*
G01X986748Y71565D02*
X985700Y72613D01*
G01X986748Y67861D02*
Y71565D01*
G01X985675Y66788D02*
X986748Y67861D01*
G01X985675Y64066D02*
Y66788D01*
G01X984647Y63038D02*
X985675Y64066D01*
G01X984647Y57551D02*
Y63038D01*
G01X985418Y56780D02*
X984647Y57551D01*
G01X989985Y56780D02*
X985418D01*
G01X990748Y56017D02*
X989985Y56780D01*
G01X990748Y54857D02*
Y56017D01*
G01X989017Y53126D02*
X990748Y54857D01*
G01X989017Y34984D02*
Y53126D01*
G01X989600Y34401D02*
X989017Y34984D01*
G01X972400Y51876D02*
X977362Y46914D01*
G01X972400Y57741D02*
Y51876D01*
G01X975627Y60968D02*
X972400Y57741D01*
G01X975627Y67092D02*
Y60968D01*
G01X975360Y67359D02*
X975627Y67092D01*
G01X975360Y69359D02*
Y67359D01*
G01X975960Y69959D02*
X975360Y69359D01*
G01X975960Y72459D02*
Y69959D01*
G01X975746Y72673D02*
X975960Y72459D01*
G01X975746Y83686D02*
Y72673D01*
G01X975960Y83900D02*
X975746Y83686D01*
G01X975960Y85874D02*
Y83900D01*
G01X975460Y86374D02*
X975960Y85874D01*
G01X975460Y88274D02*
Y86374D01*
G01X976160Y88974D02*
X975460Y88274D01*
G01X976160Y91074D02*
Y88974D01*
G01X975429Y91805D02*
X976160Y91074D01*
G01X975429Y95488D02*
Y91805D01*
G01X976600Y35957D02*
X977362D01*
G01X975700Y36857D02*
X976600Y35957D01*
G01X975700Y45252D02*
Y36857D01*
G01X977362Y46914D02*
X975700Y45252D01*
G01X987401Y40308D02*
Y46914D01*
G01X986791Y39698D02*
X987401Y40308D01*
G01X985801Y39698D02*
X986791D01*
G01X985191Y40308D02*
X985801Y39698D01*
G01X985191Y44375D02*
Y40308D01*
G01X984560Y45006D02*
X985191Y44375D01*
G01X983570Y45006D02*
X984560D01*
G01X982981Y44417D02*
X983570Y45006D01*
G01X982981Y38460D02*
Y44417D01*
G01X983865Y37576D02*
X982981Y38460D01*
G01X986826Y37576D02*
X983865D01*
G01X987401Y37001D02*
X986826Y37576D01*
G01X987401Y35957D02*
Y37001D01*
G01X982060Y91574D02*
Y96461D01*
G01X982504Y91130D02*
X982060Y91574D01*
G01X982504Y88818D02*
Y91130D01*
G01X982060Y88374D02*
X982504Y88818D01*
G01X982060Y86174D02*
Y88374D01*
G01X982425Y85809D02*
X982060Y86174D01*
G01X982425Y72394D02*
Y85809D01*
G01X981860Y71829D02*
X982425Y72394D01*
G01X981860Y67759D02*
Y71829D01*
G01X982400Y67219D02*
X981860Y67759D01*
G01X982400Y52500D02*
Y67219D01*
G01X982138Y52238D02*
X982400Y52500D01*
G01X982138Y49872D02*
Y52238D01*
G01X983010Y49000D02*
X982138Y49872D01*
G01X985315Y49000D02*
X983010D01*
G01X987401Y46914D02*
X985315Y49000D01*
G01X997441Y49011D02*
Y46922D01*
G01X998200Y49770D02*
X997441Y49011D01*
G01X998200Y53170D02*
Y49770D01*
G01X999150Y54120D02*
X998200Y53170D01*
G01X999150Y55950D02*
Y54120D01*
G01X995722Y59378D02*
X999150Y55950D01*
G01X995722Y67283D02*
Y59378D01*
G01X995246Y67759D02*
X995722Y67283D01*
G01X995246Y69159D02*
Y67759D01*
G01X996046Y69959D02*
X995246Y69159D01*
G01X996046Y72159D02*
Y69959D01*
G01X995752Y72453D02*
X996046Y72159D01*
G01X995752Y83406D02*
Y72453D01*
G01X996046Y83700D02*
X995752Y83406D01*
G01X996046Y85574D02*
Y83700D01*
G01X995446Y86174D02*
X996046Y85574D01*
G01X995446Y88374D02*
Y86174D01*
G01X996046Y88974D02*
X995446Y88374D01*
G01X996046Y90974D02*
Y88974D01*
G01X995446Y91574D02*
X996046Y90974D01*
G01X995446Y93308D02*
Y91574D01*
G01X998082Y95944D02*
X995446Y93308D01*
G01X997441Y37736D02*
Y35957D01*
G01X998631Y38926D02*
X997441Y37736D01*
G01X998631Y44082D02*
Y38926D01*
G01X997441Y45272D02*
X998631Y44082D01*
G01X997441Y46922D02*
Y45272D01*
G01X1004134Y56766D02*
Y54857D01*
G01X1002500Y58400D02*
X1004134Y56766D01*
G01X1002500Y66991D02*
Y58400D01*
G01X1002132Y67359D02*
X1002500Y66991D01*
G01X1002132Y69359D02*
Y67359D01*
G01X1002513Y69740D02*
X1002132Y69359D01*
G01X1002513Y83513D02*
Y69740D01*
G01X1002732Y83732D02*
X1002513Y83513D01*
G01X1002732Y85268D02*
Y83732D01*
G01X1001500Y86500D02*
X1002732Y85268D01*
G01X1001500Y87542D02*
Y86500D01*
G01X1002932Y88974D02*
X1001500Y87542D01*
G01X1002932Y91074D02*
Y88974D01*
G01X1002201Y91805D02*
X1002932Y91074D01*
G01X1002201Y96874D02*
Y91805D01*
G01X1002500Y48018D02*
Y34499D01*
G01X1002300Y48218D02*
X1002500Y48018D01*
G01X1002300Y51600D02*
Y48218D01*
G01X1002500Y51800D02*
X1002300Y51600D01*
G01X1002500Y53223D02*
Y51800D01*
G01X1004134Y54857D02*
X1002500Y53223D01*
G01X1001400Y55470D02*
X1000787Y54857D01*
G01X1001400Y56601D02*
Y55470D01*
G01X999168Y58833D02*
X1001400Y56601D01*
G01X999168Y69923D02*
Y58833D01*
G01X998987Y70104D02*
X999168Y69923D01*
G01X998987Y72514D02*
Y70104D01*
G01X999072Y72599D02*
X998987Y72514D01*
G01X999072Y83427D02*
Y72599D01*
G01X998987Y83512D02*
X999072Y83427D01*
G01X998987Y85629D02*
Y83512D01*
G01X999241Y85883D02*
X998987Y85629D01*
G01X999241Y88815D02*
Y85883D01*
G01X998987Y89069D02*
X999241Y88815D01*
G01X998987Y91429D02*
Y89069D01*
G01X1000082Y92524D02*
X998987Y91429D01*
G01X1000082Y100111D02*
Y92524D01*
G01X1000300Y38191D02*
X999067Y36958D01*
G01X1000300Y44739D02*
Y38191D01*
G01X999060Y45979D02*
X1000300Y44739D01*
G01X999060Y47902D02*
Y45979D01*
G01X1000300Y49142D02*
X999060Y47902D01*
G01X1000300Y51677D02*
Y49142D01*
G01X1000787Y52164D02*
X1000300Y51677D01*
G01X1000787Y54857D02*
Y52164D01*
G01X974015Y55875D02*
Y54857D01*
G01X979095Y60955D02*
X974015Y55875D01*
G01X979095Y67194D02*
Y60955D01*
G01X979360Y67459D02*
X979095Y67194D01*
G01X979360Y69459D02*
Y67459D01*
G01X978760Y70059D02*
X979360Y69459D01*
G01X978760Y72359D02*
Y70059D01*
G01X979001Y72600D02*
X978760Y72359D01*
G01X979001Y83798D02*
Y72600D01*
G01X978760Y84039D02*
X979001Y83798D01*
G01X978760Y85674D02*
Y84039D01*
G01X979360Y86274D02*
X978760Y85674D01*
G01X979360Y88174D02*
Y86274D01*
G01X978660Y88874D02*
X979360Y88174D01*
G01X978660Y90974D02*
Y88874D01*
G01X980060Y92374D02*
X978660Y90974D01*
G01X980060Y97290D02*
Y92374D01*
G01X978970Y48531D02*
Y32969D01*
G01X974015Y53486D02*
X978970Y48531D01*
G01X974015Y54857D02*
Y53486D01*
G01X972400Y66899D02*
Y60530D01*
G01X973060Y67559D02*
X972400Y66899D01*
G01X973060Y72053D02*
Y67559D01*
G01X972407Y72706D02*
X973060Y72053D01*
G01X972407Y74892D02*
Y72706D01*
G01X972060Y75239D02*
X972407Y74892D01*
G01X972060Y85474D02*
Y75239D01*
G01X973060Y86474D02*
X972060Y85474D01*
G01X973060Y88224D02*
Y86474D01*
G01X972060Y89224D02*
X973060Y88224D01*
G01X972060Y91274D02*
Y89224D01*
G01X973060Y92274D02*
X972060Y91274D01*
G01X973060Y95948D02*
Y92274D01*
G01X994094Y55957D02*
Y54857D01*
G01X990458Y59593D02*
X994094Y55957D01*
G01X988351Y59593D02*
X990458D01*
G01X987741Y60203D02*
X988351Y59593D01*
G01X987741Y61193D02*
Y60203D01*
G01X988351Y61803D02*
X987741Y61193D01*
G01X989884Y61803D02*
X988351D01*
G01X990630Y62549D02*
X989884Y61803D01*
G01X990630Y63597D02*
Y62549D01*
G01X989142Y65085D02*
X990630Y63597D01*
G01X989142Y68595D02*
Y65085D01*
G01X990009Y69462D02*
X989142Y68595D01*
G01X990009Y71796D02*
Y69462D01*
G01X989024Y72781D02*
X990009Y71796D01*
G01X989024Y83008D02*
Y72781D01*
G01X989346Y83330D02*
X989024Y83008D01*
G01X989346Y85874D02*
Y83330D01*
G01X988846Y86374D02*
X989346Y85874D01*
G01X988846Y88274D02*
Y86374D01*
G01X990000Y89428D02*
X988846Y88274D01*
G01X990000Y90620D02*
Y89428D01*
G01X988948Y91672D02*
X990000Y90620D01*
G01X988948Y97466D02*
Y91672D01*
G01X992487Y36649D02*
Y33870D01*
G01X991040Y38096D02*
X992487Y36649D01*
G01X991040Y44802D02*
Y38096D01*
G01X992470Y46232D02*
X991040Y44802D01*
G01X992470Y50936D02*
Y46232D01*
G01X994094Y54857D02*
X992470Y50936D01*
G01X1017700Y107669D02*
Y192974D01*
G01X1014235Y104204D02*
X1017700Y107669D01*
G01X1014235Y102837D02*
Y104204D01*
G01X1009700Y115389D02*
Y192853D01*
G01X992548Y98237D02*
X1009700Y115389D01*
G01X1032122Y106734D02*
X1033886Y104970D01*
G01X1032122Y195289D02*
Y106734D01*
G01X994645Y129045D02*
Y198346D01*
G01X971938Y106338D02*
X994645Y129045D01*
G01X971938Y97681D02*
Y106338D01*
G01X991268Y197909D02*
Y132228D01*
G01X989709Y197885D02*
Y133716D01*
G01X1005700Y117100D02*
Y189905D01*
G01X985116Y96516D02*
X1005700Y117100D01*
G01X985116Y95384D02*
Y96516D01*
G01X993094Y198703D02*
Y130691D01*
G01X981208Y101267D02*
X975429Y95488D01*
G01X981208Y104837D02*
Y101267D01*
G01X997796Y121425D02*
X981208Y104837D01*
G01X997796Y198224D02*
Y121425D01*
G01X1001796Y116197D02*
Y199049D01*
G01X982060Y96461D02*
X1001796Y116197D01*
G01X998082Y100941D02*
Y95944D01*
G01X1011700Y114559D02*
X998082Y100941D01*
G01X1011700Y192853D02*
Y114559D01*
G01X1004521Y99194D02*
X1002201Y96874D01*
G01X1006396Y99194D02*
X1004521D01*
G01X1007527Y100325D02*
X1006396Y99194D01*
G01X1007527Y101457D02*
Y100325D01*
G01X1006458Y102526D02*
X1007527Y101457D01*
G01X1006458Y103658D02*
Y102526D01*
G01X1007589Y104789D02*
X1006458Y103658D01*
G01X1008721Y104789D02*
X1007589D01*
G01X1009790Y103720D02*
X1008721Y104789D01*
G01X1010922Y103720D02*
X1009790D01*
G01X1012053Y104851D02*
X1010922Y103720D01*
G01X1012053Y105983D02*
Y104851D01*
G01X1010984Y107052D02*
X1012053Y105983D01*
G01X1010984Y108184D02*
Y107052D01*
G01X1012115Y109315D02*
X1010984Y108184D01*
G01X1015017Y109315D02*
X1012115D01*
G01X1015700Y109998D02*
X1015017Y109315D01*
G01X1015700Y192683D02*
Y109998D01*
G01X1013700Y113729D02*
X1000082Y100111D01*
G01X1013700Y192561D02*
Y113729D01*
G01X984584Y101814D02*
X980060Y97290D01*
G01X984584Y103084D02*
Y101814D01*
G01X983830Y103838D02*
X984584Y103084D01*
G01X983830Y104546D02*
Y103838D01*
G01X985329Y106045D02*
X983830Y104546D01*
G01X986037Y106045D02*
X985329D01*
G01X986995Y105087D02*
X986037Y106045D01*
G01X987857Y105087D02*
X986995D01*
G01X989202Y106432D02*
X987857Y105087D01*
G01X989202Y107294D02*
Y106432D01*
G01X988105Y108391D02*
X989202Y107294D01*
G01X988105Y109253D02*
Y108391D01*
G01X989450Y110598D02*
X988105Y109253D01*
G01X990312Y110598D02*
X989450D01*
G01X991409Y109501D02*
X990312Y110598D01*
G01X992271Y109501D02*
X991409D01*
G01X993616Y110846D02*
X992271Y109501D01*
G01X993616Y111708D02*
Y110846D01*
G01X992519Y112805D02*
X993616Y111708D01*
G01X992519Y113667D02*
Y112805D01*
G01X993864Y115012D02*
X992519Y113667D01*
G01X994726Y115012D02*
X993864D01*
G01X995538Y114200D02*
X994726Y115012D01*
G01X996246Y114200D02*
X995538D01*
G01X999796Y117750D02*
X996246Y114200D01*
G01X999796Y198928D02*
Y117750D01*
G01X979100Y101988D02*
X973060Y95948D01*
G01X979100Y105558D02*
Y101988D01*
G01X996184Y122642D02*
X979100Y105558D01*
G01X996184Y198054D02*
Y122642D01*
G01X1007700Y116218D02*
X988948Y97466D01*
G01X1007700Y190734D02*
Y116218D01*
G01X977756Y183856D02*
Y197291D01*
G01X972700Y196635D02*
Y184900D01*
G01X972756Y196691D02*
X972700Y196635D01*
G01X1003796Y191809D02*
Y198734D01*
G01X1005700Y189905D02*
X1003796Y191809D01*
G01X975475Y196432D02*
X975256Y196651D01*
G01X975475Y184675D02*
Y196432D01*
G01X1005796Y192638D02*
X1007700Y190734D01*
G01X1005796Y198807D02*
Y192638D01*
G01X980250Y197285D02*
X980256Y197291D01*
G01X980250Y182750D02*
Y197285D01*
G01X972561Y175061D02*
X980250Y182750D01*
G01X971847Y175061D02*
X972561D01*
G01X988354Y400454D02*
Y473546D01*
G01X994398Y396937D02*
Y476502D01*
G01X996398Y397118D02*
Y482150D01*
G01X990354Y401003D02*
Y474546D01*
G01X998398Y397365D02*
Y482570D01*
G01X992354Y400788D02*
Y475446D01*
G01X1006398Y407982D02*
Y487272D01*
G01X980512Y405921D02*
Y418908D01*
G01X1016398Y408694D02*
Y500114D01*
G01X1000398Y407015D02*
Y482948D01*
G01X1002398Y407700D02*
Y485612D01*
G01X1031800Y407043D02*
Y496600D01*
G01X1012398Y408331D02*
Y494801D01*
G01X972712Y403924D02*
Y416100D01*
G01X975212Y403862D02*
Y417136D01*
G01X1008398Y408586D02*
Y493252D01*
G01X1010398Y408385D02*
Y493972D01*
G01X1004398Y407727D02*
Y486442D01*
G01X1014398Y408465D02*
Y498700D01*
G01X978216Y405717D02*
Y417668D01*
G01X992400Y519400D02*
Y530400D01*
G01X992559Y519241D02*
X992400Y519400D01*
G01X992559Y516859D02*
Y519241D01*
G01X992260Y516560D02*
X992559Y516859D01*
G01X992260Y514140D02*
Y516560D01*
G01X992559Y513841D02*
X992260Y514140D01*
G01X992559Y511559D02*
Y513841D01*
G01X992303Y511303D02*
X992559Y511559D01*
G01X992303Y509359D02*
Y511303D01*
G01X994000Y507662D02*
X992303Y509359D01*
G01X994000Y499670D02*
Y507662D01*
G01X1006398Y487272D02*
X994000Y499670D01*
G01X1008300Y517306D02*
Y526900D01*
G01X1006852Y515858D02*
X1008300Y517306D01*
G01X1006852Y514589D02*
Y515858D01*
G01X1007327Y514114D02*
X1006852Y514589D01*
G01X1007327Y511327D02*
Y514114D01*
G01X1006678Y510678D02*
X1007327Y511327D01*
G01X1006678Y507764D02*
Y510678D01*
G01X1007382Y507060D02*
X1006678Y507764D01*
G01X1013713Y507060D02*
X1007382D01*
G01X1014844Y505929D02*
X1013713Y507060D01*
G01X1014844Y501668D02*
Y505929D01*
G01X1016398Y500114D02*
X1014844Y501668D01*
G01X982400Y519500D02*
Y530400D01*
G01X982100Y519200D02*
X982400Y519500D01*
G01X982100Y517000D02*
Y519200D01*
G01X982600Y516500D02*
X982100Y517000D01*
G01X982600Y514400D02*
Y516500D01*
G01X982200Y514000D02*
X982600Y514400D01*
G01X982200Y511600D02*
Y514000D01*
G01X983500Y510300D02*
X982200Y511600D01*
G01X983500Y499846D02*
Y510300D01*
G01X1000398Y482948D02*
X983500Y499846D01*
G01X985900Y516900D02*
Y527700D01*
G01X985500Y516500D02*
X985900Y516900D01*
G01X985500Y514200D02*
Y516500D01*
G01X985974Y513726D02*
X985500Y514200D01*
G01X985974Y511774D02*
Y513726D01*
G01X985500Y511300D02*
X985974Y511774D01*
G01X985500Y507310D02*
Y511300D01*
G01X986300Y506510D02*
X985500Y507310D01*
G01X988538Y506510D02*
X986300D01*
G01X989338Y505710D02*
X988538Y506510D01*
G01X989338Y504110D02*
Y505710D01*
G01X988538Y503310D02*
X989338Y504110D01*
G01X986300Y503310D02*
X988538D01*
G01X985656Y502666D02*
X986300Y503310D01*
G01X985656Y500608D02*
Y502666D01*
G01X986391Y499873D02*
X985656Y500608D01*
G01X988137Y499873D02*
X986391D01*
G01X993709Y494301D02*
X988137Y499873D01*
G01X993709Y492491D02*
Y494301D01*
G01X995067Y491133D02*
X993709Y492491D01*
G01X996877Y491133D02*
X995067D01*
G01X998235Y489775D02*
X996877Y491133D01*
G01X998235Y487965D02*
Y489775D01*
G01X999593Y486607D02*
X998235Y487965D01*
G01X1001403Y486607D02*
X999593D01*
G01X1002398Y485612D02*
X1001403Y486607D01*
G01X1031800Y496600D02*
X1037600Y502400D01*
G01X972400Y519500D02*
Y530700D01*
G01X972600Y519300D02*
X972400Y519500D01*
G01X972600Y516900D02*
Y519300D01*
G01X972000Y516300D02*
X972600Y516900D01*
G01X972000Y514400D02*
Y516300D01*
G01X972500Y513900D02*
X972000Y514400D01*
G01X972500Y511600D02*
Y513900D01*
G01X972100Y511200D02*
X972500Y511600D01*
G01X972100Y498800D02*
Y511200D01*
G01X994398Y476502D02*
X972100Y498800D01*
G01X1002513Y520013D02*
Y539339D01*
G01X1002300Y519800D02*
X1002513Y520013D01*
G01X1002300Y516600D02*
Y519800D01*
G01X1002727Y516173D02*
X1002300Y516600D01*
G01X1002727Y514327D02*
Y516173D01*
G01X1001779Y513379D02*
X1002727Y514327D01*
G01X1001779Y512121D02*
Y513379D01*
G01X1002800Y511100D02*
X1001779Y512121D01*
G01X1002800Y504399D02*
Y511100D01*
G01X1012398Y494801D02*
X1002800Y504399D01*
G01X975657Y521049D02*
Y532957D01*
G01X975500Y520892D02*
X975657Y521049D01*
G01X975500Y516900D02*
Y520892D01*
G01X976000Y516400D02*
X975500Y516900D01*
G01X976000Y514400D02*
Y516400D01*
G01X975400Y513800D02*
X976000Y514400D01*
G01X975400Y511500D02*
Y513800D01*
G01X976000Y510900D02*
X975400Y511500D01*
G01X976000Y509446D02*
Y510900D01*
G01X979300Y506146D02*
X976000Y509446D01*
G01X979300Y499248D02*
Y506146D01*
G01X980975Y497573D02*
X979300Y499248D01*
G01X980975Y496711D02*
Y497573D01*
G01X979857Y495593D02*
X980975Y496711D01*
G01X979857Y494786D02*
Y495593D01*
G01X980841Y493802D02*
X979857Y494786D01*
G01X981758Y493802D02*
X980841D01*
G01X982821Y494865D02*
X981758Y493802D01*
G01X983683Y494865D02*
X982821D01*
G01X984667Y493881D02*
X983683Y494865D01*
G01X984667Y493019D02*
Y493881D01*
G01X983593Y491945D02*
X984667Y493019D01*
G01X983593Y491083D02*
Y491945D01*
G01X984577Y490099D02*
X983593Y491083D01*
G01X985439Y490099D02*
X984577D01*
G01X986513Y491173D02*
X985439Y490099D01*
G01X987375Y491173D02*
X986513D01*
G01X988359Y490189D02*
X987375Y491173D01*
G01X988359Y489327D02*
Y490189D01*
G01X987571Y488539D02*
X988359Y489327D01*
G01X987571Y487611D02*
Y488539D01*
G01X988555Y486627D02*
X987571Y487611D01*
G01X989351Y486627D02*
X988555D01*
G01X990205Y487481D02*
X989351Y486627D01*
G01X991067Y487481D02*
X990205D01*
G01X996398Y482150D02*
X991067Y487481D01*
G01X995726Y520698D02*
Y530374D01*
G01X995185Y520157D02*
X995726Y520698D01*
G01X995185Y517339D02*
Y520157D01*
G01X996104Y516420D02*
X995185Y517339D01*
G01X996104Y514504D02*
Y516420D01*
G01X995008Y513408D02*
X996104Y514504D01*
G01X995008Y511772D02*
Y513408D01*
G01X996000Y510780D02*
X995008Y511772D01*
G01X996000Y505540D02*
Y510780D01*
G01X998767Y502773D02*
X996000Y505540D01*
G01X998767Y501281D02*
Y502773D01*
G01X997824Y500338D02*
X998767Y501281D01*
G01X997824Y499178D02*
Y500338D01*
G01X998955Y498047D02*
X997824Y499178D01*
G01X1000059Y498047D02*
X998955D01*
G01X1001210Y499198D02*
X1000059Y498047D01*
G01X1002342Y499198D02*
X1001210D01*
G01X1003473Y498067D02*
X1002342Y499198D01*
G01X1003473Y496935D02*
Y498067D01*
G01X1002056Y495518D02*
X1003473Y496935D01*
G01X1002056Y494486D02*
Y495518D01*
G01X1003187Y493355D02*
X1002056Y494486D01*
G01X1004419Y493355D02*
X1003187D01*
G01X1005671Y494607D02*
X1004419Y493355D01*
G01X1007043Y494607D02*
X1005671D01*
G01X1008398Y493252D02*
X1007043Y494607D01*
G01X999164Y519236D02*
Y533036D01*
G01X999400Y519000D02*
X999164Y519236D01*
G01X999400Y516600D02*
Y519000D01*
G01X998800Y516000D02*
X999400Y516600D01*
G01X998800Y514300D02*
Y516000D01*
G01X999400Y513700D02*
X998800Y514300D01*
G01X999400Y511700D02*
Y513700D01*
G01X998000Y510300D02*
X999400Y511700D01*
G01X998000Y506370D02*
Y510300D01*
G01X1010398Y493972D02*
X998000Y506370D01*
G01X988948Y516952D02*
Y527848D01*
G01X989400Y516500D02*
X988948Y516952D01*
G01X989400Y514400D02*
Y516500D01*
G01X988800Y513800D02*
X989400Y514400D01*
G01X988800Y512000D02*
Y513800D01*
G01X989300Y511500D02*
X988800Y512000D01*
G01X989300Y509533D02*
Y511500D01*
G01X992000Y506833D02*
X989300Y509533D01*
G01X992000Y498840D02*
Y506833D01*
G01X1004398Y486442D02*
X992000Y498840D01*
G01X979094Y519206D02*
Y530388D01*
G01X979400Y518900D02*
X979094Y519206D01*
G01X979400Y517100D02*
Y518900D01*
G01X978700Y516400D02*
X979400Y517100D01*
G01X978700Y514700D02*
Y516400D01*
G01X979300Y514100D02*
X978700Y514700D01*
G01X979300Y511500D02*
Y514100D01*
G01X978700Y510900D02*
X979300Y511500D01*
G01X978700Y509576D02*
Y510900D01*
G01X981500Y506776D02*
X978700Y509576D01*
G01X981500Y499468D02*
Y506776D01*
G01X998398Y482570D02*
X981500Y499468D01*
G01X1006300Y524630D02*
Y527400D01*
G01X1005564Y523894D02*
X1006300Y524630D01*
G01X1005564Y520986D02*
Y523894D01*
G01X1006300Y520250D02*
X1005564Y520986D01*
G01X1006300Y517856D02*
Y520250D01*
G01X1005043Y516599D02*
X1006300Y517856D01*
G01X1005043Y514101D02*
Y516599D01*
G01X1005680Y513464D02*
X1005043Y514101D01*
G01X1005680Y512006D02*
Y513464D01*
G01X1004532Y510858D02*
X1005680Y512006D01*
G01X1004532Y505868D02*
Y510858D01*
G01X1006072Y504328D02*
X1004532Y505868D01*
G01X1007686Y504328D02*
X1006072D01*
G01X1008563Y505205D02*
X1007686Y504328D01*
G01X1009695Y505205D02*
X1008563D01*
G01X1010826Y504074D02*
X1009695Y505205D01*
G01X1010826Y502942D02*
Y504074D01*
G01X1009708Y501824D02*
X1010826Y502942D01*
G01X1009708Y500692D02*
Y501824D01*
G01X1010839Y499561D02*
X1009708Y500692D01*
G01X1013537Y499561D02*
X1010839D01*
G01X1014398Y498700D02*
X1013537Y499561D01*
G01X994094Y553575D02*
Y555857D01*
G01X992473Y551954D02*
X994094Y553575D01*
G01X992473Y535873D02*
Y551954D01*
G01X992133Y535533D02*
X992473Y535873D01*
G01X992133Y533667D02*
Y535533D01*
G01X992700Y533100D02*
X992133Y533667D01*
G01X992700Y530700D02*
Y533100D01*
G01X992400Y530400D02*
X992700Y530700D01*
G01X994094Y565386D02*
Y566822D01*
G01X993484Y564776D02*
X994094Y565386D01*
G01X990179Y564776D02*
X993484D01*
G01X989590Y564187D02*
X990179Y564776D01*
G01X989590Y563197D02*
Y564187D01*
G01X990221Y562566D02*
X989590Y563197D01*
G01X994895Y562566D02*
X990221D01*
G01X995547Y561914D02*
X994895Y562566D01*
G01X995547Y560924D02*
Y561914D01*
G01X994979Y560356D02*
X995547Y560924D01*
G01X990115Y560356D02*
X994979D01*
G01X989441Y559682D02*
X990115Y560356D01*
G01X989441Y558692D02*
Y559682D01*
G01X989987Y558146D02*
X989441Y558692D01*
G01X993484Y558146D02*
X989987D01*
G01X994094Y557536D02*
X993484Y558146D01*
G01X994094Y555857D02*
Y557536D01*
G01X1004134Y570022D02*
Y574757D01*
G01X1005813Y568343D02*
X1004134Y570022D01*
G01X1005813Y554997D02*
Y568343D01*
G01X1005379Y554563D02*
X1005813Y554997D01*
G01X1005379Y551837D02*
Y554563D01*
G01X1004134Y550592D02*
X1005379Y551837D01*
G01X1004134Y547923D02*
Y550592D01*
G01X1004133Y547922D02*
X1004134Y547923D01*
G01X1004133Y546844D02*
Y547922D01*
G01X1008600Y542377D02*
X1004133Y546844D01*
G01X1008600Y540068D02*
Y542377D01*
G01X1009400Y539268D02*
X1008600Y540068D01*
G01X1009400Y528000D02*
Y539268D01*
G01X1008300Y526900D02*
X1009400Y528000D01*
G01X977362Y572138D02*
Y574757D01*
G01X979079Y570421D02*
X977362Y572138D01*
G01X979079Y554179D02*
Y570421D01*
G01X977362Y552462D02*
X979079Y554179D01*
G01X977362Y547914D02*
Y552462D01*
G01X982444Y542832D02*
X977362Y547914D01*
G01X982444Y536044D02*
Y542832D01*
G01X982092Y535692D02*
X982444Y536044D01*
G01X982092Y530708D02*
Y535692D01*
G01X982400Y530400D02*
X982092Y530708D01*
G01X985931Y573287D02*
X987401Y574757D01*
G01X985931Y570438D02*
Y573287D01*
G01X984352Y568859D02*
X985931Y570438D01*
G01X983516Y568859D02*
X984352D01*
G01X982394Y567737D02*
X983516Y568859D01*
G01X982394Y555106D02*
Y567737D01*
G01X983356Y554144D02*
X982394Y555106D01*
G01X984452Y554144D02*
X983356D01*
G01X985662Y552934D02*
X984452Y554144D01*
G01X985662Y552238D02*
Y552934D01*
G01X987401Y550499D02*
X985662Y552238D01*
G01X987401Y547914D02*
Y550499D01*
G01X985764Y546277D02*
X987401Y547914D01*
G01X985764Y530564D02*
Y546277D01*
G01X985676Y530476D02*
X985764Y530564D01*
G01X985676Y527924D02*
Y530476D01*
G01X985900Y527700D02*
X985676Y527924D01*
G01X972395Y535995D02*
Y538105D01*
G01X972835Y535555D02*
X972395Y535995D01*
G01X972835Y531135D02*
Y535555D01*
G01X972400Y530700D02*
X972835Y531135D01*
G01X1000787Y555857D02*
Y566822D01*
G01Y553723D02*
Y555857D01*
G01X1000183Y553119D02*
X1000787Y553723D01*
G01X1000183Y550383D02*
Y553119D01*
G01X999062Y549262D02*
X1000183Y550383D01*
G01X999062Y546338D02*
Y549262D01*
G01X1001300Y544100D02*
X999062Y546338D01*
G01X1001300Y540552D02*
Y544100D01*
G01X1002513Y539339D02*
X1001300Y540552D01*
G01X972601Y549501D02*
Y553925D01*
G01X972394Y549294D02*
X972601Y549501D01*
G01X972394Y546706D02*
Y549294D01*
G01X975700Y543400D02*
X972394Y546706D01*
G01X975700Y533000D02*
Y543400D01*
G01X975657Y532957D02*
X975700Y533000D01*
G01X994094Y545506D02*
Y547922D01*
G01X995800Y543800D02*
X994094Y545506D01*
G01X995800Y533200D02*
Y543800D01*
G01X995500Y532900D02*
X995800Y533200D01*
G01X995500Y530600D02*
Y532900D01*
G01X995726Y530374D02*
X995500Y530600D01*
G01X994094Y570370D02*
Y574757D01*
G01X995711Y568753D02*
X994094Y570370D01*
G01X995711Y565319D02*
Y568753D01*
G01X997257Y563773D02*
X995711Y565319D01*
G01X997257Y558766D02*
Y563773D01*
G01X995711Y557220D02*
X997257Y558766D01*
G01X995711Y551691D02*
Y557220D01*
G01X994094Y550074D02*
X995711Y551691D01*
G01X994094Y547922D02*
Y550074D01*
G01X997441Y545059D02*
Y547922D01*
G01X999046Y543454D02*
X997441Y545059D01*
G01X999046Y535946D02*
Y543454D01*
G01X998900Y535800D02*
X999046Y535946D01*
G01X998900Y533300D02*
Y535800D01*
G01X999164Y533036D02*
X998900Y533300D01*
G01X997441Y571763D02*
Y574757D01*
G01X999164Y570040D02*
X997441Y571763D01*
G01X999164Y554664D02*
Y570040D01*
G01X998300Y553800D02*
X999164Y554664D01*
G01X998300Y551451D02*
Y553800D01*
G01X997441Y550592D02*
X998300Y551451D01*
G01X997441Y547922D02*
Y550592D01*
G01X990748Y553648D02*
Y555857D01*
G01X989026Y551926D02*
X990748Y553648D01*
G01X989026Y532826D02*
Y551926D01*
G01X988947Y532747D02*
X989026Y532826D01*
G01X988947Y530653D02*
Y532747D01*
G01X989115Y530485D02*
X988947Y530653D01*
G01X989115Y528015D02*
Y530485D01*
G01X988948Y527848D02*
X989115Y528015D01*
G01X991365Y567439D02*
X990748Y566822D01*
G01X991365Y571385D02*
Y567439D01*
G01X990671Y572079D02*
X991365Y571385D01*
G01X988628Y572079D02*
X990671D01*
G01X987976Y571427D02*
X988628Y572079D01*
G01X987976Y569943D02*
Y571427D01*
G01X985683Y567650D02*
X987976Y569943D01*
G01X985683Y565505D02*
Y567650D01*
G01X986284Y564904D02*
X985683Y565505D01*
G01X987231Y564904D02*
X986284D01*
G01X987757Y564378D02*
X987231Y564904D01*
G01X987757Y562989D02*
Y564378D01*
G01X987147Y562379D02*
X987757Y562989D01*
G01X985815Y562379D02*
X987147D01*
G01X985227Y561791D02*
X985815Y562379D01*
G01X985227Y560801D02*
Y561791D01*
G01X985859Y560169D02*
X985227Y560801D01*
G01X987147Y560169D02*
X985859D01*
G01X987757Y559559D02*
X987147Y560169D01*
G01X987757Y558058D02*
Y559559D01*
G01X989958Y555857D02*
X987757Y558058D01*
G01X990748Y555857D02*
X989958D01*
G01X974015D02*
Y566814D01*
G01Y555115D02*
Y555857D01*
G01X975100Y554030D02*
X974015Y555115D01*
G01X975100Y549500D02*
Y554030D01*
G01X975700Y548900D02*
X975100Y549500D01*
G01X975700Y546800D02*
Y548900D01*
G01X978991Y543509D02*
X975700Y546800D01*
G01X978991Y530491D02*
Y543509D01*
G01X979094Y530388D02*
X978991Y530491D01*
G01X1004134Y566821D02*
X1004133Y566822D01*
G01X1004134Y555857D02*
Y566821D01*
G01X1003763Y555486D02*
X1004134Y555857D01*
G01X1003763Y553063D02*
Y555486D01*
G01X1002500Y551800D02*
X1003763Y553063D01*
G01X1002500Y546100D02*
Y551800D01*
G01X1005762Y542838D02*
X1002500Y546100D01*
G01X1005762Y536302D02*
Y542838D01*
G01X1005350Y535890D02*
X1005762Y536302D01*
G01X1005350Y530888D02*
Y535890D01*
G01X1005769Y530469D02*
X1005350Y530888D01*
G01X1005769Y527931D02*
Y530469D01*
G01X1006300Y527400D02*
X1005769Y527931D01*
G01X1087797Y30103D02*
Y28022D01*
G01X1082840Y35060D02*
X1087797Y30103D01*
G01X1059659Y29989D02*
X1057677Y28007D01*
G01X1059659Y34724D02*
Y29989D01*
G01X1074409Y32871D02*
Y28007D01*
G01X1072690Y34590D02*
X1074409Y32871D01*
G01X1081102Y29998D02*
Y28007D01*
G01X1076141Y34959D02*
X1081102Y29998D01*
G01X1049360Y31959D02*
Y47828D01*
G01X1047637Y30236D02*
X1049360Y31959D01*
G01X1047637Y28007D02*
Y30236D01*
G01X1054330Y32686D02*
X1052668Y34348D01*
G01X1054330Y28023D02*
Y32686D01*
G01X1054331Y28022D02*
X1054330Y28023D01*
G01X1064371Y32228D02*
Y28022D01*
G01X1065217Y33074D02*
X1064371Y32228D01*
G01X1067410Y31945D02*
X1066281Y33074D01*
G01X1068396Y31945D02*
X1067410D01*
G01X1069457Y33006D02*
X1068396Y31945D01*
G01X1094488Y30012D02*
Y28022D01*
G01X1089421Y35079D02*
X1094488Y30012D01*
G01X1094786Y51946D02*
X1096600Y53760D01*
G01X1094786Y47220D02*
Y51946D01*
G01X1094488Y46922D02*
X1094786Y47220D01*
G01X1073858Y54842D02*
X1074409D01*
G01X1068580Y60120D02*
X1073858Y54842D01*
G01X1068580Y63780D02*
Y60120D01*
G01X1069450Y64650D02*
X1068580Y63780D01*
G01X1069450Y67166D02*
Y64650D01*
G01X1069157Y67459D02*
X1069450Y67166D01*
G01X1069157Y71471D02*
Y67459D01*
G01X1069469Y71783D02*
X1069157Y71471D01*
G01X1069469Y72647D02*
Y71783D01*
G01X1069452Y72664D02*
X1069469Y72647D01*
G01X1069452Y75054D02*
Y72664D01*
G01X1069757Y75359D02*
X1069452Y75054D01*
G01X1069757Y91074D02*
Y75359D01*
G01X1069200Y91631D02*
X1069757Y91074D01*
G01X1069200Y95300D02*
Y91631D01*
G01X1082840Y48260D02*
Y35060D01*
G01X1081321Y49779D02*
X1082840Y48260D01*
G01X1081321Y52143D02*
Y49779D01*
G01X1082739Y53561D02*
X1081321Y52143D01*
G01X1082739Y56973D02*
Y53561D01*
G01X1079381Y60331D02*
X1082739Y56973D01*
G01X1079381Y69852D02*
Y60331D01*
G01X1079074Y70159D02*
X1079381Y69852D01*
G01X1079074Y72059D02*
Y70159D01*
G01X1079362Y72347D02*
X1079074Y72059D01*
G01X1079362Y83186D02*
Y72347D01*
G01X1079160Y83388D02*
X1079362Y83186D01*
G01X1079160Y85660D02*
Y83388D01*
G01X1079605Y86105D02*
X1079160Y85660D01*
G01X1079605Y88543D02*
Y86105D01*
G01X1079174Y88974D02*
X1079605Y88543D01*
G01X1079174Y91074D02*
Y88974D01*
G01X1079587Y91487D02*
X1079174Y91074D01*
G01X1079587Y94813D02*
Y91487D01*
G01X1057562Y54957D02*
X1057677Y54842D01*
G01X1056644Y54957D02*
X1057562D01*
G01X1052648Y58953D02*
X1056644Y54957D01*
G01X1052648Y67477D02*
Y58953D01*
G01X1051618Y68507D02*
X1052648Y67477D01*
G01X1051618Y71946D02*
Y68507D01*
G01X1052701Y73029D02*
X1051618Y71946D01*
G01X1052700Y73032D02*
X1052701Y73029D01*
G01X1052700Y75372D02*
Y73032D01*
G01X1051570Y76502D02*
X1052700Y75372D01*
G01X1051570Y79244D02*
Y76502D01*
G01X1052700Y80374D02*
X1051570Y79244D01*
G01X1052700Y82900D02*
Y80374D01*
G01X1052300Y83300D02*
X1052700Y82900D01*
G01X1052300Y86163D02*
Y83300D01*
G01X1052783Y86646D02*
X1052300Y86163D01*
G01X1052783Y88138D02*
Y86646D01*
G01X1052300Y88621D02*
X1052783Y88138D01*
G01X1052300Y91528D02*
Y88621D01*
G01X1053169Y92397D02*
X1052300Y91528D01*
G01X1053169Y94142D02*
Y92397D01*
G01X1051811Y95500D02*
X1053169Y94142D01*
G01X1059397Y34986D02*
X1059659Y34724D01*
G01X1059397Y36710D02*
Y34986D01*
G01X1055958Y40149D02*
X1059397Y36710D01*
G01X1055958Y53123D02*
Y40149D01*
G01X1057677Y54842D02*
X1055958Y53123D01*
G01X1042300Y51582D02*
X1044290Y49592D01*
G01X1042300Y55800D02*
Y51582D01*
G01X1039300Y58800D02*
X1042300Y55800D01*
G01X1039300Y62200D02*
Y58800D01*
G01X1042400Y65300D02*
X1039300Y62200D01*
G01X1042400Y92786D02*
Y65300D01*
G01X1038721Y96465D02*
X1042400Y92786D01*
G01X1046100Y37765D02*
X1044292Y35957D01*
G01X1046100Y45600D02*
Y37765D01*
G01X1045500Y46200D02*
X1046100Y45600D01*
G01X1045500Y48382D02*
Y46200D01*
G01X1044290Y49592D02*
X1045500Y48382D01*
G01X1072690Y51814D02*
Y34590D01*
G01X1071732Y52772D02*
X1072690Y51814D01*
G01X1070428Y52772D02*
X1071732D01*
G01X1069452Y53748D02*
X1070428Y52772D01*
G01X1069452Y55677D02*
Y53748D01*
G01X1066350Y58779D02*
X1069452Y55677D01*
G01X1066350Y64250D02*
Y58779D01*
G01X1066006Y64594D02*
X1066350Y64250D01*
G01X1066006Y83494D02*
Y64594D01*
G01X1065789Y83711D02*
X1066006Y83494D01*
G01X1065789Y85889D02*
Y83711D01*
G01X1066274Y86374D02*
X1065789Y85889D01*
G01X1066274Y88374D02*
Y86374D01*
G01X1065571Y89077D02*
X1066274Y88374D01*
G01X1065571Y91087D02*
Y89077D01*
G01X1066396Y91912D02*
X1065571Y91087D01*
G01X1066396Y95204D02*
Y91912D01*
G01X1076141Y53559D02*
Y34959D01*
G01X1076026Y53674D02*
X1076141Y53559D01*
G01X1076026Y55574D02*
Y53674D01*
G01X1072700Y58900D02*
X1076026Y55574D01*
G01X1072700Y66902D02*
Y58900D01*
G01X1073247Y67449D02*
X1072700Y66902D01*
G01X1073247Y70969D02*
Y67449D01*
G01X1072684Y71532D02*
X1073247Y70969D01*
G01X1072684Y76016D02*
Y71532D01*
G01X1072274Y76426D02*
X1072684Y76016D01*
G01X1072274Y85591D02*
Y76426D01*
G01X1072919Y86236D02*
X1072274Y85591D01*
G01X1072919Y88412D02*
Y86236D01*
G01X1072296Y89035D02*
X1072919Y88412D01*
G01X1072296Y91013D02*
Y89035D01*
G01X1073300Y92017D02*
X1072296Y91013D01*
G01X1073300Y94600D02*
Y92017D01*
G01X1066429Y101471D02*
X1073300Y94600D01*
G01X1048427Y54052D02*
X1047637Y54842D01*
G01X1048427Y52954D02*
Y54052D01*
G01X1047637Y52164D02*
X1048427Y52954D01*
G01X1047637Y49551D02*
Y52164D01*
G01X1049360Y47828D02*
X1047637Y49551D01*
G01X1045100Y89299D02*
Y96897D01*
G01X1046231Y88168D02*
X1045100Y89299D01*
G01X1046231Y86731D02*
Y88168D01*
G01X1045555Y86055D02*
X1046231Y86731D01*
G01X1045555Y84135D02*
Y86055D01*
G01X1046546Y83144D02*
X1045555Y84135D01*
G01X1046546Y77756D02*
Y83144D01*
G01X1044992Y76202D02*
X1046546Y77756D01*
G01X1044992Y73035D02*
Y76202D01*
G01X1047095Y70932D02*
X1044992Y73035D01*
G01X1047095Y68023D02*
Y70932D01*
G01X1045700Y66628D02*
X1047095Y68023D01*
G01X1045700Y62699D02*
Y66628D01*
G01X1045028Y62027D02*
X1045700Y62699D01*
G01X1042200Y62027D02*
X1045028D01*
G01X1041400Y61227D02*
X1042200Y62027D01*
G01X1041400Y59627D02*
Y61227D01*
G01X1042200Y58827D02*
X1041400Y59627D01*
G01X1046576Y58827D02*
X1042200D01*
G01X1047637Y57766D02*
X1046576Y58827D01*
G01X1047637Y54842D02*
Y57766D01*
G01X1076128Y59816D02*
X1081102Y54842D01*
G01X1076128Y82692D02*
Y59816D01*
G01X1076571Y83135D02*
X1076128Y82692D01*
G01X1076571Y85360D02*
Y83135D01*
G01X1075457Y86474D02*
X1076571Y85360D01*
G01X1075457Y88224D02*
Y86474D01*
G01X1076457Y89224D02*
X1075457Y88224D01*
G01X1076457Y91042D02*
Y89224D01*
G01X1075300Y92199D02*
X1076457Y91042D01*
G01X1075300Y95600D02*
Y92199D01*
G01X1054331Y54245D02*
Y54857D01*
G01X1052668Y52582D02*
X1054331Y54245D01*
G01X1052668Y34348D02*
Y52582D01*
G01X1047200Y93781D02*
Y98186D01*
G01X1050307Y90674D02*
X1047200Y93781D01*
G01X1050307Y89340D02*
Y90674D01*
G01X1049000Y88033D02*
X1050307Y89340D01*
G01X1049000Y86330D02*
Y88033D01*
G01X1049991Y85339D02*
X1049000Y86330D01*
G01X1049991Y83443D02*
Y85339D01*
G01X1049000Y82452D02*
X1049991Y83443D01*
G01X1049000Y74813D02*
Y82452D01*
G01X1049368Y74445D02*
X1049000Y74813D01*
G01X1049368Y66994D02*
Y74445D01*
G01X1049373Y66971D02*
X1049368Y66994D01*
G01X1049373Y62966D02*
Y66971D01*
G01X1050550Y58050D02*
X1049373Y62966D01*
G01X1053743Y54857D02*
X1050550Y58050D01*
G01X1054331Y54857D02*
X1053743D01*
G01X1082827Y59827D02*
X1087795Y54859D01*
G01X1082827Y66670D02*
Y59827D01*
G01X1081344Y68153D02*
X1082827Y66670D01*
G01X1081344Y71163D02*
Y68153D01*
G01X1082808Y72627D02*
X1081344Y71163D01*
G01X1082808Y85740D02*
Y72627D01*
G01X1082579Y85969D02*
X1082808Y85740D01*
G01X1082579Y88479D02*
Y85969D01*
G01X1082947Y88847D02*
X1082579Y88479D01*
G01X1082947Y91101D02*
Y88847D01*
G01X1082261Y91787D02*
X1082947Y91101D01*
G01X1082261Y95139D02*
Y91787D01*
G01X1092864Y37583D02*
X1094490Y35957D01*
G01X1092864Y47607D02*
Y37583D01*
G01X1092300Y48970D02*
X1092864Y47607D01*
G01X1092300Y52600D02*
Y48970D01*
G01X1092864Y53164D02*
X1092300Y52600D01*
G01X1092864Y56436D02*
Y53164D01*
G01X1089419Y59881D02*
X1092864Y56436D01*
G01X1089419Y66981D02*
Y59881D01*
G01X1088900Y67500D02*
X1089419Y66981D01*
G01X1088900Y69200D02*
Y67500D01*
G01X1089800Y70100D02*
X1088900Y69200D01*
G01X1089800Y71900D02*
Y70100D01*
G01X1089436Y72264D02*
X1089800Y71900D01*
G01X1089436Y74636D02*
Y72264D01*
G01X1089900Y75100D02*
X1089436Y74636D01*
G01X1089900Y85700D02*
Y75100D01*
G01X1088866Y86734D02*
X1089900Y85700D01*
G01X1088866Y87866D02*
Y86734D01*
G01X1090100Y89100D02*
X1088866Y87866D01*
G01X1090100Y90700D02*
Y89100D01*
G01X1089060Y91740D02*
X1090100Y90700D01*
G01X1089060Y95349D02*
Y91740D01*
G01X1066281Y33074D02*
X1065217D01*
G01X1069457Y36995D02*
Y33006D01*
G01X1070083Y37621D02*
X1069457Y36995D01*
G01X1070083Y44425D02*
Y37621D01*
G01X1069457Y45051D02*
X1070083Y44425D01*
G01X1069457Y47877D02*
Y45051D01*
G01X1065990Y51344D02*
X1069457Y47877D01*
G01X1065990Y56310D02*
Y51344D01*
G01X1062508Y59792D02*
X1065990Y56310D01*
G01X1062508Y64508D02*
Y59792D01*
G01X1062764Y64764D02*
X1062508Y64508D01*
G01X1062764Y72269D02*
Y64764D01*
G01X1062634Y72399D02*
X1062764Y72269D01*
G01X1062634Y83635D02*
Y72399D01*
G01X1062823Y83824D02*
X1062634Y83635D01*
G01X1062823Y85825D02*
Y83824D01*
G01X1062569Y86079D02*
X1062823Y85825D01*
G01X1062569Y88569D02*
Y86079D01*
G01X1062823Y88823D02*
X1062569Y88569D01*
G01X1062823Y91077D02*
Y88823D01*
G01X1062500Y91400D02*
X1062823Y91077D01*
G01X1062500Y95800D02*
Y91400D01*
G01X1064371Y37698D02*
Y35957D01*
G01X1064987Y38314D02*
X1064371Y37698D01*
G01X1066296Y38314D02*
X1064987D01*
G01X1067200Y39218D02*
X1066296Y38314D01*
G01X1067200Y41649D02*
Y39218D01*
G01X1066721Y42128D02*
X1067200Y41649D01*
G01X1061751Y42128D02*
X1066721D01*
G01X1061251Y41628D02*
X1061751Y42128D01*
G01X1061251Y40673D02*
Y41628D01*
G01X1060751Y40173D02*
X1061251Y40673D01*
G01X1058797Y40173D02*
X1060751D01*
G01X1058131Y40839D02*
X1058797Y40173D01*
G01X1058131Y44237D02*
Y40839D01*
G01X1059143Y45249D02*
X1058131Y44237D01*
G01X1063401Y45249D02*
X1059143D01*
G01X1064371Y46219D02*
X1063401Y45249D01*
G01X1064371Y46922D02*
Y46219D01*
G01Y48887D02*
Y46922D01*
G01X1059305Y53953D02*
X1064371Y48887D01*
G01X1059305Y56347D02*
Y53953D01*
G01X1058695Y56957D02*
X1059305Y56347D01*
G01X1057243Y56957D02*
X1058695D01*
G01X1055944Y58256D02*
X1057243Y56957D01*
G01X1055944Y66631D02*
Y58256D01*
G01X1055800Y66775D02*
X1055944Y66631D01*
G01X1055800Y69988D02*
Y66775D01*
G01X1056130Y70318D02*
X1055800Y69988D01*
G01X1056130Y71810D02*
Y70318D01*
G01X1055966Y71974D02*
X1056130Y71810D01*
G01X1055966Y74767D02*
Y71974D01*
G01X1056300Y75101D02*
X1055966Y74767D01*
G01X1056300Y85175D02*
Y75101D01*
G01X1055800Y85675D02*
X1056300Y85175D01*
G01X1055800Y88888D02*
Y85675D01*
G01X1056130Y89218D02*
X1055800Y88888D01*
G01X1056130Y90710D02*
Y89218D01*
G01X1055800Y91040D02*
X1056130Y90710D01*
G01X1055800Y95590D02*
Y91040D01*
G01X1089421Y49600D02*
Y35079D01*
G01X1089413Y49608D02*
X1089421Y49600D01*
G01X1089413Y56683D02*
Y49608D01*
G01X1086166Y59930D02*
X1089413Y56683D01*
G01X1086166Y67266D02*
Y59930D01*
G01X1086400Y67500D02*
X1086166Y67266D01*
G01X1086400Y69500D02*
Y67500D01*
G01X1085600Y70300D02*
X1086400Y69500D01*
G01X1085600Y72000D02*
Y70300D01*
G01X1086100Y72500D02*
X1085600Y72000D01*
G01X1086100Y83000D02*
Y72500D01*
G01X1085600Y83500D02*
X1086100Y83000D01*
G01X1085600Y85500D02*
Y83500D01*
G01X1086500Y86400D02*
X1085600Y85500D01*
G01X1086500Y88500D02*
Y86400D01*
G01X1085700Y89300D02*
X1086500Y88500D01*
G01X1085700Y90800D02*
Y89300D01*
G01X1086300Y91400D02*
X1085700Y90800D01*
G01X1086300Y95280D02*
Y91400D01*
G01X1059411Y59817D02*
X1064371Y54857D01*
G01X1059411Y67296D02*
Y59817D01*
G01X1060100Y67985D02*
X1059411Y67296D01*
G01X1060100Y71709D02*
Y67985D01*
G01X1059401Y72408D02*
X1060100Y71709D01*
G01X1059401Y82361D02*
Y72408D01*
G01X1058847Y82915D02*
X1059401Y82361D01*
G01X1058847Y85747D02*
Y82915D01*
G01X1059528Y86428D02*
X1058847Y85747D01*
G01X1059528Y88420D02*
Y86428D01*
G01X1059152Y88796D02*
X1059528Y88420D01*
G01X1059152Y91352D02*
Y88796D01*
G01X1059561Y91761D02*
X1059152Y91352D01*
G01X1059561Y95839D02*
Y91761D01*
G01X1094464Y92786D02*
Y96426D01*
G01X1092297Y90619D02*
X1094464Y92786D01*
G01X1092297Y89350D02*
Y90619D01*
G01X1093470Y88177D02*
X1092297Y89350D01*
G01X1093470Y86575D02*
Y88177D01*
G01X1092174Y85279D02*
X1093470Y86575D01*
G01X1092174Y82264D02*
Y85279D01*
G01X1092820Y81618D02*
X1092174Y82264D01*
G01X1094107Y81618D02*
X1092820D01*
G01X1094717Y81008D02*
X1094107Y81618D01*
G01X1094717Y79618D02*
Y81008D01*
G01X1094107Y79008D02*
X1094717Y79618D01*
G01X1092626Y79008D02*
X1094107D01*
G01X1092015Y78397D02*
X1092626Y79008D01*
G01X1092015Y76033D02*
Y78397D01*
G01X1092882Y75166D02*
X1092015Y76033D01*
G01X1092882Y71450D02*
Y75166D01*
G01X1093492Y70840D02*
X1092882Y71450D01*
G01X1094190Y70840D02*
X1093492D01*
G01X1094800Y70230D02*
X1094190Y70840D01*
G01X1094800Y68840D02*
Y70230D01*
G01X1094190Y68230D02*
X1094800Y68840D01*
G01X1093492Y68230D02*
X1094190D01*
G01X1092882Y67620D02*
X1093492Y68230D01*
G01X1092882Y64725D02*
Y67620D01*
G01X1093492Y64115D02*
X1092882Y64725D01*
G01X1094232Y64115D02*
X1093492D01*
G01X1094842Y63505D02*
X1094232Y64115D01*
G01X1094842Y62115D02*
Y63505D01*
G01X1094232Y61505D02*
X1094842Y62115D01*
G01X1093492Y61505D02*
X1094232D01*
G01X1092882Y60895D02*
X1093492Y61505D01*
G01X1092882Y59418D02*
Y60895D01*
G01X1094488Y57812D02*
X1092882Y59418D01*
G01X1094488Y54859D02*
Y57812D01*
G01X1058763Y136236D02*
Y194050D01*
G01X1096440Y98559D02*
X1058763Y136236D01*
G01X1090375Y152325D02*
X1133591Y109109D01*
G01X1090375Y167469D02*
Y152325D01*
G01X1062200Y102300D02*
X1069200Y95300D01*
G01X1062200Y110161D02*
Y102300D01*
G01X1045357Y127004D02*
X1062200Y110161D01*
G01X1045357Y192972D02*
Y127004D01*
G01X1075400Y129264D02*
X1106074Y98590D01*
G01X1075400Y130735D02*
Y129264D01*
G01X1078600Y133935D02*
X1075400Y130735D01*
G01X1078600Y135193D02*
Y133935D01*
G01X1069498Y144295D02*
X1078600Y135193D01*
G01X1069498Y178501D02*
Y144295D01*
G01X1073300Y101100D02*
X1079587Y94813D01*
G01X1073300Y107550D02*
Y101100D01*
G01X1050858Y129992D02*
X1073300Y107550D01*
G01X1050858Y195652D02*
Y129992D01*
G01X1050668Y95500D02*
X1051811D01*
G01X1049483Y96685D02*
X1050668Y95500D01*
G01X1049483Y99017D02*
Y96685D01*
G01X1045571Y102929D02*
X1049483Y99017D01*
G01X1045571Y103791D02*
Y102929D01*
G01X1046472Y104692D02*
X1045571Y103791D01*
G01X1046472Y105400D02*
Y104692D01*
G01X1044973Y106899D02*
X1046472Y105400D01*
G01X1044265Y106899D02*
X1044973D01*
G01X1043364Y105998D02*
X1044265Y106899D01*
G01X1042502Y105998D02*
X1043364D01*
G01X1041157Y107343D02*
X1042502Y105998D01*
G01X1041157Y108205D02*
Y107343D01*
G01X1042903Y109951D02*
X1041157Y108205D01*
G01X1042903Y110708D02*
Y109951D01*
G01X1041429Y112182D02*
X1042903Y110708D01*
G01X1040720Y112182D02*
X1041429D01*
G01X1038950Y110412D02*
X1040720Y112182D01*
G01X1038088Y110412D02*
X1038950D01*
G01X1037104Y111396D02*
X1038088Y110412D01*
G01X1037104Y199996D02*
Y111396D01*
G01X1035835Y96465D02*
X1038721D01*
G01X1033886Y98414D02*
X1035835Y96465D01*
G01X1033886Y104970D02*
Y98414D01*
G01X1060200Y101400D02*
X1066396Y95204D01*
G01X1060200Y109331D02*
Y101400D01*
G01X1043556Y125975D02*
X1060200Y109331D01*
G01X1043556Y192984D02*
Y125975D01*
G01X1066429Y108761D02*
Y101471D01*
G01X1047522Y127668D02*
X1066429Y108761D01*
G01X1047522Y195410D02*
Y127668D01*
G01X1033744Y109272D02*
Y195798D01*
G01X1037238Y105778D02*
X1033744Y109272D01*
G01X1037238Y104856D02*
Y105778D01*
G01X1035552Y103170D02*
X1037238Y104856D01*
G01X1035552Y102339D02*
Y103170D01*
G01X1036683Y101208D02*
X1035552Y102339D01*
G01X1038116Y101208D02*
X1036683D01*
G01X1039181Y102273D02*
X1038116Y101208D01*
G01X1040313Y102273D02*
X1039181D01*
G01X1041444Y101142D02*
X1040313Y102273D01*
G01X1041444Y100010D02*
Y101142D01*
G01X1040211Y98777D02*
X1041444Y100010D01*
G01X1040211Y97595D02*
Y98777D01*
G01X1041292Y96514D02*
X1040211Y97595D01*
G01X1042474Y96514D02*
X1041292D01*
G01X1043509Y97549D02*
X1042474Y96514D01*
G01X1044448Y97549D02*
X1043509D01*
G01X1045100Y96897D02*
X1044448Y97549D01*
G01X1085306Y150195D02*
X1108046Y127455D01*
G01X1085306Y179831D02*
Y150195D01*
G01X1079770Y128429D02*
X1109674Y98525D01*
G01X1079770Y129221D02*
Y128429D01*
G01X1081280Y130731D02*
X1079770Y129221D01*
G01X1082072Y130731D02*
X1081280D01*
G01X1085156Y127647D02*
X1082072Y130731D01*
G01X1085948Y127647D02*
X1085156D01*
G01X1087419Y129118D02*
X1085948Y127647D01*
G01X1087419Y129910D02*
Y129118D01*
G01X1071998Y145331D02*
X1087419Y129910D01*
G01X1071998Y178498D02*
Y145331D01*
G01X1068500Y102400D02*
X1075300Y95600D01*
G01X1068500Y109520D02*
Y102400D01*
G01X1049145Y128875D02*
X1068500Y109520D01*
G01X1049145Y195507D02*
Y128875D01*
G01X1069435Y131543D02*
X1103600Y97378D01*
G01X1069435Y132335D02*
Y131543D01*
G01X1070775Y133675D02*
X1069435Y132335D01*
G01X1071567Y133675D02*
X1070775D01*
G01X1072455Y132787D02*
X1071567Y133675D01*
G01X1073465Y132787D02*
X1072455D01*
G01X1074718Y134040D02*
X1073465Y132787D01*
G01X1074718Y135050D02*
Y134040D01*
G01X1067274Y142494D02*
X1074718Y135050D01*
G01X1067274Y178774D02*
Y142494D01*
G01X1087875Y151226D02*
X1129200Y109901D01*
G01X1087875Y179774D02*
Y151226D01*
G01X1074498Y146367D02*
Y178501D01*
G01X1096683Y124182D02*
X1074498Y146367D01*
G01X1094421Y121919D02*
X1095488D01*
G01X1091641Y124699D02*
X1094421Y121919D01*
G01X1090849Y124699D02*
X1091641D01*
G01X1089628Y123478D02*
X1090849Y124699D01*
G01X1089628Y122686D02*
Y123478D01*
G01X1112441Y99873D02*
X1089628Y122686D01*
G01X1035327Y110059D02*
Y200166D01*
G01X1047200Y98186D02*
X1035327Y110059D01*
G01X1075300Y102100D02*
X1082261Y95139D01*
G01X1075300Y108380D02*
Y102100D01*
G01X1052414Y131266D02*
X1075300Y108380D01*
G01X1052414Y195555D02*
Y131266D01*
G01X1081500Y102909D02*
X1089060Y95349D01*
G01X1081500Y107840D02*
Y102909D01*
G01X1055600Y133740D02*
X1081500Y107840D01*
G01X1055600Y194366D02*
Y133740D01*
G01X1055800Y102500D02*
X1062500Y95800D01*
G01X1055800Y110901D02*
Y102500D01*
G01X1041634Y125067D02*
X1055800Y110901D01*
G01X1041634Y192547D02*
Y125067D01*
G01X1049000Y102390D02*
X1055800Y95590D01*
G01X1049000Y107700D02*
Y102390D01*
G01X1038614Y118086D02*
X1049000Y107700D01*
G01X1038614Y191891D02*
Y118086D01*
G01X1079400Y102180D02*
X1086300Y95280D01*
G01X1079400Y107110D02*
Y102180D01*
G01X1053961Y132549D02*
X1079400Y107110D01*
G01X1053961Y195531D02*
Y132549D01*
G01X1092875Y153425D02*
X1136091Y110209D01*
G01X1092875Y162336D02*
Y153425D01*
G01X1053600Y101800D02*
X1059561Y95839D01*
G01X1053600Y110075D02*
Y101800D01*
G01X1052807Y110868D02*
X1053600Y110075D01*
G01X1051640Y110868D02*
X1052807D01*
G01X1050752Y109980D02*
X1051640Y110868D01*
G01X1049622Y109980D02*
X1050752D01*
G01X1048489Y111113D02*
X1049622Y109980D01*
G01X1048489Y112243D02*
Y111113D01*
G01X1049494Y113247D02*
X1048489Y112243D01*
G01X1049494Y114377D02*
Y113247D01*
G01X1048361Y115510D02*
X1049494Y114377D01*
G01X1047231Y115510D02*
X1048361D01*
G01X1046226Y114506D02*
X1047231Y115510D01*
G01X1045096Y114506D02*
X1046226D01*
G01X1043963Y115639D02*
X1045096Y114506D01*
G01X1043963Y116769D02*
Y115639D01*
G01X1044968Y117773D02*
X1043963Y116769D01*
G01X1044968Y118903D02*
Y117773D01*
G01X1044077Y119794D02*
X1044968Y118903D01*
G01X1041304Y119794D02*
X1044077D01*
G01X1040124Y120974D02*
X1041304Y119794D01*
G01X1040124Y192316D02*
Y120974D01*
G01X1057225Y134945D02*
Y194172D01*
G01X1085761Y106409D02*
X1057225Y134945D01*
G01X1085761Y105277D02*
Y106409D01*
G01X1084608Y104124D02*
X1085761Y105277D01*
G01X1084608Y102992D02*
Y104124D01*
G01X1085739Y101861D02*
X1084608Y102992D01*
G01X1086871Y101861D02*
X1085739D01*
G01X1088024Y103014D02*
X1086871Y101861D01*
G01X1089156Y103014D02*
X1088024D01*
G01X1090287Y101883D02*
X1089156Y103014D01*
G01X1090287Y100751D02*
Y101883D01*
G01X1089134Y99598D02*
X1090287Y100751D01*
G01X1089134Y98466D02*
Y99598D01*
G01X1090124Y97476D02*
X1089134Y98466D01*
G01X1093414Y97476D02*
X1090124D01*
G01X1094464Y96426D02*
X1093414Y97476D01*
G01X1090985Y168079D02*
X1090375Y167469D01*
G01X1092140Y168079D02*
X1090985D01*
G01X1092700Y168639D02*
X1092140Y168079D01*
G01X1092700Y170629D02*
Y168639D01*
G01X1092140Y171189D02*
X1092700Y170629D01*
G01X1090985Y171189D02*
X1092140D01*
G01X1090375Y171799D02*
X1090985Y171189D01*
G01X1090375Y179774D02*
Y171799D01*
G01X1090318Y179831D02*
X1090375Y179774D01*
G01X1087818Y179831D02*
X1087875Y179774D01*
G01X1095578Y165039D02*
X1092875Y162336D01*
G01Y176219D02*
X1095578Y173516D01*
G01X1092875Y179774D02*
Y176219D01*
G01X1092818Y179831D02*
X1092875Y179774D01*
G01X1068816Y417842D02*
Y469042D01*
G01X1063800Y406826D02*
Y473230D01*
G01X1076316Y461051D02*
X1111244Y495979D01*
G01X1076316Y418521D02*
Y461051D01*
G01X1043800Y406684D02*
Y480353D01*
G01X1057800Y405358D02*
Y475826D01*
G01X1093926Y452214D02*
X1122225Y480513D01*
G01X1093926Y409681D02*
Y452214D01*
G01X1045800Y479634D02*
Y406935D01*
G01X1086416Y456780D02*
X1126600Y496964D01*
G01X1086416Y411022D02*
Y456780D01*
G01X1073816Y462094D02*
X1076616Y464894D01*
G01X1073816Y418511D02*
Y462094D01*
G01X1041800Y406612D02*
Y486180D01*
G01X1091426Y453250D02*
X1115088Y476912D01*
G01X1091426Y410424D02*
Y453250D01*
G01X1049800Y407615D02*
Y478476D01*
G01X1037800Y406629D02*
Y487840D01*
G01X1047800Y407132D02*
Y478968D01*
G01X1055800Y405734D02*
Y476600D01*
G01X1035800Y406737D02*
Y488670D01*
G01X1053800Y407669D02*
Y477262D01*
G01X1051800Y407687D02*
Y477868D01*
G01X1088916Y456516D02*
X1095354Y462954D01*
G01X1088916Y411535D02*
Y456516D01*
G01X1071316Y418081D02*
Y468093D01*
G01X1061800Y406100D02*
Y473892D01*
G01X1059800Y405805D02*
Y475109D01*
G01X1033800Y406734D02*
Y489158D01*
G01X1039800Y406540D02*
Y487010D01*
G01X1068816Y469042D02*
X1102982Y503208D01*
G01X1063800Y473230D02*
X1096405Y505835D01*
G01X1062500Y516500D02*
Y527700D01*
G01X1062900Y516100D02*
X1062500Y516500D01*
G01X1062900Y514600D02*
Y516100D01*
G01X1062500Y514200D02*
X1062900Y514600D01*
G01X1062500Y511400D02*
Y514200D01*
G01X1063100Y510800D02*
X1062500Y511400D01*
G01X1063100Y504651D02*
Y510800D01*
G01X1053893Y495444D02*
X1063100Y504651D01*
G01X1053893Y494582D02*
Y495444D01*
G01X1055481Y492994D02*
X1053893Y494582D01*
G01X1055481Y492112D02*
Y492994D01*
G01X1054497Y491128D02*
X1055481Y492112D01*
G01X1053656Y491128D02*
X1054497D01*
G01X1052048Y492736D02*
X1053656Y491128D01*
G01X1051185Y492736D02*
X1052048D01*
G01X1049744Y491295D02*
X1051185Y492736D01*
G01X1049744Y486297D02*
Y491295D01*
G01X1043800Y480353D02*
X1049744Y486297D01*
G01X1086127Y519673D02*
Y532873D01*
G01X1086300Y519500D02*
X1086127Y519673D01*
G01X1086300Y516900D02*
Y519500D01*
G01X1085900Y516500D02*
X1086300Y516900D01*
G01X1085900Y514400D02*
Y516500D01*
G01X1086300Y514000D02*
X1085900Y514400D01*
G01X1086300Y511700D02*
Y514000D01*
G01X1085936Y511336D02*
X1086300Y511700D01*
G01X1085936Y507684D02*
Y511336D01*
G01X1069830Y491578D02*
X1085936Y507684D01*
G01X1069830Y487856D02*
Y491578D01*
G01X1057800Y475826D02*
X1069830Y487856D01*
G01X1057700Y491534D02*
X1045800Y479634D01*
G01X1057700Y496422D02*
Y491534D01*
G01X1065400Y504122D02*
X1057700Y496422D01*
G01X1065400Y510700D02*
Y504122D01*
G01X1066500Y511800D02*
X1065400Y510700D01*
G01X1066500Y513900D02*
Y511800D01*
G01X1065900Y514500D02*
X1066500Y513900D01*
G01X1065900Y516400D02*
Y514500D01*
G01X1066300Y516800D02*
X1065900Y516400D01*
G01X1066300Y527600D02*
Y516800D01*
G01X1084535Y472813D02*
X1107322Y495600D01*
G01X1083405Y472813D02*
X1084535D01*
G01X1082237Y473981D02*
X1083405Y472813D01*
G01X1081106Y473981D02*
X1082237D01*
G01X1079973Y472848D02*
X1081106Y473981D01*
G01X1079973Y471718D02*
Y472848D01*
G01X1081142Y470549D02*
X1079973Y471718D01*
G01X1081142Y469420D02*
Y470549D01*
G01X1080009Y468287D02*
X1081142Y469420D01*
G01X1078879Y468287D02*
X1080009D01*
G01X1078029Y469137D02*
X1078879Y468287D01*
G01X1076872Y469137D02*
X1078029D01*
G01X1075739Y468004D02*
X1076872Y469137D01*
G01X1075739Y466900D02*
Y468004D01*
G01X1076616Y466023D02*
X1075739Y466900D01*
G01X1076616Y464894D02*
Y466023D01*
G01X1042490Y508490D02*
Y548792D01*
G01X1037600Y503600D02*
X1042490Y508490D01*
G01X1037600Y502400D02*
Y503600D01*
G01X1059800Y517300D02*
Y526800D01*
G01X1059100Y516600D02*
X1059800Y517300D01*
G01X1059100Y514200D02*
Y516600D01*
G01X1059600Y513700D02*
X1059100Y514200D01*
G01X1059600Y511500D02*
Y513700D01*
G01X1059189Y511089D02*
X1059600Y511500D01*
G01X1059189Y509401D02*
Y511089D01*
G01X1060407Y508183D02*
X1059189Y509401D01*
G01X1060407Y506456D02*
Y508183D01*
G01X1059129Y505178D02*
X1060407Y506456D01*
G01X1057244Y505178D02*
X1059129D01*
G01X1056051Y503985D02*
X1057244Y505178D01*
G01X1056051Y502611D02*
Y503985D01*
G01X1056575Y502087D02*
X1056051Y502611D01*
G01X1056575Y500955D02*
Y502087D01*
G01X1045905Y490285D02*
X1056575Y500955D01*
G01X1045905Y489153D02*
Y490285D01*
G01X1047613Y487445D02*
X1045905Y489153D01*
G01X1047613Y486313D02*
Y487445D01*
G01X1046482Y485182D02*
X1047613Y486313D01*
G01X1045350Y485182D02*
X1046482D01*
G01X1043642Y486890D02*
X1045350Y485182D01*
G01X1042510Y486890D02*
X1043642D01*
G01X1041800Y486180D02*
X1042510Y486890D01*
G01X1072700Y519600D02*
Y530400D01*
G01X1073000Y519300D02*
X1072700Y519600D01*
G01X1073000Y516800D02*
Y519300D01*
G01X1072500Y516300D02*
X1073000Y516800D01*
G01X1072500Y514400D02*
Y516300D01*
G01X1073200Y513700D02*
X1072500Y514400D01*
G01X1073200Y512200D02*
Y513700D01*
G01X1072255Y511255D02*
X1073200Y512200D01*
G01X1072255Y505319D02*
Y511255D01*
G01X1061830Y494894D02*
X1072255Y505319D01*
G01X1061830Y490506D02*
Y494894D01*
G01X1049800Y478476D02*
X1061830Y490506D01*
G01X1052658Y519642D02*
Y535258D01*
G01X1053000Y519300D02*
X1052658Y519642D01*
G01X1053000Y516900D02*
Y519300D01*
G01X1052300Y516200D02*
X1053000Y516900D01*
G01X1052300Y514400D02*
Y516200D01*
G01X1052900Y513800D02*
X1052300Y514400D01*
G01X1052900Y511800D02*
Y513800D01*
G01X1052400Y511300D02*
X1052900Y511800D01*
G01X1052400Y509387D02*
Y511300D01*
G01X1049228Y506215D02*
X1052400Y509387D01*
G01X1049228Y503973D02*
Y506215D01*
G01X1050900Y502301D02*
X1049228Y503973D01*
G01X1050900Y500940D02*
Y502301D01*
G01X1037800Y487840D02*
X1050900Y500940D01*
G01X1069163Y516937D02*
Y527563D01*
G01X1069543Y516557D02*
X1069163Y516937D01*
G01X1069543Y514343D02*
Y516557D01*
G01X1069102Y513902D02*
X1069543Y514343D01*
G01X1069102Y511598D02*
Y513902D01*
G01X1069470Y511230D02*
X1069102Y511598D01*
G01X1069470Y505363D02*
Y511230D01*
G01X1059830Y495723D02*
X1069470Y505363D01*
G01X1059830Y490998D02*
Y495723D01*
G01X1047800Y478968D02*
X1059830Y490998D01*
G01X1082821Y519721D02*
Y530179D01*
G01X1082524Y519424D02*
X1082821Y519721D01*
G01X1082524Y517176D02*
Y519424D01*
G01X1082972Y516728D02*
X1082524Y517176D01*
G01X1082972Y514372D02*
Y516728D01*
G01X1082500Y513900D02*
X1082972Y514372D01*
G01X1082500Y511500D02*
Y513900D01*
G01X1082888Y511112D02*
X1082500Y511500D01*
G01X1082888Y507465D02*
Y511112D01*
G01X1067830Y492407D02*
X1082888Y507465D01*
G01X1067830Y488630D02*
Y492407D01*
G01X1055800Y476600D02*
X1067830Y488630D01*
G01X1049352Y519552D02*
Y542674D01*
G01X1049100Y519300D02*
X1049352Y519552D01*
G01X1049100Y516900D02*
Y519300D01*
G01X1050100Y515900D02*
X1049100Y516900D01*
G01X1050100Y514700D02*
Y515900D01*
G01X1049100Y513700D02*
X1050100Y514700D01*
G01X1049100Y511700D02*
Y513700D01*
G01X1049600Y511200D02*
X1049100Y511700D01*
G01X1049600Y509416D02*
Y511200D01*
G01X1047228Y507044D02*
X1049600Y509416D01*
G01X1047228Y500098D02*
Y507044D01*
G01X1035800Y488670D02*
X1047228Y500098D01*
G01X1079397Y519703D02*
Y533103D01*
G01X1079735Y519365D02*
X1079397Y519703D01*
G01X1079735Y517135D02*
Y519365D01*
G01X1079000Y516400D02*
X1079735Y517135D01*
G01X1079000Y514700D02*
Y516400D01*
G01X1079600Y514100D02*
X1079000Y514700D01*
G01X1079600Y511400D02*
Y514100D01*
G01X1078600Y510400D02*
X1079600Y511400D01*
G01X1078600Y506006D02*
Y510400D01*
G01X1065830Y493236D02*
X1078600Y506006D01*
G01X1065830Y489292D02*
Y493236D01*
G01X1053800Y477262D02*
X1065830Y489292D01*
G01X1076122Y522234D02*
Y530451D01*
G01X1075328Y521440D02*
X1076122Y522234D01*
G01X1075328Y517772D02*
Y521440D01*
G01X1076951Y516149D02*
X1075328Y517772D01*
G01X1076951Y514521D02*
Y516149D01*
G01X1075520Y513090D02*
X1076951Y514521D01*
G01X1075520Y511830D02*
Y513090D01*
G01X1076500Y510850D02*
X1075520Y511830D01*
G01X1076500Y506735D02*
Y510850D01*
G01X1063830Y494065D02*
X1076500Y506735D01*
G01X1063830Y489898D02*
Y494065D01*
G01X1051800Y477868D02*
X1063830Y489898D01*
G01X1089491Y481369D02*
X1105100Y496978D01*
G01X1088492Y481369D02*
X1089491D01*
G01X1087108Y482753D02*
X1088492Y481369D01*
G01X1085976Y482753D02*
X1087108D01*
G01X1084882Y481659D02*
X1085976Y482753D01*
G01X1084882Y480527D02*
Y481659D01*
G01X1086100Y479309D02*
X1084882Y480527D01*
G01X1086100Y478077D02*
Y479309D01*
G01X1085069Y477046D02*
X1086100Y478077D01*
G01X1083837Y477046D02*
X1085069D01*
G01X1082619Y478264D02*
X1083837Y477046D01*
G01X1081487Y478264D02*
X1082619D01*
G01X1071316Y468093D02*
X1081487Y478264D01*
G01X1092848Y519552D02*
Y530548D01*
G01X1092941Y519459D02*
X1092848Y519552D01*
G01X1092941Y516941D02*
Y519459D01*
G01X1092688Y516688D02*
X1092941Y516941D01*
G01X1092688Y514112D02*
Y516688D01*
G01X1092941Y513859D02*
X1092688Y514112D01*
G01X1092941Y511641D02*
Y513859D01*
G01X1092200Y510900D02*
X1092941Y511641D01*
G01X1092200Y504292D02*
Y510900D01*
G01X1061800Y473892D02*
X1092200Y504292D01*
G01X1089418Y516682D02*
Y530682D01*
G01X1089900Y516200D02*
X1089418Y516682D01*
G01X1089900Y514400D02*
Y516200D01*
G01X1088881Y513381D02*
X1089900Y514400D01*
G01X1088881Y512019D02*
Y513381D01*
G01X1089980Y510920D02*
X1088881Y512019D01*
G01X1089980Y508899D02*
Y510920D01*
G01X1071830Y490749D02*
X1089980Y508899D01*
G01X1071830Y487139D02*
Y490749D01*
G01X1059800Y475109D02*
X1071830Y487139D01*
G01X1045922Y518662D02*
Y529724D01*
G01X1044941Y517681D02*
X1045922Y518662D01*
G01X1044941Y515259D02*
Y517681D01*
G01X1046606Y513594D02*
X1044941Y515259D01*
G01X1046606Y512006D02*
Y513594D01*
G01X1045100Y510500D02*
X1046606Y512006D01*
G01X1045100Y508002D02*
Y510500D01*
G01X1042759Y505661D02*
X1045100Y508002D01*
G01X1042759Y504529D02*
Y505661D01*
G01X1045228Y502060D02*
X1042759Y504529D01*
G01X1045228Y500928D02*
Y502060D01*
G01X1044097Y499797D02*
X1045228Y500928D01*
G01X1042965Y499797D02*
X1044097D01*
G01X1040585Y502177D02*
X1042965Y499797D01*
G01X1039877Y502177D02*
X1040585D01*
G01X1038322Y500622D02*
X1039877Y502177D01*
G01X1038322Y499914D02*
Y500622D01*
G01X1040702Y497534D02*
X1038322Y499914D01*
G01X1040702Y496402D02*
Y497534D01*
G01X1039571Y495271D02*
X1040702Y496402D01*
G01X1038439Y495271D02*
X1039571D01*
G01X1036079Y497631D02*
X1038439Y495271D01*
G01X1035129Y497631D02*
X1036079D01*
G01X1033800Y496302D02*
X1035129Y497631D01*
G01X1033800Y495188D02*
Y496302D01*
G01X1035844Y493144D02*
X1033800Y495188D01*
G01X1035844Y491202D02*
Y493144D01*
G01X1033800Y489158D02*
X1035844Y491202D01*
G01X1054747Y525796D02*
X1055957Y527006D01*
G01X1054747Y524189D02*
Y525796D01*
G01X1055551Y523385D02*
X1054747Y524189D01*
G01X1057453Y523385D02*
X1055551D01*
G01X1058063Y522775D02*
X1057453Y523385D01*
G01X1058063Y521385D02*
Y522775D01*
G01X1057453Y520775D02*
X1058063Y521385D01*
G01X1055825Y520775D02*
X1057453D01*
G01X1055215Y520165D02*
X1055825Y520775D01*
G01X1055215Y517485D02*
Y520165D01*
G01X1056200Y516500D02*
X1055215Y517485D01*
G01X1056200Y514300D02*
Y516500D01*
G01X1055800Y513900D02*
X1056200Y514300D01*
G01X1055800Y511600D02*
Y513900D01*
G01X1057100Y510300D02*
X1055800Y511600D01*
G01X1057100Y508288D02*
Y510300D01*
G01X1055912Y507100D02*
X1057100Y508288D01*
G01X1052942Y507100D02*
X1055912D01*
G01X1051502Y505660D02*
X1052942Y507100D01*
G01X1051502Y504528D02*
Y505660D01*
G01X1052900Y503130D02*
X1051502Y504528D01*
G01X1052900Y500111D02*
Y503130D01*
G01X1048994Y496205D02*
X1052900Y500111D01*
G01X1048995Y496205D02*
X1048994D01*
G01X1039800Y487010D02*
X1048995Y496205D01*
G01X1094488Y574755D02*
X1094490Y574757D01*
G01X1094488Y569712D02*
Y574755D01*
G01X1096750Y567450D02*
X1094488Y569712D01*
G01X1064371Y572633D02*
Y574757D01*
G01X1064369Y572631D02*
X1064371Y572633D01*
G01X1065984Y571016D02*
X1064369Y572631D01*
G01X1065984Y549535D02*
Y571016D01*
G01X1064371Y547922D02*
X1065984Y549535D01*
G01X1064371Y545236D02*
Y547922D01*
G01X1062634Y543499D02*
X1064371Y545236D01*
G01X1062634Y532834D02*
Y543499D01*
G01X1062500Y532700D02*
X1062634Y532834D01*
G01X1062500Y530600D02*
Y532700D01*
G01X1062737Y530363D02*
X1062500Y530600D01*
G01X1062737Y527937D02*
Y530363D01*
G01X1062500Y527700D02*
X1062737Y527937D01*
G01X1092700Y565034D02*
X1094488Y566822D01*
G01X1092700Y557400D02*
Y565034D01*
G01X1092856Y557244D02*
X1092700Y557400D01*
G01X1092856Y554856D02*
Y557244D01*
G01X1089418Y551418D02*
X1092856Y554856D01*
G01X1089418Y546818D02*
Y551418D01*
G01X1086083Y543483D02*
X1089418Y546818D01*
G01X1086083Y532917D02*
Y543483D01*
G01X1086127Y532873D02*
X1086083Y532917D01*
G01X1066006Y527894D02*
X1066300Y527600D01*
G01X1066006Y535690D02*
Y527894D01*
G01X1065998Y535698D02*
X1066006Y535690D01*
G01X1065998Y543198D02*
Y535698D01*
G01X1069377Y546577D02*
X1065998Y543198D01*
G01X1069377Y549223D02*
Y546577D01*
G01X1069200Y549400D02*
X1069377Y549223D01*
G01X1069200Y552738D02*
Y549400D01*
G01X1070289Y553827D02*
X1069200Y552738D01*
G01X1071539Y553827D02*
X1070289D01*
G01X1072728Y555016D02*
X1071539Y553827D01*
G01X1072728Y565126D02*
Y555016D01*
G01X1074409Y566807D02*
X1072728Y565126D01*
G01X1044290Y574755D02*
X1044292Y574757D01*
G01X1044290Y572310D02*
Y574755D01*
G01X1046300Y570300D02*
X1044290Y572310D01*
G01X1046300Y568700D02*
Y570300D01*
G01X1045400Y567800D02*
X1046300Y568700D01*
G01X1045400Y557800D02*
Y567800D01*
G01X1046003Y557197D02*
X1045400Y557800D01*
G01X1046003Y554803D02*
Y557197D01*
G01X1044290Y553090D02*
X1046003Y554803D01*
G01X1044290Y550592D02*
Y553090D01*
G01X1042490Y548792D02*
X1044290Y550592D01*
G01X1062708Y554194D02*
X1064371Y555857D01*
G01X1062708Y546908D02*
Y554194D01*
G01X1059401Y543601D02*
X1062708Y546908D01*
G01X1059401Y535799D02*
Y543601D01*
G01X1059600Y535600D02*
X1059401Y535799D01*
G01X1059600Y530700D02*
Y535600D01*
G01X1059387Y530487D02*
X1059600Y530700D01*
G01X1059387Y527213D02*
Y530487D01*
G01X1059800Y526800D02*
X1059387Y527213D01*
G01X1079479Y565184D02*
X1081102Y566807D01*
G01X1079479Y555023D02*
Y565184D01*
G01X1075700Y551244D02*
X1079479Y555023D01*
G01X1075700Y549400D02*
Y551244D01*
G01X1076136Y548964D02*
X1075700Y549400D01*
G01X1076136Y546836D02*
Y548964D01*
G01X1072684Y543384D02*
X1076136Y546836D01*
G01X1072684Y535606D02*
Y543384D01*
G01X1073100Y535190D02*
X1072684Y535606D01*
G01X1073100Y530800D02*
Y535190D01*
G01X1072700Y530400D02*
X1073100Y530800D01*
G01X1056763Y566807D02*
X1057677D01*
G01X1056088Y566132D02*
X1056763Y566807D01*
G01X1056088Y565044D02*
Y566132D01*
G01X1056698Y564434D02*
X1056088Y565044D01*
G01X1061417Y564434D02*
X1056698D01*
G01X1062131Y563720D02*
X1061417Y564434D01*
G01X1062131Y560282D02*
Y563720D01*
G01X1061490Y559641D02*
X1062131Y560282D01*
G01X1058886Y559641D02*
X1061490D01*
G01X1058276Y560251D02*
X1058886Y559641D01*
G01X1058276Y561506D02*
Y560251D01*
G01X1057719Y562063D02*
X1058276Y561506D01*
G01X1056757Y562063D02*
X1057719D01*
G01X1055981Y561287D02*
X1056757Y562063D01*
G01X1055981Y556652D02*
Y561287D01*
G01X1056791Y555842D02*
X1055981Y556652D01*
G01X1057677Y555842D02*
X1056791D01*
G01X1057677Y554398D02*
Y555842D01*
G01X1055949Y552670D02*
X1057677Y554398D01*
G01X1055949Y546449D02*
Y552670D01*
G01X1052700Y543200D02*
X1055949Y546449D01*
G01X1052700Y535300D02*
Y543200D01*
G01X1052658Y535258D02*
X1052700Y535300D01*
G01X1074409Y553262D02*
Y555842D01*
G01X1073600Y552453D02*
X1074409Y553262D01*
G01X1073600Y549800D02*
Y552453D01*
G01X1072698Y548898D02*
X1073600Y549800D01*
G01X1072698Y546898D02*
Y548898D01*
G01X1069437Y543637D02*
X1072698Y546898D01*
G01X1069437Y535563D02*
Y543637D01*
G01X1069200Y535326D02*
X1069437Y535563D01*
G01X1069200Y530200D02*
Y535326D01*
G01X1069437Y529963D02*
X1069200Y530200D01*
G01X1069437Y527837D02*
Y529963D01*
G01X1069163Y527563D02*
X1069437Y527837D01*
G01X1087795Y550795D02*
Y555859D01*
G01X1086112Y549112D02*
X1087795Y550795D01*
G01X1086112Y546812D02*
Y549112D01*
G01X1082835Y543535D02*
X1086112Y546812D01*
G01X1082835Y535827D02*
Y543535D01*
G01X1081381Y534373D02*
X1082835Y535827D01*
G01X1081381Y531619D02*
Y534373D01*
G01X1082821Y530179D02*
X1081381Y531619D01*
G01X1054331Y555857D02*
Y566822D01*
G01Y554445D02*
Y555857D01*
G01X1052673Y552787D02*
X1054331Y554445D01*
G01X1052673Y545995D02*
Y552787D01*
G01X1049352Y542674D02*
X1052673Y545995D01*
G01X1086156Y565181D02*
X1087797Y566822D01*
G01X1086156Y554856D02*
Y565181D01*
G01X1085333Y554033D02*
X1086156Y554856D01*
G01X1085333Y551343D02*
Y554033D01*
G01X1082821Y548831D02*
X1085333Y551343D01*
G01X1082821Y546521D02*
Y548831D01*
G01X1079368Y543068D02*
X1082821Y546521D01*
G01X1079368Y533132D02*
Y543068D01*
G01X1079397Y533103D02*
X1079368Y533132D01*
G01X1081102Y553164D02*
Y555842D01*
G01X1079384Y551446D02*
X1081102Y553164D01*
G01X1079384Y547184D02*
Y551446D01*
G01X1076122Y543922D02*
X1079384Y547184D01*
G01X1076122Y535145D02*
Y543922D01*
G01X1076620Y534647D02*
X1076122Y535145D01*
G01X1076620Y530949D02*
Y534647D01*
G01X1076122Y530451D02*
X1076620Y530949D01*
G01X1094488Y545388D02*
Y547922D01*
G01X1092871Y543771D02*
X1094488Y545388D01*
G01X1092871Y530571D02*
Y543771D01*
G01X1092848Y530548D02*
X1092871Y530571D01*
G01X1094488Y553164D02*
Y555859D01*
G01X1092871Y551547D02*
X1094488Y553164D01*
G01X1092871Y546771D02*
Y551547D01*
G01X1089403Y543303D02*
X1092871Y546771D01*
G01X1089403Y530697D02*
Y543303D01*
G01X1089418Y530682D02*
X1089403Y530697D01*
G01X1047637Y555842D02*
Y566807D01*
G01Y550863D02*
Y555842D01*
G01X1045837Y549063D02*
X1047637Y550863D01*
G01X1045837Y547053D02*
Y549063D01*
G01X1045929Y546961D02*
X1045837Y547053D01*
G01X1045929Y532971D02*
Y546961D01*
G01X1046193Y532707D02*
X1045929Y532971D01*
G01X1046193Y529995D02*
Y532707D01*
G01X1045922Y529724D02*
X1046193Y529995D01*
G01X1064371Y559640D02*
Y566822D01*
G01X1062686Y557955D02*
X1064371Y559640D01*
G01X1060594Y557955D02*
X1062686D01*
G01X1059291Y556652D02*
X1060594Y557955D01*
G01X1059291Y554143D02*
Y556652D01*
G01X1059500Y553934D02*
X1059291Y554143D01*
G01X1059500Y549200D02*
Y553934D01*
G01X1059387Y549087D02*
X1059500Y549200D01*
G01X1059387Y546587D02*
Y549087D01*
G01X1056600Y543800D02*
X1059387Y546587D01*
G01X1056600Y538700D02*
Y543800D01*
G01X1055964Y538064D02*
X1056600Y538700D01*
G01X1055964Y535864D02*
Y538064D01*
G01X1055553Y535453D02*
X1055964Y535864D01*
G01X1055553Y531047D02*
Y535453D01*
G01X1055957Y530643D02*
X1055553Y531047D01*
G01X1055957Y527006D02*
Y530643D01*
G01X1142902Y28849D02*
Y35049D01*
G01X1142885Y28832D02*
X1142902Y28849D01*
G01X1142885Y26453D02*
Y28832D01*
G01X1140800Y24368D02*
X1142885Y26453D01*
G01X1140800Y17262D02*
Y24368D01*
G01X1139052Y15514D02*
X1140800Y17262D01*
G01X1139052Y14100D02*
Y15514D01*
G01X1141038Y12114D02*
X1139052Y14100D01*
G01X1101181Y29453D02*
Y27899D01*
G01X1103428Y31700D02*
X1101181Y29453D01*
G01X1104652Y31700D02*
X1103428D01*
G01X1106228Y33276D02*
X1104652Y31700D01*
G01X1149252Y25853D02*
Y114456D01*
G01X1146792Y23393D02*
X1149252Y25853D01*
G01X1146792Y16692D02*
Y23393D01*
G01X1145469Y15369D02*
X1146792Y16692D01*
G01X1145469Y13976D02*
Y15369D01*
G01X1147331Y12114D02*
X1145469Y13976D01*
G01X1145402Y29597D02*
Y34203D01*
G01X1146552Y28447D02*
X1145402Y29597D01*
G01X1146552Y26653D02*
Y28447D01*
G01X1144685Y24786D02*
X1146552Y26653D01*
G01X1144685Y17157D02*
Y24786D01*
G01X1125853Y29146D02*
X1124606Y27899D01*
G01X1125853Y30400D02*
Y29146D01*
G01X1127153Y31700D02*
X1125853Y30400D01*
G01X1128153Y31700D02*
X1127153D01*
G01X1129953Y33500D02*
X1128153Y31700D01*
G01X1111153Y31900D02*
X1112609Y33356D01*
G01X1109753Y31900D02*
X1111153D01*
G01X1107874Y30021D02*
X1109753Y31900D01*
G01X1107874Y27899D02*
Y30021D01*
G01X1139052Y29347D02*
Y34299D01*
G01X1139952Y28447D02*
X1139052Y29347D01*
G01X1139952Y27216D02*
Y28447D01*
G01X1137992Y25256D02*
X1139952Y27216D01*
G01X1137992Y17157D02*
Y25256D01*
G01X1132546Y29146D02*
X1131299Y27899D01*
G01X1132546Y30400D02*
Y29146D01*
G01X1133846Y31700D02*
X1132546Y30400D01*
G01X1134846Y31700D02*
X1133846D01*
G01X1136646Y33500D02*
X1134846Y31700D01*
G01X1096440Y67401D02*
Y98559D01*
G01X1096600Y67241D02*
X1096440Y67401D01*
G01X1096600Y53760D02*
Y67241D01*
G01X1142735Y91581D02*
Y105961D01*
G01X1142838Y91478D02*
X1142735Y91581D01*
G01X1142838Y86400D02*
Y91478D01*
G01X1142552Y86114D02*
X1142838Y86400D01*
G01X1142552Y73199D02*
Y86114D01*
G01X1142902Y72849D02*
X1142552Y73199D01*
G01X1142902Y66649D02*
Y72849D01*
G01X1142652Y66399D02*
X1142902Y66649D01*
G01X1142652Y53864D02*
Y66399D01*
G01X1142902Y53614D02*
X1142652Y53864D01*
G01X1142902Y48664D02*
Y53614D01*
G01X1142552Y48314D02*
X1142902Y48664D01*
G01X1142552Y35399D02*
Y48314D01*
G01X1142902Y35049D02*
X1142552Y35399D01*
G01X1133078Y35667D02*
X1134645Y34100D01*
G01X1133078Y36868D02*
Y35667D01*
G01X1131720Y38226D02*
X1133078Y36868D01*
G01X1131720Y39599D02*
Y38226D01*
G01X1132920Y40799D02*
X1131720Y39599D01*
G01X1132920Y41925D02*
Y40799D01*
G01X1131720Y43125D02*
X1132920Y41925D01*
G01X1131720Y44700D02*
Y43125D01*
G01X1133520Y46500D02*
X1131720Y44700D01*
G01X1133520Y47558D02*
Y46500D01*
G01X1130178Y50900D02*
X1133520Y47558D01*
G01X1130178Y53836D02*
Y50900D01*
G01X1131299Y54957D02*
X1130178Y53836D01*
G01X1131299Y55577D02*
Y54957D01*
G01X1133541Y57819D02*
X1131299Y55577D01*
G01X1133541Y66003D02*
Y57819D01*
G01X1132741Y66803D02*
X1133541Y66003D01*
G01X1132741Y72541D02*
Y66803D01*
G01X1133241Y73041D02*
X1132741Y72541D01*
G01X1133241Y85818D02*
Y73041D01*
G01X1132641Y86418D02*
X1133241Y85818D01*
G01X1132641Y91118D02*
Y86418D01*
G01X1133591Y92068D02*
X1132641Y91118D01*
G01X1133591Y96105D02*
Y92068D01*
G01X1102377Y51414D02*
X1104227Y49564D01*
G01X1102377Y53178D02*
Y51414D01*
G01X1103900Y54701D02*
X1102377Y53178D01*
G01X1103900Y62301D02*
Y54701D01*
G01X1106074Y64475D02*
X1103900Y62301D01*
G01X1106074Y66636D02*
Y64475D01*
G01X1106091Y66653D02*
X1106074Y66636D01*
G01X1106091Y72853D02*
Y66653D01*
G01X1105741Y73203D02*
X1106091Y72853D01*
G01X1105741Y86118D02*
Y73203D01*
G01X1106091Y86468D02*
X1105741Y86118D01*
G01X1106091Y89857D02*
Y86468D01*
G01X1106077Y89871D02*
X1106091Y89857D01*
G01X1106077Y91102D02*
Y89871D01*
G01X1106074Y91105D02*
X1106077Y91102D01*
G01X1106074Y98590D02*
Y91105D01*
G01X1106228Y34900D02*
Y33276D01*
G01X1105453Y35675D02*
X1106228Y34900D01*
G01X1105453Y48348D02*
Y35675D01*
G01X1104237Y49564D02*
X1105453Y48348D01*
G01X1104227Y49564D02*
X1104237D01*
G01X1146752Y92264D02*
Y104796D01*
G01X1145402Y90914D02*
X1146752Y92264D01*
G01X1145402Y86714D02*
Y90914D01*
G01X1146752Y85364D02*
X1145402Y86714D01*
G01X1146752Y73453D02*
Y85364D01*
G01X1145402Y72103D02*
X1146752Y73453D01*
G01X1145402Y67397D02*
Y72103D01*
G01X1146752Y66047D02*
X1145402Y67397D01*
G01X1146752Y54452D02*
Y66047D01*
G01X1145402Y53102D02*
X1146752Y54452D01*
G01X1145402Y48914D02*
Y53102D01*
G01X1146752Y47564D02*
X1145402Y48914D01*
G01X1146752Y35553D02*
Y47564D01*
G01X1145402Y34203D02*
X1146752Y35553D01*
G01X1126478Y35574D02*
X1127952Y34100D01*
G01X1126478Y36668D02*
Y35574D01*
G01X1125045Y38101D02*
X1126478Y36668D01*
G01X1125045Y39324D02*
Y38101D01*
G01X1126545Y40824D02*
X1125045Y39324D01*
G01X1126545Y42176D02*
Y40824D01*
G01X1125045Y43676D02*
X1126545Y42176D01*
G01X1125045Y44799D02*
Y43676D01*
G01X1126720Y46474D02*
X1125045Y44799D01*
G01X1126720Y47859D02*
Y46474D01*
G01X1123678Y50901D02*
X1126720Y47859D01*
G01X1123678Y54029D02*
Y50901D01*
G01X1124606Y54957D02*
X1123678Y54029D01*
G01X1123847Y55716D02*
X1124606Y54957D01*
G01X1123847Y56848D02*
Y55716D01*
G01X1126406Y59407D02*
X1123847Y56848D01*
G01X1126406Y60894D02*
Y59407D01*
G01X1125600Y61700D02*
X1126406Y60894D01*
G01X1125600Y63500D02*
Y61700D01*
G01X1126406Y64306D02*
X1125600Y63500D01*
G01X1126406Y66538D02*
Y64306D01*
G01X1126041Y66903D02*
X1126406Y66538D01*
G01X1126041Y72541D02*
Y66903D01*
G01X1126841Y73341D02*
X1126041Y72541D01*
G01X1126841Y85718D02*
Y73341D01*
G01X1126041Y86518D02*
X1126841Y85718D01*
G01X1126041Y91218D02*
Y86518D01*
G01X1126441Y91618D02*
X1126041Y91218D01*
G01X1126441Y93659D02*
Y91618D01*
G01X1125500Y94600D02*
X1126441Y93659D01*
G01X1106600Y56231D02*
X1107874Y54957D01*
G01X1106600Y61879D02*
Y56231D01*
G01X1109741Y65020D02*
X1106600Y61879D01*
G01X1109741Y66259D02*
Y65020D01*
G01X1108591Y67409D02*
X1109741Y66259D01*
G01X1108591Y71991D02*
Y67409D01*
G01X1109941Y73341D02*
X1108591Y71991D01*
G01X1109941Y85368D02*
Y73341D01*
G01X1108591Y86718D02*
X1109941Y85368D01*
G01X1108591Y90928D02*
Y86718D01*
G01X1109674Y92011D02*
X1108591Y90928D01*
G01X1109674Y98525D02*
Y92011D01*
G01X1109653Y34567D02*
X1110520Y33700D01*
G01X1109653Y36868D02*
Y34567D01*
G01X1108020Y38501D02*
X1109653Y36868D01*
G01X1108020Y39800D02*
Y38501D01*
G01X1109370Y41150D02*
X1108020Y39800D01*
G01X1109370Y42050D02*
Y41150D01*
G01X1108120Y43300D02*
X1109370Y42050D01*
G01X1108120Y44499D02*
Y43300D01*
G01X1109653Y46032D02*
X1108120Y44499D01*
G01X1109653Y48000D02*
Y46032D01*
G01X1106753Y50900D02*
X1109653Y48000D01*
G01X1106753Y53836D02*
Y50900D01*
G01X1107874Y54957D02*
X1106753Y53836D01*
G01X1101181Y62682D02*
Y54957D01*
G01X1102981Y64482D02*
X1101181Y62682D01*
G01X1102981Y66419D02*
Y64482D01*
G01X1102241Y67159D02*
X1102981Y66419D01*
G01X1102241Y72103D02*
Y67159D01*
G01X1103241Y73103D02*
X1102241Y72103D01*
G01X1103241Y85418D02*
Y73103D01*
G01X1102241Y86418D02*
X1103241Y85418D01*
G01X1102241Y91218D02*
Y86418D01*
G01X1103600Y92577D02*
X1102241Y91218D01*
G01X1103600Y93300D02*
Y92577D01*
G01X1102300Y94600D02*
X1103600Y93300D01*
G01X1103053Y34788D02*
X1104141Y33700D01*
G01X1103053Y36668D02*
Y34788D01*
G01X1101620Y38101D02*
X1103053Y36668D01*
G01X1101620Y39300D02*
Y38101D01*
G01X1103120Y40800D02*
X1101620Y39300D01*
G01X1103120Y42000D02*
Y40800D01*
G01X1101670Y43450D02*
X1103120Y42000D01*
G01X1101670Y44849D02*
Y43450D01*
G01X1103053Y46232D02*
X1101670Y44849D01*
G01X1103053Y48101D02*
Y46232D01*
G01X1100253Y50901D02*
X1103053Y48101D01*
G01X1100253Y54029D02*
Y50901D01*
G01X1101181Y54957D02*
X1100253Y54029D01*
G01X1129953Y34900D02*
Y33500D01*
G01X1129341Y35512D02*
X1129953Y34900D01*
G01X1129341Y48525D02*
Y35512D01*
G01X1127952Y49914D02*
X1129341Y48525D01*
G01X1126041Y51825D02*
X1127952Y49914D01*
G01X1126041Y53610D02*
Y51825D01*
G01X1127591Y55160D02*
X1126041Y53610D01*
G01X1127591Y55732D02*
Y55160D01*
G01X1129499Y57640D02*
X1127591Y55732D01*
G01X1129499Y66511D02*
Y57640D01*
G01X1130241Y67253D02*
X1129499Y66511D01*
G01X1130241Y72159D02*
Y67253D01*
G01X1129341Y73059D02*
X1130241Y72159D01*
G01X1129341Y85718D02*
Y73059D01*
G01X1130141Y86518D02*
X1129341Y85718D01*
G01X1130141Y91018D02*
Y86518D01*
G01X1129499Y91660D02*
X1130141Y91018D01*
G01X1129499Y94501D02*
Y91660D01*
G01X1128000Y96000D02*
X1129499Y94501D01*
G01X1112441Y64442D02*
Y99873D01*
G01X1109941Y61942D02*
X1112441Y64442D01*
G01X1109941Y54542D02*
Y61942D01*
G01X1108447Y53048D02*
X1109941Y54542D01*
G01X1108447Y51987D02*
Y53048D01*
G01X1110520Y49914D02*
X1108447Y51987D01*
G01X1111993Y48441D02*
X1110520Y49914D01*
G01X1111993Y35316D02*
Y48441D01*
G01X1112609Y34700D02*
X1111993Y35316D01*
G01X1112609Y33356D02*
Y34700D01*
G01X1140100Y92262D02*
Y105200D01*
G01X1139052Y91214D02*
X1140100Y92262D01*
G01X1139052Y86414D02*
Y91214D01*
G01X1140052Y85414D02*
X1139052Y86414D01*
G01X1140052Y73099D02*
Y85414D01*
G01X1139052Y72099D02*
X1140052Y73099D01*
G01X1139052Y67147D02*
Y72099D01*
G01X1139952Y66247D02*
X1139052Y67147D01*
G01X1139952Y54314D02*
Y66247D01*
G01X1139052Y53414D02*
X1139952Y54314D01*
G01X1139052Y48614D02*
Y53414D01*
G01X1140052Y47614D02*
X1139052Y48614D01*
G01X1140052Y35299D02*
Y47614D01*
G01X1139052Y34299D02*
X1140052Y35299D01*
G01X1136646Y34900D02*
Y33500D01*
G01X1136034Y35512D02*
X1136646Y34900D01*
G01X1136034Y48525D02*
Y35512D01*
G01X1134645Y49914D02*
X1136034Y48525D01*
G01X1132741Y51818D02*
X1134645Y49914D01*
G01X1132741Y53418D02*
Y51818D01*
G01X1136091Y56768D02*
X1132741Y53418D01*
G01X1136091Y66503D02*
Y56768D01*
G01X1136641Y67053D02*
X1136091Y66503D01*
G01X1136641Y72459D02*
Y67053D01*
G01X1136041Y73059D02*
X1136641Y72459D01*
G01X1136041Y85918D02*
Y73059D01*
G01X1136741Y86618D02*
X1136041Y85918D01*
G01X1136741Y91018D02*
Y86618D01*
G01X1136091Y91668D02*
X1136741Y91018D01*
G01X1136091Y110209D02*
Y91668D01*
G01X1115829Y148523D02*
X1101800Y162552D01*
G01X1115829Y147391D02*
Y148523D01*
G01X1114365Y145927D02*
X1115829Y147391D01*
G01X1114365Y145135D02*
Y145927D01*
G01X1115836Y143664D02*
X1114365Y145135D01*
G01X1116628Y143664D02*
X1115836D01*
G01X1118092Y145128D02*
X1116628Y143664D01*
G01X1119224Y145128D02*
X1118092D01*
G01X1120432Y143920D02*
X1119224Y145128D01*
G01X1120432Y142568D02*
Y143920D01*
G01X1118000Y140136D02*
X1120432Y142568D01*
G01X1118000Y138636D02*
Y140136D01*
G01X1142600Y114036D02*
X1118000Y138636D01*
G01X1142600Y111300D02*
Y114036D01*
G01X1142900Y111000D02*
X1142600Y111300D01*
G01X1142900Y106126D02*
Y111000D01*
G01X1142735Y105961D02*
X1142900Y106126D01*
G01X1132791Y96905D02*
X1133591Y96105D01*
G01X1131710Y96905D02*
X1132791D01*
G01X1131150Y97465D02*
X1131710Y96905D01*
G01X1131150Y99545D02*
Y97465D01*
G01X1131710Y100105D02*
X1131150Y99545D01*
G01X1132791Y100105D02*
X1131710D01*
G01X1133591Y100905D02*
X1132791Y100105D01*
G01X1133591Y109109D02*
Y100905D01*
G01X1159052Y139200D02*
X1124492Y173760D01*
G01X1137619Y133805D02*
X1106800Y164624D01*
G01X1137619Y132081D02*
Y133805D01*
G01X1139290Y130410D02*
X1137619Y132081D01*
G01X1141014Y130410D02*
X1139290D01*
G01X1142300Y129124D02*
X1141014Y130410D01*
G01X1142300Y127900D02*
Y129124D01*
G01X1140000Y125600D02*
X1142300Y127900D01*
G01X1140000Y123708D02*
Y125600D01*
G01X1149252Y114456D02*
X1140000Y123708D01*
G01X1124078Y143810D02*
X1104300Y163588D01*
G01X1124078Y142678D02*
Y143810D01*
G01X1122046Y140646D02*
X1124078Y142678D01*
G01X1122046Y139854D02*
Y140646D01*
G01X1123705Y138195D02*
X1122046Y139854D01*
G01X1124497Y138195D02*
X1123705D01*
G01X1126435Y140133D02*
X1124497Y138195D01*
G01X1127567Y140133D02*
X1126435D01*
G01X1128698Y139002D02*
X1127567Y140133D01*
G01X1128698Y137870D02*
Y139002D01*
G01X1127560Y136732D02*
X1128698Y137870D01*
G01X1127560Y135940D02*
Y136732D01*
G01X1129142Y134358D02*
X1127560Y135940D01*
G01X1129934Y134358D02*
X1129142D01*
G01X1131072Y135496D02*
X1129934Y134358D01*
G01X1132204Y135496D02*
X1131072D01*
G01X1133335Y134365D02*
X1132204Y135496D01*
G01X1133335Y133233D02*
Y134365D01*
G01X1130703Y130601D02*
X1133335Y133233D01*
G01X1130703Y129469D02*
Y130601D01*
G01X1146700Y113472D02*
X1130703Y129469D01*
G01X1146700Y111700D02*
Y113472D01*
G01X1145374Y110374D02*
X1146700Y111700D01*
G01X1145374Y106174D02*
Y110374D01*
G01X1146752Y104796D02*
X1145374Y106174D01*
G01X1125500Y110001D02*
Y94600D01*
G01X1125017Y110484D02*
X1125500Y110001D01*
G01X1123887Y110484D02*
X1125017D01*
G01X1123218Y109814D02*
X1123887Y110484D01*
G01X1122088Y109814D02*
X1123218D01*
G01X1120955Y110947D02*
X1122088Y109814D01*
G01X1120955Y112077D02*
Y110947D01*
G01X1121624Y112746D02*
X1120955Y112077D01*
G01X1121624Y113877D02*
Y112746D01*
G01X1120491Y115010D02*
X1121624Y113877D01*
G01X1119361Y115010D02*
X1120491D01*
G01X1118692Y114340D02*
X1119361Y115010D01*
G01X1117562Y114340D02*
X1118692D01*
G01X1116429Y115473D02*
X1117562Y114340D01*
G01X1116429Y116603D02*
Y115473D01*
G01X1117098Y117272D02*
X1116429Y116603D01*
G01X1117098Y118403D02*
Y117272D01*
G01X1115965Y119536D02*
X1117098Y118403D01*
G01X1114835Y119536D02*
X1115965D01*
G01X1114166Y118866D02*
X1114835Y119536D01*
G01X1113036Y118866D02*
X1114166D01*
G01X1111903Y119999D02*
X1113036Y118866D01*
G01X1111903Y121898D02*
Y119999D01*
G01X1110409Y123392D02*
X1111903Y121898D01*
G01X1108510Y123392D02*
X1110409D01*
G01X1107377Y124525D02*
X1108510Y123392D01*
G01X1107377Y125655D02*
Y124525D01*
G01X1108046Y126324D02*
X1107377Y125655D01*
G01X1108046Y127455D02*
Y126324D01*
G01X1102300Y95300D02*
Y94600D01*
G01X1103600Y96600D02*
X1102300Y95300D01*
G01X1103600Y97378D02*
Y96600D01*
G01X1156919Y135945D02*
X1121992Y170872D01*
G01X1128000Y107100D02*
Y96000D01*
G01X1129200Y108300D02*
X1128000Y107100D01*
G01X1129200Y109901D02*
Y108300D01*
G01X1096683Y123114D02*
Y124182D01*
G01X1095488Y121919D02*
X1096683Y123114D01*
G01X1167000Y122328D02*
X1119492Y169836D01*
G01X1101651Y155141D02*
X1103097Y156587D01*
G01X1101651Y154349D02*
Y155141D01*
G01X1103122Y152878D02*
X1101651Y154349D01*
G01X1103914Y152878D02*
X1103122D01*
G01X1105360Y154324D02*
X1103914Y152878D01*
G01X1106492Y154324D02*
X1105360D01*
G01X1107623Y153193D02*
X1106492Y154324D01*
G01X1107623Y152061D02*
Y153193D01*
G01X1105977Y150415D02*
X1107623Y152061D01*
G01X1105977Y149623D02*
Y150415D01*
G01X1107448Y148152D02*
X1105977Y149623D01*
G01X1108240Y148152D02*
X1107448D01*
G01X1109886Y149798D02*
X1108240Y148152D01*
G01X1111018Y149798D02*
X1109886D01*
G01X1112293Y148523D02*
X1111018Y149798D01*
G01X1112293Y147391D02*
Y148523D01*
G01X1109800Y144898D02*
X1112293Y147391D01*
G01X1109800Y143300D02*
Y144898D01*
G01X1138200Y114900D02*
X1109800Y143300D01*
G01X1138400Y114900D02*
X1138200D01*
G01X1140100Y113200D02*
X1138400Y114900D01*
G01X1140100Y111400D02*
Y113200D01*
G01X1139000Y110300D02*
X1140100Y111400D01*
G01X1139000Y106300D02*
Y110300D01*
G01X1140100Y105200D02*
X1139000Y106300D01*
G01X1162100Y123692D02*
X1116992Y168800D01*
G01X1161423Y191460D02*
X1148018Y204865D01*
G01X1101800Y162552D02*
Y184000D01*
G01X1124492Y173760D02*
Y186158D01*
G01X1145116Y205100D02*
X1160641Y189575D01*
G01X1155188Y174260D02*
X1181800Y147648D01*
G01X1148202Y174260D02*
X1155188D01*
G01X1129160Y193302D02*
X1148202Y174260D01*
G01X1149764Y178030D02*
X1158490D01*
G01X1131900Y195894D02*
X1149764Y178030D01*
G01X1106800Y164624D02*
Y184900D01*
G01X1104300Y163588D02*
Y184800D01*
G01X1156839Y176145D02*
X1184300Y148684D01*
G01X1148983Y176145D02*
X1156839D01*
G01X1130493Y194635D02*
X1148983Y176145D01*
G01X1148099Y207450D02*
X1162204Y193345D01*
G01X1121992Y170872D02*
Y185598D01*
G01X1119492Y169836D02*
Y185408D01*
G01X1145135Y202415D02*
X1159860Y187690D01*
G01X1099300Y161516D02*
Y183700D01*
G01X1103097Y157719D02*
X1099300Y161516D01*
G01X1103097Y156587D02*
Y157719D01*
G01X1095578Y173516D02*
Y165039D01*
G01X1116992Y168800D02*
Y185192D01*
G01X1150545Y179915D02*
X1160141D01*
G01X1133395Y197065D02*
X1150545Y179915D01*
G01X1137250Y428150D02*
X1157119D01*
G01X1136100Y427000D02*
X1137250Y428150D01*
G01X1136100Y422864D02*
Y427000D01*
G01X1113209Y459391D02*
X1137473Y483655D01*
G01X1113209Y455412D02*
Y459391D01*
G01X1103850Y446053D02*
X1113209Y455412D01*
G01X1103850Y422014D02*
Y446053D01*
G01X1121340Y442384D02*
X1144261Y465305D01*
G01X1121340Y422124D02*
Y442384D01*
G01X1154610Y454906D02*
X1184525Y484821D01*
G01X1143312Y454906D02*
X1154610D01*
G01X1128640Y440234D02*
X1143312Y454906D01*
G01X1128640Y422710D02*
Y440234D01*
G01X1162954Y412791D02*
X1153382D01*
G01X1098740Y450631D02*
X1136561Y488452D01*
G01X1098740Y422124D02*
Y450631D01*
G01X1152355Y415300D02*
X1162663D01*
G01X1151589Y414534D02*
X1152355Y415300D01*
G01X1146300Y450700D02*
X1157166D01*
G01X1133640Y438040D02*
X1146300Y450700D01*
G01X1133640Y423105D02*
Y438040D01*
G01X1118840Y442694D02*
X1144211Y468065D01*
G01X1118840Y422124D02*
Y442694D01*
G01X1124227Y464324D02*
X1123233Y465318D01*
G01X1124227Y463462D02*
Y464324D01*
G01X1123243Y462478D02*
X1124227Y463462D01*
G01X1122381Y462478D02*
X1123243D01*
G01X1121387Y463472D02*
X1122381Y462478D01*
G01X1120525Y463472D02*
X1121387D01*
G01X1119541Y462488D02*
X1120525Y463472D01*
G01X1119541Y461626D02*
Y462488D01*
G01X1120535Y460632D02*
X1119541Y461626D01*
G01X1120535Y459770D02*
Y460632D01*
G01X1119551Y458786D02*
X1120535Y459770D01*
G01X1118689Y458786D02*
X1119551D01*
G01X1117695Y459780D02*
X1118689Y458786D01*
G01X1116833Y459780D02*
X1117695D01*
G01X1115849Y458796D02*
X1116833Y459780D01*
G01X1115849Y457934D02*
Y458796D01*
G01X1116843Y456940D02*
X1115849Y457934D01*
G01X1116843Y456078D02*
Y456940D01*
G01X1106240Y445475D02*
X1116843Y456078D01*
G01X1106240Y422124D02*
Y445475D01*
G01X1099117Y464579D02*
X1098479Y465217D01*
G01X1099117Y463717D02*
Y464579D01*
G01X1097716Y462316D02*
X1099117Y463717D01*
G01X1096854Y462316D02*
X1097716D01*
G01X1096216Y462954D02*
X1096854Y462316D01*
G01X1095354Y462954D02*
X1096216D01*
G01X1150919Y417400D02*
X1161963D01*
G01X1149521Y416002D02*
X1150919Y417400D01*
G01X1109958Y458897D02*
X1137013Y485952D01*
G01X1109958Y458036D02*
Y458897D01*
G01X1110951Y457043D02*
X1109958Y458036D01*
G01X1110951Y456181D02*
Y457043D01*
G01X1109967Y455197D02*
X1110951Y456181D01*
G01X1109104Y455197D02*
X1109967D01*
G01X1108112Y456189D02*
X1109104Y455197D01*
G01X1107250Y456189D02*
X1108112D01*
G01X1106266Y455205D02*
X1107250Y456189D01*
G01X1106266Y454344D02*
Y455205D01*
G01X1107259Y453351D02*
X1106266Y454344D01*
G01X1107259Y452489D02*
Y453351D01*
G01X1106275Y451505D02*
X1107259Y452489D01*
G01X1105412Y451505D02*
X1106275D01*
G01X1104420Y452497D02*
X1105412Y451505D01*
G01X1103558Y452497D02*
X1104420D01*
G01X1101240Y450179D02*
X1103558Y452497D01*
G01X1101240Y422124D02*
Y450179D01*
G01X1156120Y453021D02*
X1185277Y482178D01*
G01X1144093Y453021D02*
X1156120D01*
G01X1131140Y440068D02*
X1144093Y453021D01*
G01X1131140Y423140D02*
Y440068D01*
G01X1151445Y462997D02*
X1163667Y475219D01*
G01X1145189Y462997D02*
X1151445D01*
G01X1123900Y441708D02*
X1145189Y462997D01*
G01X1123900Y422184D02*
Y441708D01*
G01X1123840Y422124D02*
X1123900Y422184D01*
G01X1149333Y419350D02*
X1161113D01*
G01X1147671Y417688D02*
X1149333Y419350D01*
G01X1116340Y443164D02*
X1150945Y477769D01*
G01X1116340Y422124D02*
Y443164D01*
G01X1103141Y517407D02*
Y529359D01*
G01X1102241Y516507D02*
X1103141Y517407D01*
G01X1102241Y511757D02*
Y516507D01*
G01X1102982Y511016D02*
X1102241Y511757D01*
G01X1102982Y503208D02*
Y511016D01*
G01X1096093Y520062D02*
Y530307D01*
G01X1096405Y519750D02*
X1096093Y520062D01*
G01X1096405Y514505D02*
Y519750D01*
G01X1095500Y513600D02*
X1096405Y514505D01*
G01X1095500Y511800D02*
Y513600D01*
G01X1096405Y510895D02*
X1095500Y511800D01*
G01X1096405Y505835D02*
Y510895D01*
G01X1146100Y519952D02*
Y527600D01*
G01X1146752Y519300D02*
X1146100Y519952D01*
G01X1146752Y517657D02*
Y519300D01*
G01X1145402Y516307D02*
X1146752Y517657D01*
G01X1145402Y512057D02*
Y516307D01*
G01X1146574Y510885D02*
X1145402Y512057D01*
G01X1146574Y508726D02*
Y510885D01*
G01X1148000Y507300D02*
X1146574Y508726D01*
G01X1148000Y501036D02*
Y507300D01*
G01X1146574Y499610D02*
X1148000Y501036D01*
G01X1146574Y495674D02*
Y499610D01*
G01X1144800Y493900D02*
X1146574Y495674D01*
G01X1144800Y489601D02*
Y493900D01*
G01X1138854Y483655D02*
X1144800Y489601D01*
G01X1137473Y483655D02*
X1138854D01*
G01X1114058Y526454D02*
X1112441Y528071D01*
G01X1114058Y525261D02*
Y526454D01*
G01X1113448Y524651D02*
X1114058Y525261D01*
G01X1111513Y524651D02*
X1113448D01*
G01X1110876Y524014D02*
X1111513Y524651D01*
G01X1110876Y522624D02*
Y524014D01*
G01X1111459Y522041D02*
X1110876Y522624D01*
G01X1113448Y522041D02*
X1111459D01*
G01X1114058Y521431D02*
X1113448Y522041D01*
G01X1114058Y520355D02*
Y521431D01*
G01X1112441Y518738D02*
X1114058Y520355D01*
G01X1112441Y508841D02*
Y518738D01*
G01X1111511Y507911D02*
X1112441Y508841D01*
G01X1111511Y506871D02*
Y507911D01*
G01X1110950Y506310D02*
X1111511Y506871D01*
G01X1110030Y506310D02*
X1110950D01*
G01X1109470Y505750D02*
X1110030Y506310D01*
G01X1109470Y504631D02*
Y505750D01*
G01X1110080Y504021D02*
X1109470Y504631D01*
G01X1111829Y504021D02*
X1110080D01*
G01X1112439Y503411D02*
X1111829Y504021D01*
G01X1112439Y502021D02*
Y503411D01*
G01X1111829Y501411D02*
X1112439Y502021D01*
G01X1111804Y501411D02*
X1111829D01*
G01X1111244Y500851D02*
X1111804Y501411D01*
G01X1111244Y495979D02*
Y500851D01*
G01X1150625Y465305D02*
X1165158Y479838D01*
G01X1144261Y465305D02*
X1150625D01*
G01X1136300Y520001D02*
Y527900D01*
G01X1135700Y519401D02*
X1136300Y520001D01*
G01X1135700Y517748D02*
Y519401D01*
G01X1136641Y516807D02*
X1135700Y517748D01*
G01X1136641Y511641D02*
Y516807D01*
G01X1136041Y511041D02*
X1136641Y511641D01*
G01X1136041Y503241D02*
Y511041D01*
G01X1134300Y501500D02*
X1136041Y503241D01*
G01X1134300Y492588D02*
Y501500D01*
G01X1132317Y490605D02*
X1134300Y492588D01*
G01X1131455Y490605D02*
X1132317D01*
G01X1130596Y491464D02*
X1131455Y490605D01*
G01X1129888Y491464D02*
X1130596D01*
G01X1128750Y490326D02*
X1129888Y491464D01*
G01X1128750Y489618D02*
Y490326D01*
G01X1129609Y488759D02*
X1128750Y489618D01*
G01X1129609Y487897D02*
Y488759D01*
G01X1128625Y486913D02*
X1129609Y487897D01*
G01X1127763Y486913D02*
X1128625D01*
G01X1126775Y487901D02*
X1127763Y486913D01*
G01X1125913Y487901D02*
X1126775D01*
G01X1124929Y486917D02*
X1125913Y487901D01*
G01X1124929Y486055D02*
Y486917D01*
G01X1125917Y485067D02*
X1124929Y486055D01*
G01X1125917Y484205D02*
Y485067D01*
G01X1124933Y483221D02*
X1125917Y484205D01*
G01X1124071Y483221D02*
X1124933D01*
G01X1123083Y484209D02*
X1124071Y483221D01*
G01X1122221Y484209D02*
X1123083D01*
G01X1121237Y483225D02*
X1122221Y484209D01*
G01X1121237Y482363D02*
Y483225D01*
G01X1122225Y481375D02*
X1121237Y482363D01*
G01X1122225Y480513D02*
Y481375D01*
G01X1126300Y519841D02*
Y527800D01*
G01X1127000Y519141D02*
X1126300Y519841D01*
G01X1127000Y517500D02*
Y519141D01*
G01X1125600Y516100D02*
X1127000Y517500D01*
G01X1125600Y512000D02*
Y516100D01*
G01X1126600Y511000D02*
X1125600Y512000D01*
G01X1126600Y496964D02*
Y511000D01*
G01X1108701Y520040D02*
Y526801D01*
G01X1109741Y519000D02*
X1108701Y520040D01*
G01X1109741Y517457D02*
Y519000D01*
G01X1108591Y516307D02*
X1109741Y517457D01*
G01X1108591Y512057D02*
Y516307D01*
G01X1109941Y510707D02*
X1108591Y512057D01*
G01X1109941Y509641D02*
Y510707D01*
G01X1107322Y507022D02*
X1109941Y509641D01*
G01X1107322Y495600D02*
Y507022D01*
G01X1133203Y517519D02*
Y529595D01*
G01X1132805Y517121D02*
X1133203Y517519D01*
G01X1132805Y511495D02*
Y517121D01*
G01X1133018Y511282D02*
X1132805Y511495D01*
G01X1133018Y508618D02*
Y511282D01*
G01X1131800Y507400D02*
X1133018Y508618D01*
G01X1131800Y496500D02*
Y507400D01*
G01X1115088Y479788D02*
X1131800Y496500D01*
G01X1115088Y476912D02*
Y479788D01*
G01X1139700Y520052D02*
Y527800D01*
G01X1140300Y519452D02*
X1139700Y520052D01*
G01X1140300Y517601D02*
Y519452D01*
G01X1139052Y516353D02*
X1140300Y517601D01*
G01X1139052Y511797D02*
Y516353D01*
G01X1139952Y510897D02*
X1139052Y511797D01*
G01X1139952Y509452D02*
Y510897D01*
G01X1139100Y508600D02*
X1139952Y509452D01*
G01X1139100Y507198D02*
Y508600D01*
G01X1139900Y506398D02*
X1139100Y507198D01*
G01X1140600Y506398D02*
X1139900D01*
G01X1141400Y505598D02*
X1140600Y506398D01*
G01X1141400Y503998D02*
Y505598D01*
G01X1140600Y503198D02*
X1141400Y503998D01*
G01X1139900Y503198D02*
X1140600D01*
G01X1139100Y502398D02*
X1139900Y503198D01*
G01X1139100Y500852D02*
Y502398D01*
G01X1139952Y500000D02*
X1139100Y500852D01*
G01X1139952Y495452D02*
Y500000D01*
G01X1139174Y494674D02*
X1139952Y495452D01*
G01X1139174Y489652D02*
Y494674D01*
G01X1137974Y488452D02*
X1139174Y489652D01*
G01X1136561Y488452D02*
X1137974D01*
G01X1151740Y475594D02*
X1157838D01*
G01X1150611Y474465D02*
X1151740Y475594D01*
G01X1150611Y473603D02*
Y474465D01*
G01X1152663Y471551D02*
X1150611Y473603D01*
G01X1152663Y470843D02*
Y471551D01*
G01X1151525Y469705D02*
X1152663Y470843D01*
G01X1150817Y469705D02*
X1151525D01*
G01X1148765Y471757D02*
X1150817Y469705D01*
G01X1147903Y471757D02*
X1148765D01*
G01X1146919Y470773D02*
X1147903Y471757D01*
G01X1146919Y469911D02*
Y470773D01*
G01X1147777Y469053D02*
X1146919Y469911D01*
G01X1147777Y468345D02*
Y469053D01*
G01X1146639Y467207D02*
X1147777Y468345D01*
G01X1145931Y467207D02*
X1146639D01*
G01X1145073Y468065D02*
X1145931Y467207D01*
G01X1144211Y468065D02*
X1145073D01*
G01X1149700Y519300D02*
Y527600D01*
G01X1149274Y518874D02*
X1149700Y519300D01*
G01X1149274Y509326D02*
Y518874D01*
G01X1150552Y508048D02*
X1149274Y509326D01*
G01X1150552Y501152D02*
Y508048D01*
G01X1149100Y499700D02*
X1150552Y501152D01*
G01X1149100Y488653D02*
Y499700D01*
G01X1142087Y481640D02*
X1149100Y488653D01*
G01X1138693Y481640D02*
X1142087D01*
G01X1130617Y473564D02*
X1138693Y481640D01*
G01X1130617Y472702D02*
Y473564D01*
G01X1131611Y471708D02*
X1130617Y472702D01*
G01X1131611Y470846D02*
Y471708D01*
G01X1130627Y469862D02*
X1131611Y470846D01*
G01X1129765Y469862D02*
X1130627D01*
G01X1128771Y470856D02*
X1129765Y469862D01*
G01X1127909Y470856D02*
X1128771D01*
G01X1126925Y469872D02*
X1127909Y470856D01*
G01X1126925Y469010D02*
Y469872D01*
G01X1127919Y468016D02*
X1126925Y469010D01*
G01X1127919Y467154D02*
Y468016D01*
G01X1126935Y466170D02*
X1127919Y467154D01*
G01X1126073Y466170D02*
X1126935D01*
G01X1125079Y467164D02*
X1126073Y466170D01*
G01X1124217Y467164D02*
X1125079D01*
G01X1123233Y466180D02*
X1124217Y467164D01*
G01X1123233Y465318D02*
Y466180D01*
G01X1129900Y526200D02*
Y527500D01*
G01X1128800Y525100D02*
X1129900Y526200D01*
G01X1128800Y523400D02*
Y525100D01*
G01X1130000Y522200D02*
X1128800Y523400D01*
G01X1130000Y520359D02*
Y522200D01*
G01X1129000Y519359D02*
X1130000Y520359D01*
G01X1129000Y517500D02*
Y519359D01*
G01X1130500Y516000D02*
X1129000Y517500D01*
G01X1130500Y512416D02*
Y516000D01*
G01X1129100Y511016D02*
X1130500Y512416D01*
G01X1129100Y496700D02*
Y511016D01*
G01X1112057Y479657D02*
X1129100Y496700D01*
G01X1112057Y478795D02*
Y479657D01*
G01X1112695Y478157D02*
X1112057Y478795D01*
G01X1112695Y477295D02*
Y478157D01*
G01X1111294Y475894D02*
X1112695Y477295D01*
G01X1110432Y475894D02*
X1111294D01*
G01X1109794Y476532D02*
X1110432Y475894D01*
G01X1108932Y476532D02*
X1109794D01*
G01X1107531Y475131D02*
X1108932Y476532D01*
G01X1107531Y474269D02*
Y475131D01*
G01X1108169Y473631D02*
X1107531Y474269D01*
G01X1108169Y472769D02*
Y473631D01*
G01X1106768Y471368D02*
X1108169Y472769D01*
G01X1105906Y471368D02*
X1106768D01*
G01X1105268Y472006D02*
X1105906Y471368D01*
G01X1104406Y472006D02*
X1105268D01*
G01X1103005Y470605D02*
X1104406Y472006D01*
G01X1103005Y469743D02*
Y470605D01*
G01X1103643Y469105D02*
X1103005Y469743D01*
G01X1103643Y468243D02*
Y469105D01*
G01X1102242Y466842D02*
X1103643Y468243D01*
G01X1101380Y466842D02*
X1102242D01*
G01X1100742Y467480D02*
X1101380Y466842D01*
G01X1099880Y467480D02*
X1100742D01*
G01X1098479Y466079D02*
X1099880Y467480D01*
G01X1098479Y465217D02*
Y466079D01*
G01X1143000Y520100D02*
Y527652D01*
G01X1142100Y519200D02*
X1143000Y520100D01*
G01X1142100Y517301D02*
Y519200D01*
G01X1143300Y516101D02*
X1142100Y517301D01*
G01X1143300Y512350D02*
Y516101D01*
G01X1142674Y511724D02*
X1143300Y512350D01*
G01X1142674Y508726D02*
Y511724D01*
G01X1145600Y505800D02*
X1142674Y508726D01*
G01X1145600Y502426D02*
Y505800D01*
G01X1142200Y499026D02*
X1145600Y502426D01*
G01X1142200Y495100D02*
Y499026D01*
G01X1142800Y494500D02*
X1142200Y495100D01*
G01X1142800Y490300D02*
Y494500D01*
G01X1138452Y485952D02*
X1142800Y490300D01*
G01X1137013Y485952D02*
X1138452D01*
G01X1106200Y519459D02*
Y527300D01*
G01X1105841Y519100D02*
X1106200Y519459D01*
G01X1105841Y517457D02*
Y519100D01*
G01X1106091Y517207D02*
X1105841Y517457D01*
G01X1106091Y511791D02*
Y517207D01*
G01X1105100Y510800D02*
X1106091Y511791D01*
G01X1105100Y496978D02*
Y510800D01*
G01X1150945Y477769D02*
X1157149D01*
G01X1103153Y572500D02*
X1104141D01*
G01X1100098Y569445D02*
X1103153Y572500D01*
G01X1100098Y568257D02*
Y569445D01*
G01X1099476Y567635D02*
X1100098Y568257D01*
G01X1099476Y557662D02*
Y567635D01*
G01X1101181Y555957D02*
X1099476Y557662D01*
G01X1100639Y555415D02*
X1101181Y555957D01*
G01X1100639Y551109D02*
Y555415D01*
G01X1103091Y548657D02*
X1100639Y551109D01*
G01X1103091Y536142D02*
Y548657D01*
G01X1102310Y535361D02*
X1103091Y536142D01*
G01X1102310Y530190D02*
Y535361D01*
G01X1103141Y529359D02*
X1102310Y530190D01*
G01X1096750Y557650D02*
Y567450D01*
G01X1096400Y557300D02*
X1096750Y557650D01*
G01X1096400Y552200D02*
Y557300D01*
G01X1095400Y551200D02*
X1096400Y552200D01*
G01X1095400Y549700D02*
Y551200D01*
G01X1096600Y548500D02*
X1095400Y549700D01*
G01X1096600Y539200D02*
Y548500D01*
G01X1096178Y538778D02*
X1096600Y539200D01*
G01X1096178Y530392D02*
Y538778D01*
G01X1096093Y530307D02*
X1096178Y530392D01*
G01X1146602Y586457D02*
X1144685Y588374D01*
G01X1146602Y574203D02*
Y586457D01*
G01X1145452Y573053D02*
X1146602Y574203D01*
G01X1145452Y568347D02*
Y573053D01*
G01X1146552Y567247D02*
X1145452Y568347D01*
G01X1146552Y565952D02*
Y567247D01*
G01X1146400Y565800D02*
X1146552Y565952D01*
G01X1146400Y557452D02*
Y565800D01*
G01X1146600Y557252D02*
X1146400Y557452D01*
G01X1146600Y555305D02*
Y557252D01*
G01X1145402Y554107D02*
X1146600Y555305D01*
G01X1145402Y549857D02*
Y554107D01*
G01X1146752Y548507D02*
X1145402Y549857D01*
G01X1146752Y546352D02*
Y548507D01*
G01X1145700Y545300D02*
X1146752Y546352D01*
G01X1145700Y538752D02*
Y545300D01*
G01X1146752Y537700D02*
X1145700Y538752D01*
G01X1146752Y536552D02*
Y537700D01*
G01X1145402Y535202D02*
X1146752Y536552D01*
G01X1145402Y530598D02*
Y535202D01*
G01X1146752Y529248D02*
X1145402Y530598D01*
G01X1146752Y528252D02*
Y529248D01*
G01X1146100Y527600D02*
X1146752Y528252D01*
G01X1108854Y566699D02*
X1107874D01*
G01X1109453Y566100D02*
X1108854Y566699D01*
G01X1109453Y564900D02*
Y566100D01*
G01X1108509Y563956D02*
X1109453Y564900D01*
G01X1108509Y562744D02*
Y563956D01*
G01X1109353Y561900D02*
X1108509Y562744D01*
G01X1109353Y560200D02*
Y561900D01*
G01X1108509Y559356D02*
X1109353Y560200D01*
G01X1108509Y557936D02*
Y559356D01*
G01X1109653Y556792D02*
X1108509Y557936D01*
G01X1109653Y555199D02*
Y556792D01*
G01X1108746Y554292D02*
X1109653Y555199D01*
G01X1108746Y552600D02*
Y554292D01*
G01X1110432Y550914D02*
X1108746Y552600D01*
G01X1110520Y550914D02*
X1110432D01*
G01X1110520Y550564D02*
Y550914D01*
G01X1112441Y548643D02*
X1110520Y550564D01*
G01X1112441Y547159D02*
Y548643D01*
G01X1114138Y545462D02*
X1112441Y547159D01*
G01X1114138Y544301D02*
Y545462D01*
G01X1113528Y543691D02*
X1114138Y544301D01*
G01X1111221Y543691D02*
X1113528D01*
G01X1110611Y543081D02*
X1111221Y543691D01*
G01X1110611Y541691D02*
Y543081D01*
G01X1111221Y541081D02*
X1110611Y541691D01*
G01X1113528Y541081D02*
X1111221D01*
G01X1114138Y540471D02*
X1113528Y541081D01*
G01X1114138Y539437D02*
Y540471D01*
G01X1112441Y537740D02*
X1114138Y539437D01*
G01X1112441Y528071D02*
Y537740D01*
G01X1134645Y550966D02*
Y550914D01*
G01X1135941Y549670D02*
X1134645Y550966D01*
G01X1135941Y546759D02*
Y549670D01*
G01X1136300Y546400D02*
X1135941Y546759D01*
G01X1136300Y537899D02*
Y546400D01*
G01X1135941Y537540D02*
X1136300Y537899D01*
G01X1135941Y536258D02*
Y537540D01*
G01X1136941Y535258D02*
X1135941Y536258D01*
G01X1136941Y530469D02*
Y535258D01*
G01X1136091Y529619D02*
X1136941Y530469D01*
G01X1136091Y528109D02*
Y529619D01*
G01X1136300Y527900D02*
X1136091Y528109D01*
G01X1132371Y566699D02*
X1131299D01*
G01X1133071Y565999D02*
X1132371Y566699D01*
G01X1133071Y564725D02*
Y565999D01*
G01X1131934Y563588D02*
X1133071Y564725D01*
G01X1131934Y562512D02*
Y563588D01*
G01X1132946Y561500D02*
X1131934Y562512D01*
G01X1132946Y560300D02*
Y561500D01*
G01X1131934Y559288D02*
X1132946Y560300D01*
G01X1131934Y558212D02*
Y559288D01*
G01X1133046Y557100D02*
X1131934Y558212D01*
G01X1133046Y554467D02*
Y557100D01*
G01X1132871Y554292D02*
X1133046Y554467D01*
G01X1132871Y552600D02*
Y554292D01*
G01X1134557Y550914D02*
X1132871Y552600D01*
G01X1134645Y550914D02*
X1134557D01*
G01X1122901Y567849D02*
X1127952Y572900D01*
G01X1122901Y557662D02*
Y567849D01*
G01X1124606Y555957D02*
X1122901Y557662D01*
G01X1123941Y555292D02*
X1124606Y555957D01*
G01X1123941Y551721D02*
Y555292D01*
G01X1126841Y548821D02*
X1123941Y551721D01*
G01X1126841Y547041D02*
Y548821D01*
G01X1126275Y546475D02*
X1126841Y547041D01*
G01X1126275Y538266D02*
Y546475D01*
G01X1126841Y537700D02*
X1126275Y538266D01*
G01X1126841Y536742D02*
Y537700D01*
G01X1125200Y535101D02*
X1126841Y536742D01*
G01X1125200Y531000D02*
Y535101D01*
G01X1126784Y529416D02*
X1125200Y531000D01*
G01X1126784Y528284D02*
Y529416D01*
G01X1126300Y527800D02*
X1126784Y528284D01*
G01X1109354Y572500D02*
X1110520D01*
G01X1106169Y569315D02*
X1109354Y572500D01*
G01X1106169Y557662D02*
Y569315D01*
G01X1107874Y555957D02*
X1106169Y557662D01*
G01X1106441Y554524D02*
X1107874Y555957D01*
G01X1106441Y552007D02*
Y554524D01*
G01X1109791Y548657D02*
X1106441Y552007D01*
G01X1109791Y546991D02*
Y548657D01*
G01X1108410Y545610D02*
X1109791Y546991D01*
G01X1108410Y539381D02*
Y545610D01*
G01X1109791Y538000D02*
X1108410Y539381D01*
G01X1109791Y536491D02*
Y538000D01*
G01X1108641Y535341D02*
X1109791Y536491D01*
G01X1108641Y530559D02*
Y535341D01*
G01X1109741Y529459D02*
X1108641Y530559D01*
G01X1109741Y527841D02*
Y529459D01*
G01X1108701Y526801D02*
X1109741Y527841D01*
G01X1129594Y567849D02*
X1134645Y572900D01*
G01X1129594Y557662D02*
Y567849D01*
G01X1131299Y555957D02*
X1129594Y557662D01*
G01X1129941Y554599D02*
X1131299Y555957D01*
G01X1129941Y552107D02*
Y554599D01*
G01X1133071Y548977D02*
X1129941Y552107D01*
G01X1133071Y535972D02*
Y548977D01*
G01X1132441Y535342D02*
X1133071Y535972D01*
G01X1132441Y530357D02*
Y535342D01*
G01X1133203Y529595D02*
X1132441Y530357D01*
G01X1135833Y586929D02*
X1137992Y589088D01*
G01X1135833Y579569D02*
Y586929D01*
G01X1140115Y575287D02*
X1135833Y579569D01*
G01X1140115Y574155D02*
Y575287D01*
G01X1138300Y572340D02*
X1140115Y574155D01*
G01X1138300Y568901D02*
Y572340D01*
G01X1139952Y567249D02*
X1138300Y568901D01*
G01X1139952Y565952D02*
Y567249D01*
G01X1139700Y565700D02*
X1139952Y565952D01*
G01X1139700Y557800D02*
Y565700D01*
G01X1140300Y557200D02*
X1139700Y557800D01*
G01X1140300Y555505D02*
Y557200D01*
G01X1139052Y554257D02*
X1140300Y555505D01*
G01X1139052Y549557D02*
Y554257D01*
G01X1140052Y548557D02*
X1139052Y549557D01*
G01X1140052Y547252D02*
Y548557D01*
G01X1139700Y546900D02*
X1140052Y547252D01*
G01X1139700Y538052D02*
Y546900D01*
G01X1140052Y537700D02*
X1139700Y538052D01*
G01X1140052Y536242D02*
Y537700D01*
G01X1139052Y535242D02*
X1140052Y536242D01*
G01X1139052Y530348D02*
Y535242D01*
G01X1139952Y529448D02*
X1139052Y530348D01*
G01X1139952Y528052D02*
Y529448D01*
G01X1139700Y527800D02*
X1139952Y528052D01*
G01X1149274Y586771D02*
X1147331Y588714D01*
G01X1149274Y566126D02*
Y586771D01*
G01X1149700Y565700D02*
X1149274Y566126D01*
G01X1149700Y563000D02*
Y565700D01*
G01X1148900Y562200D02*
X1149700Y563000D01*
G01X1148900Y559800D02*
Y562200D01*
G01X1149700Y559000D02*
X1148900Y559800D01*
G01X1149700Y557200D02*
Y559000D01*
G01X1149274Y556774D02*
X1149700Y557200D01*
G01X1149274Y546926D02*
Y556774D01*
G01X1149700Y546500D02*
X1149274Y546926D01*
G01X1149700Y544800D02*
Y546500D01*
G01X1148400Y543500D02*
X1149700Y544800D01*
G01X1148400Y541700D02*
Y543500D01*
G01X1149700Y540400D02*
X1148400Y541700D01*
G01X1149700Y538326D02*
Y540400D01*
G01X1149274Y537900D02*
X1149700Y538326D01*
G01X1149274Y528026D02*
Y537900D01*
G01X1149700Y527600D02*
X1149274Y528026D01*
G01X1125678Y566699D02*
X1124606D01*
G01X1126378Y565999D02*
X1125678Y566699D01*
G01X1126378Y564725D02*
Y565999D01*
G01X1125241Y563588D02*
X1126378Y564725D01*
G01X1125241Y562512D02*
Y563588D01*
G01X1126253Y561500D02*
X1125241Y562512D01*
G01X1126253Y560300D02*
Y561500D01*
G01X1125241Y559288D02*
X1126253Y560300D01*
G01X1125241Y558212D02*
Y559288D01*
G01X1126353Y557100D02*
X1125241Y558212D01*
G01X1126353Y554467D02*
Y557100D01*
G01X1126178Y554292D02*
X1126353Y554467D01*
G01X1126178Y552600D02*
Y554292D01*
G01X1127864Y550914D02*
X1126178Y552600D01*
G01X1127952Y550914D02*
X1127864D01*
G01X1129298Y549568D02*
X1127952Y550914D01*
G01X1129341Y549568D02*
X1129298D01*
G01X1129341Y547059D02*
Y549568D01*
G01X1130000Y546400D02*
X1129341Y547059D01*
G01X1130000Y544600D02*
Y546400D01*
G01X1128934Y543534D02*
X1130000Y544600D01*
G01X1128934Y541166D02*
Y543534D01*
G01X1130000Y540100D02*
X1128934Y541166D01*
G01X1130000Y538399D02*
Y540100D01*
G01X1129341Y537740D02*
X1130000Y538399D01*
G01X1129341Y536159D02*
Y537740D01*
G01X1130007Y535493D02*
X1129341Y536159D01*
G01X1130007Y530221D02*
Y535493D01*
G01X1129441Y529655D02*
X1130007Y530221D01*
G01X1129441Y527959D02*
Y529655D01*
G01X1129900Y527500D02*
X1129441Y527959D01*
G01X1141038Y586562D02*
Y588714D01*
G01X1143000Y584600D02*
X1141038Y586562D01*
G01X1143000Y583374D02*
Y584600D01*
G01X1142390Y582764D02*
X1143000Y583374D01*
G01X1139572Y582764D02*
X1142390D01*
G01X1138962Y582154D02*
X1139572Y582764D01*
G01X1138962Y580174D02*
Y582154D01*
G01X1139572Y579564D02*
X1138962Y580174D01*
G01X1142390Y579564D02*
X1139572D01*
G01X1143000Y578954D02*
X1142390Y579564D01*
G01X1143000Y575848D02*
Y578954D01*
G01X1142552Y575400D02*
X1143000Y575848D01*
G01X1142552Y573256D02*
Y575400D01*
G01X1143152Y572656D02*
X1142552Y573256D01*
G01X1143152Y568497D02*
Y572656D01*
G01X1142652Y567997D02*
X1143152Y568497D01*
G01X1142652Y566048D02*
Y567997D01*
G01X1143000Y565700D02*
X1142652Y566048D01*
G01X1143000Y557548D02*
Y565700D01*
G01X1142400Y556948D02*
X1143000Y557548D01*
G01X1142400Y555509D02*
Y556948D01*
G01X1143400Y554509D02*
X1142400Y555509D01*
G01X1143400Y550101D02*
Y554509D01*
G01X1142214Y548915D02*
X1143400Y550101D01*
G01X1142214Y546986D02*
Y548915D01*
G01X1143000Y546200D02*
X1142214Y546986D01*
G01X1143000Y537948D02*
Y546200D01*
G01X1142392Y537340D02*
X1143000Y537948D01*
G01X1142392Y536208D02*
Y537340D01*
G01X1143000Y535600D02*
X1142392Y536208D01*
G01X1143000Y530400D02*
Y535600D01*
G01X1142300Y529700D02*
X1143000Y530400D01*
G01X1142300Y528352D02*
Y529700D01*
G01X1143000Y527652D02*
X1142300Y528352D01*
G01X1102253Y566699D02*
X1101181D01*
G01X1102853Y566099D02*
X1102253Y566699D01*
G01X1102853Y565201D02*
Y566099D01*
G01X1101816Y564164D02*
X1102853Y565201D01*
G01X1101816Y562936D02*
Y564164D01*
G01X1102753Y561999D02*
X1101816Y562936D01*
G01X1102753Y560601D02*
Y561999D01*
G01X1101816Y559664D02*
X1102753Y560601D01*
G01X1101816Y558336D02*
Y559664D01*
G01X1102953Y557199D02*
X1101816Y558336D01*
G01X1102953Y555300D02*
Y557199D01*
G01X1102453Y554800D02*
X1102953Y555300D01*
G01X1102453Y552600D02*
Y554800D01*
G01X1104139Y550914D02*
X1102453Y552600D01*
G01X1104227Y550914D02*
X1104139D01*
G01X1105741Y549400D02*
X1104227Y550914D01*
G01X1105741Y546959D02*
Y549400D01*
G01X1106200Y546500D02*
X1105741Y546959D01*
G01X1106200Y538059D02*
Y546500D01*
G01X1105741Y537600D02*
X1106200Y538059D01*
G01X1105741Y535456D02*
Y537600D01*
G01X1106341Y534856D02*
X1105741Y535456D01*
G01X1106341Y530697D02*
Y534856D01*
G01X1105841Y530197D02*
X1106341Y530697D01*
G01X1105841Y527659D02*
Y530197D01*
G01X1106200Y527300D02*
X1105841Y527659D01*
G01X1144685Y588374D02*
Y593757D01*
G01X1137992Y589088D02*
Y593757D01*
G01X1173452Y29249D02*
Y34547D01*
G01X1172902Y28699D02*
X1173452Y29249D01*
G01X1172902Y18964D02*
Y28699D01*
G01X1169552Y15614D02*
X1172902Y18964D01*
G01X1169552Y14018D02*
Y15614D01*
G01X1171456Y12114D02*
X1169552Y14018D01*
G01X1199475Y29146D02*
X1198228Y27899D01*
G01X1199475Y30400D02*
Y29146D01*
G01X1200775Y31700D02*
X1199475Y30400D01*
G01X1201775Y31700D02*
X1200775D01*
G01X1203575Y33500D02*
X1201775Y31700D01*
G01X1211614Y29453D02*
Y27899D01*
G01X1213861Y31700D02*
X1211614Y29453D01*
G01X1215085Y31700D02*
X1213861D01*
G01X1216661Y33276D02*
X1215085Y31700D01*
G01X1206168Y29146D02*
X1204921Y27899D01*
G01X1206168Y30400D02*
Y29146D01*
G01X1207468Y31700D02*
X1206168Y30400D01*
G01X1208468Y31700D02*
X1207468D01*
G01X1210268Y33500D02*
X1208468Y31700D01*
G01X1178274D02*
X1179850Y33276D01*
G01X1177050Y31700D02*
X1178274D01*
G01X1175800Y30450D02*
X1177050Y31700D01*
G01X1175800Y28896D02*
Y30450D01*
G01X1174803Y27899D02*
X1175800Y28896D01*
G01X1184775Y31900D02*
X1186231Y33356D01*
G01X1183375Y31900D02*
X1184775D01*
G01X1181496Y30021D02*
X1183375Y31900D01*
G01X1181496Y27899D02*
Y30021D01*
G01X1169552Y28999D02*
Y34851D01*
G01X1170352Y28199D02*
X1169552Y28999D01*
G01X1170352Y19399D02*
Y28199D01*
G01X1168110Y17157D02*
X1170352Y19399D01*
G01X1167052Y29499D02*
Y34447D01*
G01X1165952Y28399D02*
X1167052Y29499D01*
G01X1165952Y18792D02*
Y28399D01*
G01X1162852Y15692D02*
X1165952Y18792D01*
G01X1162852Y14025D02*
Y15692D01*
G01X1164763Y12114D02*
X1162852Y14025D01*
G01Y29099D02*
Y34751D01*
G01X1163452Y28499D02*
X1162852Y29099D01*
G01X1163452Y20052D02*
Y28499D01*
G01X1161417Y18017D02*
X1163452Y20052D01*
G01X1161417Y17157D02*
Y18017D01*
G01X1218307Y30021D02*
Y27899D01*
G01X1220186Y31900D02*
X1218307Y30021D01*
G01X1172900Y91926D02*
Y105600D01*
G01X1173552Y91274D02*
X1172900Y91926D01*
G01X1173552Y86614D02*
Y91274D01*
G01X1172852Y85914D02*
X1173552Y86614D01*
G01X1172852Y73047D02*
Y85914D01*
G01X1173452Y72447D02*
X1172852Y73047D01*
G01X1173452Y67049D02*
Y72447D01*
G01X1172902Y66499D02*
X1173452Y67049D01*
G01X1172902Y53864D02*
Y66499D01*
G01X1173552Y53214D02*
X1172902Y53864D01*
G01X1173552Y48814D02*
Y53214D01*
G01X1172852Y48114D02*
X1173552Y48814D01*
G01X1172852Y35147D02*
Y48114D01*
G01X1173452Y34547D02*
X1172852Y35147D01*
G01X1213486Y34788D02*
X1214574Y33700D01*
G01X1213486Y36668D02*
Y34788D01*
G01X1212053Y38101D02*
X1213486Y36668D01*
G01X1212053Y39300D02*
Y38101D01*
G01X1213553Y40800D02*
X1212053Y39300D01*
G01X1213553Y42000D02*
Y40800D01*
G01X1212103Y43450D02*
X1213553Y42000D01*
G01X1212103Y44849D02*
Y43450D01*
G01X1213486Y46232D02*
X1212103Y44849D01*
G01X1213486Y48101D02*
Y46232D01*
G01X1210686Y50901D02*
X1213486Y48101D01*
G01X1210686Y54029D02*
Y50901D01*
G01X1211614Y54957D02*
X1210686Y54029D01*
G01X1213574Y56917D02*
X1211614Y54957D01*
G01X1213574Y66227D02*
Y56917D01*
G01X1212674Y67127D02*
X1213574Y66227D01*
G01X1212674Y72103D02*
Y67127D01*
G01X1213674Y73103D02*
X1212674Y72103D01*
G01X1213674Y85274D02*
Y73103D01*
G01X1212674Y86274D02*
X1213674Y85274D01*
G01X1212674Y91218D02*
Y86274D01*
G01X1213414Y91958D02*
X1212674Y91218D01*
G01X1213414Y108100D02*
Y91958D01*
G01X1218453Y38501D02*
X1220086Y36868D01*
G01X1218453Y39800D02*
Y38501D01*
G01X1219803Y41150D02*
X1218453Y39800D01*
G01X1218553Y43300D02*
X1219803Y42050D01*
G01X1218553Y44499D02*
Y43300D01*
G01X1220086Y46032D02*
X1218553Y44499D01*
G01X1217186Y50900D02*
X1220086Y48000D01*
G01X1217186Y53836D02*
Y50900D01*
G01X1218307Y54957D02*
X1217186Y53836D01*
G01X1218307Y62807D02*
Y54957D01*
G01X1220174Y64674D02*
X1218307Y62807D01*
G01X1203575Y34900D02*
Y33500D01*
G01X1202963Y35512D02*
X1203575Y34900D01*
G01X1202963Y48525D02*
Y35512D01*
G01X1201574Y49914D02*
X1202963Y48525D01*
G01X1199774Y51714D02*
X1201574Y49914D01*
G01X1199774Y53545D02*
Y51714D01*
G01X1202405Y56176D02*
X1199774Y53545D01*
G01X1202405Y65791D02*
Y56176D01*
G01X1203605Y66991D02*
X1202405Y65791D01*
G01X1203605Y72395D02*
Y66991D01*
G01X1202874Y73126D02*
X1203605Y72395D01*
G01X1202874Y85843D02*
Y73126D01*
G01X1203705Y86674D02*
X1202874Y85843D01*
G01X1203705Y91012D02*
Y86674D01*
G01X1203005Y91712D02*
X1203705Y91012D01*
G01X1203005Y105883D02*
Y91712D01*
G01X1181496Y61357D02*
Y54957D01*
G01X1183405Y63266D02*
X1181496Y61357D01*
G01X1183405Y66202D02*
Y63266D01*
G01X1182174Y67433D02*
X1183405Y66202D01*
G01X1182174Y72074D02*
Y67433D01*
G01X1183474Y73374D02*
X1182174Y72074D01*
G01X1183474Y85305D02*
Y73374D01*
G01X1182300Y86479D02*
X1183474Y85305D01*
G01X1182300Y91099D02*
Y86479D01*
G01X1183305Y92104D02*
X1182300Y91099D01*
G01X1183305Y104924D02*
Y92104D01*
G01X1183275Y34567D02*
X1184142Y33700D01*
G01X1183275Y36868D02*
Y34567D01*
G01X1181642Y38501D02*
X1183275Y36868D01*
G01X1181642Y39800D02*
Y38501D01*
G01X1182992Y41150D02*
X1181642Y39800D01*
G01X1182992Y42050D02*
Y41150D01*
G01X1181742Y43300D02*
X1182992Y42050D01*
G01X1181742Y44499D02*
Y43300D01*
G01X1183275Y46032D02*
X1181742Y44499D01*
G01X1183275Y48000D02*
Y46032D01*
G01X1180375Y50900D02*
X1183275Y48000D01*
G01X1180375Y53836D02*
Y50900D01*
G01X1181496Y54957D02*
X1180375Y53836D01*
G01X1216661Y34900D02*
Y33276D01*
G01X1215886Y35675D02*
X1216661Y34900D01*
G01X1215886Y48688D02*
Y35675D01*
G01X1214660Y49914D02*
X1215886Y48688D01*
G01X1213806Y50768D02*
X1214660Y49914D01*
G01X1213624Y50768D02*
X1213806D01*
G01X1212674Y51718D02*
X1213624Y50768D01*
G01X1212674Y53318D02*
Y51718D01*
G01X1215700Y56344D02*
X1212674Y53318D01*
G01X1215700Y65829D02*
Y56344D01*
G01X1216524Y66653D02*
X1215700Y65829D01*
G01X1216524Y72853D02*
Y66653D01*
G01X1216174Y73203D02*
X1216524Y72853D01*
G01X1216174Y85374D02*
Y73203D01*
G01X1217174Y86374D02*
X1216174Y85374D01*
G01X1217174Y90768D02*
Y86374D01*
G01X1216000Y91942D02*
X1217174Y90768D01*
G01X1216000Y109050D02*
Y91942D01*
G01X1210268Y34900D02*
Y33500D01*
G01X1209656Y35512D02*
X1210268Y34900D01*
G01X1209656Y48525D02*
Y35512D01*
G01X1208267Y49914D02*
X1209656Y48525D01*
G01X1206121Y52060D02*
X1208267Y49914D01*
G01X1206121Y53192D02*
Y52060D01*
G01X1207914Y54985D02*
X1206121Y53192D01*
G01X1207914Y61815D02*
Y54985D01*
G01X1209814Y63715D02*
X1207914Y61815D01*
G01X1209814Y66588D02*
Y63715D01*
G01X1210205Y66979D02*
X1209814Y66588D01*
G01X1210205Y72395D02*
Y66979D01*
G01X1209505Y73095D02*
X1210205Y72395D01*
G01X1209505Y85794D02*
Y73095D01*
G01X1210205Y86494D02*
X1209505Y85794D01*
G01X1210205Y91342D02*
Y86494D01*
G01X1209505Y92042D02*
X1210205Y91342D01*
G01X1209505Y106076D02*
Y92042D01*
G01X1179075Y48688D02*
X1177849Y49914D01*
G01X1179075Y35675D02*
Y48688D01*
G01X1179850Y34900D02*
X1179075Y35675D01*
G01X1179850Y33276D02*
Y34900D01*
G01X1179505Y91474D02*
Y105658D01*
G01X1179805Y91174D02*
X1179505Y91474D01*
G01X1179805Y86474D02*
Y91174D01*
G01X1179405Y86074D02*
X1179805Y86474D01*
G01X1179405Y72959D02*
Y86074D01*
G01X1179705Y72659D02*
X1179405Y72959D01*
G01X1179705Y66905D02*
Y72659D01*
G01X1178900Y66100D02*
X1179705Y66905D01*
G01X1178900Y57300D02*
Y66100D01*
G01X1177849Y56249D02*
X1178900Y57300D01*
G01X1177849Y49914D02*
Y56249D01*
G01X1186055Y63266D02*
Y105051D01*
G01X1183924Y61135D02*
X1186055Y63266D01*
G01X1183924Y54924D02*
Y61135D01*
G01X1182400Y53400D02*
X1183924Y54924D01*
G01X1182400Y51656D02*
Y53400D01*
G01X1184142Y49914D02*
X1182400Y51656D01*
G01X1185615Y48441D02*
X1184142Y49914D01*
G01X1185615Y35316D02*
Y48441D01*
G01X1186231Y34700D02*
X1185615Y35316D01*
G01X1186231Y33356D02*
Y34700D01*
G01X1203800Y53836D02*
X1204921Y54957D01*
G01X1203800Y50900D02*
Y53836D01*
G01X1207142Y47558D02*
X1203800Y50900D01*
G01X1207142Y46500D02*
Y47558D01*
G01X1205342Y44700D02*
X1207142Y46500D01*
G01X1205342Y43125D02*
Y44700D01*
G01X1206542Y41925D02*
X1205342Y43125D01*
G01X1206542Y40799D02*
Y41925D01*
G01X1205342Y39599D02*
X1206542Y40799D01*
G01X1205342Y38226D02*
Y39599D01*
G01X1206700Y36868D02*
X1205342Y38226D01*
G01X1206700Y35667D02*
Y36868D01*
G01X1208267Y34100D02*
X1206700Y35667D01*
G01X1206905Y91906D02*
Y104954D01*
G01X1206274Y91275D02*
X1206905Y91906D01*
G01X1206274Y86505D02*
Y91275D01*
G01X1207005Y85774D02*
X1206274Y86505D01*
G01X1207005Y73205D02*
Y85774D01*
G01X1206205Y72405D02*
X1207005Y73205D01*
G01X1206205Y67027D02*
Y72405D01*
G01X1206721Y66511D02*
X1206205Y67027D01*
G01X1206721Y64952D02*
Y66511D01*
G01X1204921Y63152D02*
X1206721Y64952D01*
G01X1204921Y54957D02*
Y63152D01*
G01X1170452Y92114D02*
Y104548D01*
G01X1169452Y91114D02*
X1170452Y92114D01*
G01X1169452Y86414D02*
Y91114D01*
G01X1170052Y85814D02*
X1169452Y86414D01*
G01X1170052Y73051D02*
Y85814D01*
G01X1169600Y72599D02*
X1170052Y73051D01*
G01X1169600Y66751D02*
Y72599D01*
G01X1170402Y65949D02*
X1169600Y66751D01*
G01X1170402Y54264D02*
Y65949D01*
G01X1169452Y53314D02*
X1170402Y54264D01*
G01X1169452Y48614D02*
Y53314D01*
G01X1170052Y48014D02*
X1169452Y48614D01*
G01X1170052Y44099D02*
Y48014D01*
G01X1168600Y42647D02*
X1170052Y44099D01*
G01X1168600Y40899D02*
Y42647D01*
G01X1170052Y39447D02*
X1168600Y40899D01*
G01X1170052Y35351D02*
Y39447D01*
G01X1169552Y34851D02*
X1170052Y35351D01*
G01X1166000Y91966D02*
Y105400D01*
G01X1166952Y91014D02*
X1166000Y91966D01*
G01X1166952Y86514D02*
Y91014D01*
G01X1166152Y85714D02*
X1166952Y86514D01*
G01X1166152Y72947D02*
Y85714D01*
G01X1167052Y72047D02*
X1166152Y72947D01*
G01X1167052Y67299D02*
Y72047D01*
G01X1166252Y66499D02*
X1167052Y67299D01*
G01X1166252Y53914D02*
Y66499D01*
G01X1166952Y53214D02*
X1166252Y53914D01*
G01X1166952Y48714D02*
Y53214D01*
G01X1166152Y47914D02*
X1166952Y48714D01*
G01X1166152Y35347D02*
Y47914D01*
G01X1167052Y34447D02*
X1166152Y35347D01*
G01X1174803Y56903D02*
Y54957D01*
G01X1176705Y58805D02*
X1174803Y56903D01*
G01X1176705Y66295D02*
Y58805D01*
G01X1175855Y67145D02*
X1176705Y66295D01*
G01X1175855Y72109D02*
Y67145D01*
G01X1176705Y72959D02*
X1175855Y72109D01*
G01X1176705Y85574D02*
Y72959D01*
G01X1175990Y86290D02*
X1176705Y85574D01*
G01X1175855Y86424D02*
X1175990Y86290D01*
G01X1175855Y91156D02*
Y86424D01*
G01X1176705Y92006D02*
X1175855Y91156D01*
G01X1176705Y105074D02*
Y92006D01*
G01X1176675Y34788D02*
X1177763Y33700D01*
G01X1176675Y37124D02*
Y34788D01*
G01X1175242Y38557D02*
X1176675Y37124D01*
G01X1175242Y39642D02*
Y38557D01*
G01X1175579Y39979D02*
X1175242Y39642D01*
G01X1176179Y39979D02*
X1175579D01*
G01X1176742Y40542D02*
X1176179Y39979D01*
G01X1176742Y42258D02*
Y40542D01*
G01X1176329Y42671D02*
X1176742Y42258D01*
G01X1175629Y42671D02*
X1176329D01*
G01X1175292Y43008D02*
X1175629Y42671D01*
G01X1175292Y44493D02*
Y43008D01*
G01X1176675Y45876D02*
X1175292Y44493D01*
G01X1176675Y48101D02*
Y45876D01*
G01X1175900Y48876D02*
X1176675Y48101D01*
G01X1175900Y53860D02*
Y48876D01*
G01X1174803Y54957D02*
X1175900Y53860D01*
G01X1197300Y54029D02*
X1198228Y54957D01*
G01X1197300Y50901D02*
Y54029D01*
G01X1200342Y47859D02*
X1197300Y50901D01*
G01X1200342Y46474D02*
Y47859D01*
G01X1198667Y44799D02*
X1200342Y46474D01*
G01X1198667Y43676D02*
Y44799D01*
G01X1200167Y42176D02*
X1198667Y43676D01*
G01X1200167Y40824D02*
Y42176D01*
G01X1198667Y39324D02*
X1200167Y40824D01*
G01X1198667Y38101D02*
Y39324D01*
G01X1200100Y36668D02*
X1198667Y38101D01*
G01X1200100Y35574D02*
Y36668D01*
G01X1201574Y34100D02*
X1200100Y35574D01*
G01X1200505Y92174D02*
Y104775D01*
G01X1199405Y91074D02*
X1200505Y92174D01*
G01X1199405Y86774D02*
Y91074D01*
G01X1200174Y86005D02*
X1199405Y86774D01*
G01X1200174Y73274D02*
Y86005D01*
G01X1199405Y72505D02*
X1200174Y73274D01*
G01X1199405Y67139D02*
Y72505D01*
G01X1200205Y66339D02*
X1199405Y67139D01*
G01X1200205Y56934D02*
Y66339D01*
G01X1198228Y54957D02*
X1200205Y56934D01*
G01X1163500Y91862D02*
Y105000D01*
G01X1162852Y91214D02*
X1163500Y91862D01*
G01X1162852Y86514D02*
Y91214D01*
G01X1163652Y85714D02*
X1162852Y86514D01*
G01X1163652Y82136D02*
Y85714D01*
G01X1162400Y80884D02*
X1163652Y82136D01*
G01X1162400Y78936D02*
Y80884D01*
G01X1163652Y77684D02*
X1162400Y78936D01*
G01X1163652Y73251D02*
Y77684D01*
G01X1162852Y72451D02*
X1163652Y73251D01*
G01X1162852Y66899D02*
Y72451D01*
G01X1163252Y66499D02*
X1162852Y66899D01*
G01X1163252Y63399D02*
Y66499D01*
G01X1162100Y62247D02*
X1163252Y63399D01*
G01X1162100Y60199D02*
Y62247D01*
G01X1163252Y59047D02*
X1162100Y60199D01*
G01X1163252Y53814D02*
Y59047D01*
G01X1162852Y53414D02*
X1163252Y53814D01*
G01X1162852Y48714D02*
Y53414D01*
G01X1163652Y47914D02*
X1162852Y48714D01*
G01X1163652Y45973D02*
Y47914D01*
G01X1162300Y44621D02*
X1163652Y45973D01*
G01X1162300Y42773D02*
Y44621D01*
G01X1163652Y41421D02*
X1162300Y42773D01*
G01X1163652Y35551D02*
Y41421D01*
G01X1162852Y34751D02*
X1163652Y35551D01*
G01X1242200Y119374D02*
X1170114Y191460D01*
G01X1160900Y139200D02*
X1159052D01*
G01X1174200Y125900D02*
X1160900Y139200D01*
G01X1174200Y114600D02*
Y125900D01*
G01X1172574Y112974D02*
X1174200Y114600D01*
G01X1172574Y111674D02*
Y112974D01*
G01X1173274Y110974D02*
X1172574Y111674D01*
G01X1173274Y105974D02*
Y110974D01*
G01X1172900Y105600D02*
X1173274Y105974D01*
G01X1168463Y189575D02*
X1238100Y119938D01*
G01X1204783Y116731D02*
X1213414Y108100D01*
G01X1203651Y116731D02*
X1204783D01*
G01X1202526Y115606D02*
X1203651Y116731D01*
G01X1201394Y115606D02*
X1202526D01*
G01X1200263Y116737D02*
X1201394Y115606D01*
G01X1200263Y117869D02*
Y116737D01*
G01X1201388Y118994D02*
X1200263Y117869D01*
G01X1201388Y120126D02*
Y118994D01*
G01X1200257Y121257D02*
X1201388Y120126D01*
G01X1199125Y121257D02*
X1200257D01*
G01X1198000Y120132D02*
X1199125Y121257D01*
G01X1196868Y120132D02*
X1198000D01*
G01X1195737Y121263D02*
X1196868Y120132D01*
G01X1195737Y122395D02*
Y121263D01*
G01X1196862Y123520D02*
X1195737Y122395D01*
G01X1196862Y124652D02*
Y123520D01*
G01X1195731Y125783D02*
X1196862Y124652D01*
G01X1194599Y125783D02*
X1195731D01*
G01X1193474Y124658D02*
X1194599Y125783D01*
G01X1192342Y124658D02*
X1193474D01*
G01X1191211Y125789D02*
X1192342Y124658D01*
G01X1191211Y126921D02*
Y125789D01*
G01X1192336Y128046D02*
X1191211Y126921D01*
G01X1192336Y129178D02*
Y128046D01*
G01X1191205Y130309D02*
X1192336Y129178D01*
G01X1190073Y130309D02*
X1191205D01*
G01X1188948Y129184D02*
X1190073Y130309D01*
G01X1187816Y129184D02*
X1188948D01*
G01X1186685Y130315D02*
X1187816Y129184D01*
G01X1186685Y131447D02*
Y130315D01*
G01X1187810Y132572D02*
X1186685Y131447D01*
G01X1187810Y133704D02*
Y132572D01*
G01X1181800Y139714D02*
X1187810Y133704D01*
G01X1181800Y147648D02*
Y139714D01*
G01X1218700Y95739D02*
X1220250Y94189D01*
G01X1219500Y98139D02*
X1218700Y97339D01*
G01Y102139D02*
X1219500Y101339D01*
G01Y104539D02*
X1218700Y103739D01*
G01X1197300Y131286D02*
X1221600Y106986D01*
G01X1197300Y132424D02*
Y131286D01*
G01X1198867Y133991D02*
X1197300Y132424D01*
G01X1198867Y134783D02*
Y133991D01*
G01X1197201Y136449D02*
X1198867Y134783D01*
G01X1196409Y136449D02*
X1197201D01*
G01X1194839Y134879D02*
X1196409Y136449D01*
G01X1193707Y134879D02*
X1194839D01*
G01X1192576Y136010D02*
X1193707Y134879D01*
G01X1192576Y137142D02*
Y136010D01*
G01X1195154Y139720D02*
X1192576Y137142D01*
G01X1195154Y141366D02*
Y139720D01*
G01X1158490Y178030D02*
X1195154Y141366D01*
G01X1201574Y107314D02*
X1203005Y105883D01*
G01X1181496Y106733D02*
X1183305Y104924D01*
G01X1181496Y112357D02*
Y106733D01*
G01X1188657Y136393D02*
X1216000Y109050D01*
G01X1188657Y137525D02*
Y136393D01*
G01X1191349Y140217D02*
X1188657Y137525D01*
G01X1191349Y141349D02*
Y140217D01*
G01X1190218Y142480D02*
X1191349Y141349D01*
G01X1189086Y142480D02*
X1190218D01*
G01X1187974Y141368D02*
X1189086Y142480D01*
G01X1187182Y141368D02*
X1187974D01*
G01X1184300Y144250D02*
X1187182Y141368D01*
G01X1184300Y148684D02*
Y144250D01*
G01X1208267Y107314D02*
X1209505Y106076D01*
G01X1179505Y105658D02*
X1177849Y107314D01*
G01X1171765Y193345D02*
X1246625Y118485D01*
G01X1186055Y105051D02*
X1184142Y106964D01*
G01X1204921Y110727D02*
Y112357D01*
G01X1206274Y109374D02*
X1204921Y110727D01*
G01X1206274Y105585D02*
Y109374D01*
G01X1206905Y104954D02*
X1206274Y105585D01*
G01X1158051Y135945D02*
X1156919D01*
G01X1158737Y136631D02*
X1158051Y135945D01*
G01X1159869Y136631D02*
X1158737D01*
G01X1161000Y135500D02*
X1159869Y136631D01*
G01X1161000Y134368D02*
Y135500D01*
G01X1160314Y133682D02*
X1161000Y134368D01*
G01X1160314Y132550D02*
Y133682D01*
G01X1161445Y131419D02*
X1160314Y132550D01*
G01X1162577Y131419D02*
X1161445D01*
G01X1163263Y132105D02*
X1162577Y131419D01*
G01X1164395Y132105D02*
X1163263D01*
G01X1165526Y130974D02*
X1164395Y132105D01*
G01X1165526Y129842D02*
Y130974D01*
G01X1164840Y129156D02*
X1165526Y129842D01*
G01X1164840Y128024D02*
Y129156D01*
G01X1171700Y121164D02*
X1164840Y128024D01*
G01X1171700Y115400D02*
Y121164D01*
G01X1170074Y113774D02*
X1171700Y115400D01*
G01X1170074Y111774D02*
Y113774D01*
G01X1168700Y110400D02*
X1170074Y111774D01*
G01X1168700Y106300D02*
Y110400D01*
G01X1170452Y104548D02*
X1168700Y106300D01*
G01X1167000Y114300D02*
Y122328D01*
G01X1166000Y113300D02*
X1167000Y114300D01*
G01X1166000Y111648D02*
Y113300D01*
G01X1166874Y110774D02*
X1166000Y111648D01*
G01X1166874Y106274D02*
Y110774D01*
G01X1166000Y105400D02*
X1166874Y106274D01*
G01X1167400Y186917D02*
X1222400Y132101D01*
G01X1175874Y105905D02*
X1176705Y105074D01*
G01X1175874Y111286D02*
Y105905D01*
G01X1174803Y112357D02*
X1175874Y111286D01*
G01X1174742Y112357D02*
X1174803D01*
G01X1198228Y110121D02*
Y112357D01*
G01X1199024Y109324D02*
X1198228Y110121D01*
G01X1199285Y109064D02*
X1199024Y109324D01*
G01X1199285Y105995D02*
Y109064D01*
G01X1200505Y104775D02*
X1199285Y105995D01*
G01X1162100Y122900D02*
Y123692D01*
G01X1161300Y122100D02*
X1162100Y122900D01*
G01X1161300Y120944D02*
Y122100D01*
G01X1162100Y120144D02*
X1161300Y120944D01*
G01X1164540Y120144D02*
X1162100D01*
G01X1165100Y119584D02*
X1164540Y120144D01*
G01X1165100Y117504D02*
Y119584D01*
G01X1164540Y116944D02*
X1165100Y117504D01*
G01X1162176Y116944D02*
X1164540D01*
G01X1161438Y116206D02*
X1162176Y116944D01*
G01X1161438Y115162D02*
Y116206D01*
G01X1163500Y113100D02*
X1161438Y115162D01*
G01X1163500Y111400D02*
Y113100D01*
G01X1162400Y110300D02*
X1163500Y111400D01*
G01X1162400Y106100D02*
Y110300D01*
G01X1163500Y105000D02*
X1162400Y106100D01*
G01X1200833Y131289D02*
X1224100Y108022D01*
G01X1200833Y132422D02*
Y131289D01*
G01X1201900Y133489D02*
X1200833Y132422D01*
G01X1201900Y138156D02*
Y133489D01*
G01X1160141Y179915D02*
X1201900Y138156D01*
G01X1170114Y191460D02*
X1161423D01*
G01X1160641Y189575D02*
X1168463D01*
G01X1162204Y193345D02*
X1171765D01*
G01X1166624Y187690D02*
X1167400Y186917D01*
G01X1159860Y187690D02*
X1166624D01*
G01X1193096Y464127D02*
Y464989D01*
G01X1157119Y428150D02*
X1193096Y464127D01*
G01X1211827Y461664D02*
X1162954Y412791D01*
G01X1217892Y461664D02*
X1211827D01*
G01X1245744Y489516D02*
X1217892Y461664D01*
G01X1217258Y464264D02*
X1243545Y490551D01*
G01X1211627Y464264D02*
X1217258D01*
G01X1162663Y415300D02*
X1211627Y464264D01*
G01X1157166Y450700D02*
X1179008Y472542D01*
G01X1161963Y417400D02*
X1211671Y467108D01*
G01X1161113Y419350D02*
X1211523Y469760D01*
G01X1174600Y498784D02*
X1174203Y498387D01*
G01X1174600Y505978D02*
Y498784D01*
G01X1176863Y508241D02*
X1174600Y505978D01*
G01X1176863Y510757D02*
Y508241D01*
G01X1175863Y511757D02*
X1176863Y510757D01*
G01X1175863Y516507D02*
Y511757D01*
G01X1176763Y517407D02*
X1175863Y516507D01*
G01X1176763Y519500D02*
Y517407D01*
G01X1176500Y519763D02*
X1176763Y519500D01*
G01X1176500Y527800D02*
Y519763D01*
G01X1186500Y519401D02*
Y528100D01*
G01X1186063Y518964D02*
X1186500Y519401D01*
G01X1186063Y507641D02*
Y518964D01*
G01X1183374Y504952D02*
X1186063Y507641D01*
G01X1183374Y494162D02*
Y504952D01*
G01X1184142Y493394D02*
X1183374Y494162D01*
G01X1199496Y470527D02*
X1222874Y493905D01*
G01X1198634Y470527D02*
X1199496D01*
G01X1196128Y473033D02*
X1198634Y470527D01*
G01X1195266Y473033D02*
X1196128D01*
G01X1194282Y472049D02*
X1195266Y473033D01*
G01X1194282Y471187D02*
Y472049D01*
G01X1196788Y468681D02*
X1194282Y471187D01*
G01X1196788Y467819D02*
Y468681D01*
G01X1195804Y466835D02*
X1196788Y467819D01*
G01X1194942Y466835D02*
X1195804D01*
G01X1192436Y469341D02*
X1194942Y466835D01*
G01X1191574Y469341D02*
X1192436D01*
G01X1190590Y468357D02*
X1191574Y469341D01*
G01X1190590Y467495D02*
Y468357D01*
G01X1193096Y464989D02*
X1190590Y467495D01*
G01X1169800Y519702D02*
Y527800D01*
G01X1170300Y519202D02*
X1169800Y519702D01*
G01X1170300Y517805D02*
Y519202D01*
G01X1169552Y517057D02*
X1170300Y517805D01*
G01X1169552Y511657D02*
Y517057D01*
G01X1170052Y511157D02*
X1169552Y511657D01*
G01X1170052Y497830D02*
Y511157D01*
G01X1169300Y497078D02*
X1170052Y497830D01*
G01X1169300Y495200D02*
Y497078D01*
G01X1168700Y494600D02*
X1169300Y495200D01*
G01X1168700Y488232D02*
Y494600D01*
G01X1165158Y484690D02*
X1168700Y488232D01*
G01X1165158Y479838D02*
Y484690D01*
G01X1213300Y519474D02*
Y527800D01*
G01X1213574Y519200D02*
X1213300Y519474D01*
G01X1213574Y517357D02*
Y519200D01*
G01X1212674Y516457D02*
X1213574Y517357D01*
G01X1212674Y511757D02*
Y516457D01*
G01X1213674Y510757D02*
X1212674Y511757D01*
G01X1213674Y495790D02*
Y510757D01*
G01X1202705Y484821D02*
X1213674Y495790D01*
G01X1184525Y484821D02*
X1202705D01*
G01X1203200Y519537D02*
Y527900D01*
G01X1203063Y519400D02*
X1203200Y519537D01*
G01X1203063Y517357D02*
Y519400D01*
G01X1203863Y516557D02*
X1203063Y517357D01*
G01X1203863Y512157D02*
Y516557D01*
G01X1202963Y511257D02*
X1203863Y512157D01*
G01X1202963Y501641D02*
Y511257D01*
G01X1200974Y499652D02*
X1202963Y501641D01*
G01X1200974Y493344D02*
Y499652D01*
G01X1183200Y519763D02*
Y527600D01*
G01X1183363Y519600D02*
X1183200Y519763D01*
G01X1183363Y517457D02*
Y519600D01*
G01X1182213Y516307D02*
X1183363Y517457D01*
G01X1182213Y512057D02*
Y516307D01*
G01X1183563Y510707D02*
X1182213Y512057D01*
G01X1183563Y508677D02*
Y510707D01*
G01X1181496Y506610D02*
X1183563Y508677D01*
G01X1181496Y499483D02*
Y506610D01*
G01X1180400Y498387D02*
X1181496Y499483D01*
G01X1210000Y520087D02*
Y527600D01*
G01X1209713Y519800D02*
X1210000Y520087D01*
G01X1209713Y517357D02*
Y519800D01*
G01X1210263Y516807D02*
X1209713Y517357D01*
G01X1210263Y512257D02*
Y516807D01*
G01X1209663Y511657D02*
X1210263Y512257D01*
G01X1209663Y497540D02*
Y511657D01*
G01X1208267Y496144D02*
X1209663Y497540D01*
G01X1203299Y477397D02*
X1220374Y494472D01*
G01X1179008Y472542D02*
X1203299Y477397D01*
G01X1166400Y519348D02*
Y527800D01*
G01X1166252Y519200D02*
X1166400Y519348D01*
G01X1166252Y517357D02*
Y519200D01*
G01X1167052Y516557D02*
X1166252Y517357D01*
G01X1167052Y512157D02*
Y516557D01*
G01X1166152Y511257D02*
X1167052Y512157D01*
G01X1166152Y504352D02*
Y511257D01*
G01X1165300Y503500D02*
X1166152Y504352D01*
G01X1165300Y495200D02*
Y503500D01*
G01X1166152Y494348D02*
X1165300Y495200D01*
G01X1166152Y489291D02*
Y494348D01*
G01X1163169Y486308D02*
X1166152Y489291D01*
G01X1163169Y480925D02*
Y486308D01*
G01X1157838Y475594D02*
X1163169Y480925D01*
G01X1217080Y467108D02*
X1239831Y489859D01*
G01X1211671Y467108D02*
X1217080D01*
G01X1216700Y519926D02*
Y527500D01*
G01X1216274Y519500D02*
X1216700Y519926D01*
G01X1216274Y517457D02*
Y519500D01*
G01X1216600Y517131D02*
X1216274Y517457D01*
G01X1216600Y511399D02*
Y517131D01*
G01X1216174Y510973D02*
X1216600Y511399D01*
G01X1216174Y493346D02*
Y510973D01*
G01X1205006Y482178D02*
X1216174Y493346D01*
G01X1202017Y482178D02*
X1205006D01*
G01X1201407Y481568D02*
X1202017Y482178D01*
G01X1201407Y480022D02*
Y481568D01*
G01X1200797Y479412D02*
X1201407Y480022D01*
G01X1199407Y479412D02*
X1200797D01*
G01X1198797Y480022D02*
X1199407Y479412D01*
G01X1198797Y481568D02*
Y480022D01*
G01X1198187Y482178D02*
X1198797Y481568D01*
G01X1196797Y482178D02*
X1198187D01*
G01X1196187Y481568D02*
X1196797Y482178D01*
G01X1196187Y480022D02*
Y481568D01*
G01X1195577Y479412D02*
X1196187Y480022D01*
G01X1194187Y479412D02*
X1195577D01*
G01X1193577Y480022D02*
X1194187Y479412D01*
G01X1193577Y481568D02*
Y480022D01*
G01X1192967Y482178D02*
X1193577Y481568D01*
G01X1185277Y482178D02*
X1192967D01*
G01X1173100Y519598D02*
Y527800D01*
G01X1172902Y519400D02*
X1173100Y519598D01*
G01X1172902Y517357D02*
Y519400D01*
G01X1173452Y516807D02*
X1172902Y517357D01*
G01X1173452Y512257D02*
Y516807D01*
G01X1172852Y511657D02*
X1173452Y512257D01*
G01X1172852Y503300D02*
Y511657D01*
G01X1172400Y502848D02*
X1172852Y503300D01*
G01X1172400Y492100D02*
Y502848D01*
G01X1173006Y491494D02*
X1172400Y492100D01*
G01X1173006Y484837D02*
Y491494D01*
G01X1171784Y483615D02*
X1173006Y484837D01*
G01X1170855Y483615D02*
X1171784D01*
G01X1170050Y484420D02*
X1170855Y483615D01*
G01X1169342Y484420D02*
X1170050D01*
G01X1168204Y483282D02*
X1169342Y484420D01*
G01X1168204Y482574D02*
Y483282D01*
G01X1169182Y481596D02*
X1168204Y482574D01*
G01X1169182Y480734D02*
Y481596D01*
G01X1166375Y477927D02*
X1169182Y480734D01*
G01X1166375Y477065D02*
Y477927D01*
G01X1166950Y476490D02*
X1166375Y477065D01*
G01X1166950Y475782D02*
Y476490D01*
G01X1165812Y474644D02*
X1166950Y475782D01*
G01X1165104Y474644D02*
X1165812D01*
G01X1164529Y475219D02*
X1165104Y474644D01*
G01X1163667Y475219D02*
X1164529D01*
G01X1179800Y519537D02*
Y527600D01*
G01X1179463Y519200D02*
X1179800Y519537D01*
G01X1179463Y517457D02*
Y519200D01*
G01X1179713Y517207D02*
X1179463Y517457D01*
G01X1179713Y511791D02*
Y517207D01*
G01X1179363Y511441D02*
X1179713Y511791D01*
G01X1179363Y506040D02*
Y511441D01*
G01X1177799Y504476D02*
X1179363Y506040D01*
G01X1177799Y493544D02*
Y504476D01*
G01X1204521Y498487D02*
X1204400D01*
G01X1206863Y500829D02*
X1204521Y498487D01*
G01X1206863Y511157D02*
Y500829D01*
G01X1206363Y511657D02*
X1206863Y511157D01*
G01X1206363Y517057D02*
Y511657D01*
G01X1207163Y517857D02*
X1206363Y517057D01*
G01X1207163Y519500D02*
Y517857D01*
G01X1206597Y520066D02*
X1207163Y519500D01*
G01X1206597Y527697D02*
Y520066D01*
G01X1216442Y469760D02*
X1235429Y488747D01*
G01X1211523Y469760D02*
X1216442D01*
G01X1163100Y519552D02*
Y527800D01*
G01X1163252Y519400D02*
X1163100Y519552D01*
G01X1163252Y517357D02*
Y519400D01*
G01X1162852Y516957D02*
X1163252Y517357D01*
G01X1162852Y512057D02*
Y516957D01*
G01X1163652Y511257D02*
X1162852Y512057D01*
G01X1163652Y505052D02*
Y511257D01*
G01X1163100Y504500D02*
X1163652Y505052D01*
G01X1163100Y495200D02*
Y504500D01*
G01X1161600Y493700D02*
X1163100Y495200D01*
G01X1161600Y487894D02*
Y493700D01*
G01X1161101Y487395D02*
X1161600Y487894D01*
G01X1161101Y481721D02*
Y487395D01*
G01X1157149Y477769D02*
X1161101Y481721D01*
G01X1198228Y498528D02*
X1198100Y498400D01*
G01X1198228Y502606D02*
Y498528D01*
G01X1200463Y504841D02*
X1198228Y502606D01*
G01X1200463Y511257D02*
Y504841D01*
G01X1199663Y512057D02*
X1200463Y511257D01*
G01X1199663Y516957D02*
Y512057D01*
G01X1200263Y517557D02*
X1199663Y516957D01*
G01X1200263Y519500D02*
Y517557D01*
G01X1199900Y519863D02*
X1200263Y519500D01*
G01X1199900Y527700D02*
Y519863D01*
G01X1176763Y528063D02*
X1176500Y527800D01*
G01X1176763Y529437D02*
Y528063D01*
G01X1175715Y530485D02*
X1176763Y529437D01*
G01X1175715Y535144D02*
Y530485D01*
G01X1176713Y536142D02*
X1175715Y535144D01*
G01X1176713Y537800D02*
Y536142D01*
G01X1176500Y538013D02*
X1176713Y537800D01*
G01X1176500Y547200D02*
Y538013D01*
G01X1176713Y547413D02*
X1176500Y547200D01*
G01X1176713Y548657D02*
Y547413D01*
G01X1184142Y550564D02*
Y550914D01*
G01X1186063Y548643D02*
X1184142Y550564D01*
G01X1186063Y546837D02*
Y548643D01*
G01X1186500Y546400D02*
X1186063Y546837D01*
G01X1186500Y538137D02*
Y546400D01*
G01X1186063Y537700D02*
X1186500Y538137D01*
G01X1186063Y528537D02*
Y537700D01*
G01X1186500Y528100D02*
X1186063Y528537D01*
G01X1219287Y566699D02*
X1218307D01*
G01X1170152Y586507D02*
X1168110Y588549D01*
G01X1170152Y574042D02*
Y586507D01*
G01X1169252Y573142D02*
X1170152Y574042D01*
G01X1169252Y568397D02*
Y573142D01*
G01X1170352Y567297D02*
X1169252Y568397D01*
G01X1170352Y566052D02*
Y567297D01*
G01X1169785Y565485D02*
X1170352Y566052D01*
G01X1169785Y557567D02*
Y565485D01*
G01X1170352Y557000D02*
X1169785Y557567D01*
G01X1170352Y555657D02*
Y557000D01*
G01X1169552Y554857D02*
X1170352Y555657D01*
G01X1169552Y549457D02*
Y554857D01*
G01X1170052Y548957D02*
X1169552Y549457D01*
G01X1170052Y546652D02*
Y548957D01*
G01X1169800Y546400D02*
X1170052Y546652D01*
G01X1169800Y537952D02*
Y546400D01*
G01X1170052Y537700D02*
X1169800Y537952D01*
G01X1170052Y536552D02*
Y537700D01*
G01X1169452Y535952D02*
X1170052Y536552D01*
G01X1169452Y530238D02*
Y535952D01*
G01X1170402Y529288D02*
X1169452Y530238D01*
G01X1170402Y528402D02*
Y529288D01*
G01X1169800Y527800D02*
X1170402Y528402D01*
G01X1213586Y572500D02*
X1214574D01*
G01X1210531Y569445D02*
X1213586Y572500D01*
G01X1210531Y568257D02*
Y569445D01*
G01X1209909Y567635D02*
X1210531Y568257D01*
G01X1209909Y557662D02*
Y567635D01*
G01X1211614Y555957D02*
X1209909Y557662D01*
G01X1210374Y554717D02*
X1211614Y555957D01*
G01X1210374Y551807D02*
Y554717D01*
G01X1213524Y548657D02*
X1210374Y551807D01*
G01X1213524Y546524D02*
Y548657D01*
G01X1213300Y546300D02*
X1213524Y546524D01*
G01X1213300Y538124D02*
Y546300D01*
G01X1213524Y537900D02*
X1213300Y538124D01*
G01X1213524Y536142D02*
Y537900D01*
G01X1212526Y535144D02*
X1213524Y536142D01*
G01X1212526Y530473D02*
Y535144D01*
G01X1213574Y529425D02*
X1212526Y530473D01*
G01X1213574Y528074D02*
Y529425D01*
G01X1213300Y527800D02*
X1213574Y528074D01*
G01X1202920Y549568D02*
X1201574Y550914D01*
G01X1202963Y549568D02*
X1202920D01*
G01X1202963Y546837D02*
Y549568D01*
G01X1203300Y546500D02*
X1202963Y546837D01*
G01X1203300Y538137D02*
Y546500D01*
G01X1202963Y537800D02*
X1203300Y538137D01*
G01X1202963Y536237D02*
Y537800D01*
G01X1203629Y535571D02*
X1202963Y536237D01*
G01X1203629Y530363D02*
Y535571D01*
G01X1203063Y529797D02*
X1203629Y530363D01*
G01X1203063Y528037D02*
Y529797D01*
G01X1203200Y527900D02*
X1203063Y528037D01*
G01X1180063Y554524D02*
X1181496Y555957D01*
G01X1180063Y552007D02*
Y554524D01*
G01X1183413Y548657D02*
X1180063Y552007D01*
G01X1183413Y547313D02*
Y548657D01*
G01X1183200Y547100D02*
X1183413Y547313D01*
G01X1183200Y538113D02*
Y547100D01*
G01X1183413Y537900D02*
X1183200Y538113D01*
G01X1183413Y536413D02*
Y537900D01*
G01X1182263Y535263D02*
X1183413Y536413D01*
G01X1182263Y530567D02*
Y535263D01*
G01X1183363Y529467D02*
X1182263Y530567D01*
G01X1183363Y527763D02*
Y529467D01*
G01X1183200Y527600D02*
X1183363Y527763D01*
G01X1208267Y550966D02*
Y550914D01*
G01X1209563Y549670D02*
X1208267Y550966D01*
G01X1209563Y546237D02*
Y549670D01*
G01X1209900Y545900D02*
X1209563Y546237D01*
G01X1209900Y537937D02*
Y545900D01*
G01X1209563Y537600D02*
X1209900Y537937D01*
G01X1209563Y536338D02*
Y537600D01*
G01X1210563Y535338D02*
X1209563Y536338D01*
G01X1210563Y530697D02*
Y535338D01*
G01X1209713Y529847D02*
X1210563Y530697D01*
G01X1209713Y527887D02*
Y529847D01*
G01X1210000Y527600D02*
X1209713Y527887D01*
G01X1217400Y555050D02*
X1218307Y555957D01*
G01X1217400Y551481D02*
Y555050D01*
G01X1220224Y548657D02*
X1217400Y551481D01*
G01X1216602Y569315D02*
X1219787Y572500D01*
G01X1216602Y557662D02*
Y569315D01*
G01X1218307Y555957D02*
X1216602Y557662D01*
G01X1166109Y587368D02*
X1164763Y588714D01*
G01X1166152Y587368D02*
X1166109D01*
G01X1166152Y574147D02*
Y587368D01*
G01X1166818Y573481D02*
X1166152Y574147D01*
G01X1166818Y568163D02*
Y573481D01*
G01X1166252Y567597D02*
X1166818Y568163D01*
G01X1166252Y565548D02*
Y567597D01*
G01X1166500Y565300D02*
X1166252Y565548D01*
G01X1166500Y557699D02*
Y565300D01*
G01X1165952Y557151D02*
X1166500Y557699D01*
G01X1165952Y555457D02*
Y557151D01*
G01X1167052Y554357D02*
X1165952Y555457D01*
G01X1167052Y549957D02*
Y554357D01*
G01X1166152Y549057D02*
X1167052Y549957D01*
G01X1166152Y546248D02*
Y549057D01*
G01X1166500Y545900D02*
X1166152Y546248D01*
G01X1166500Y538100D02*
Y545900D01*
G01X1166152Y537752D02*
X1166500Y538100D01*
G01X1166152Y536348D02*
Y537752D01*
G01X1166952Y535548D02*
X1166152Y536348D01*
G01X1166952Y530350D02*
Y535548D01*
G01X1166252Y529650D02*
X1166952Y530350D01*
G01X1166252Y527948D02*
Y529650D01*
G01X1166400Y527800D02*
X1166252Y527948D01*
G01X1212686Y566699D02*
X1211614D01*
G01X1213286Y566099D02*
X1212686Y566699D01*
G01X1213286Y565201D02*
Y566099D01*
G01X1212249Y564164D02*
X1213286Y565201D01*
G01X1212249Y562936D02*
Y564164D01*
G01X1213186Y561999D02*
X1212249Y562936D01*
G01X1213186Y560601D02*
Y561999D01*
G01X1212249Y559664D02*
X1213186Y560601D01*
G01X1212249Y558336D02*
Y559664D01*
G01X1213386Y557199D02*
X1212249Y558336D01*
G01X1213386Y555300D02*
Y557199D01*
G01X1212886Y554800D02*
X1213386Y555300D01*
G01X1212886Y552600D02*
Y554800D01*
G01X1214874Y550612D02*
X1212886Y552600D01*
G01X1214874Y550574D02*
Y550612D01*
G01X1215000Y550574D02*
X1214874D01*
G01X1216174Y549400D02*
X1215000Y550574D01*
G01X1216174Y547026D02*
Y549400D01*
G01X1216600Y546600D02*
X1216174Y547026D01*
G01X1216600Y538026D02*
Y546600D01*
G01X1216174Y537600D02*
X1216600Y538026D01*
G01X1216174Y535456D02*
Y537600D01*
G01X1216774Y534856D02*
X1216174Y535456D01*
G01X1216774Y530697D02*
Y534856D01*
G01X1216274Y530197D02*
X1216774Y530697D01*
G01X1216274Y527926D02*
Y530197D01*
G01X1216700Y527500D02*
X1216274Y527926D01*
G01X1172752Y587470D02*
X1171456Y588766D01*
G01X1172752Y574248D02*
Y587470D01*
G01X1173752Y573248D02*
X1172752Y574248D01*
G01X1173752Y568497D02*
Y573248D01*
G01X1172400Y567145D02*
X1173752Y568497D01*
G01X1172400Y555659D02*
Y567145D01*
G01X1172852Y546948D02*
Y549457D01*
G01X1173100Y546700D02*
X1172852Y546948D01*
G01X1173100Y537748D02*
Y546700D01*
G01X1172852Y537500D02*
X1173100Y537748D01*
G01X1172852Y536148D02*
Y537500D01*
G01X1173552Y535448D02*
X1172852Y536148D01*
G01X1173552Y530258D02*
Y535448D01*
G01X1172902Y529608D02*
X1173552Y530258D01*
G01X1172902Y527998D02*
Y529608D01*
G01X1173100Y527800D02*
X1172902Y527998D01*
G01X1179363Y549400D02*
X1177849Y550914D01*
G01X1179363Y546837D02*
Y549400D01*
G01X1179800Y546400D02*
X1179363Y546837D01*
G01X1179800Y537937D02*
Y546400D01*
G01X1179363Y537500D02*
X1179800Y537937D01*
G01X1179363Y535456D02*
Y537500D01*
G01X1179963Y534856D02*
X1179363Y535456D01*
G01X1179963Y530697D02*
Y534856D01*
G01X1179463Y530197D02*
X1179963Y530697D01*
G01X1179463Y527937D02*
Y530197D01*
G01X1179800Y527600D02*
X1179463Y527937D01*
G01X1207163Y528263D02*
X1206597Y527697D01*
G01X1207163Y529497D02*
Y528263D01*
G01X1206063Y530597D02*
X1207163Y529497D01*
G01X1206063Y535342D02*
Y530597D01*
G01X1206963Y536242D02*
X1206063Y535342D01*
G01X1206963Y537636D02*
Y536242D01*
G01X1206600Y537999D02*
X1206963Y537636D01*
G01X1206600Y546300D02*
Y537999D01*
G01X1206963Y546663D02*
X1206600Y546300D01*
G01X1206963Y548707D02*
Y546663D01*
G01X1203563Y552107D02*
X1206963Y548707D01*
G01X1203563Y554599D02*
Y552107D01*
G01X1204921Y555957D02*
X1203563Y554599D01*
G01X1163652Y586357D02*
X1161417Y588592D01*
G01X1163652Y574242D02*
Y586357D01*
G01X1162379Y572969D02*
X1163652Y574242D01*
G01X1162379Y568470D02*
Y572969D01*
G01X1163452Y567397D02*
X1162379Y568470D01*
G01X1163452Y565952D02*
Y567397D01*
G01X1163100Y565600D02*
X1163452Y565952D01*
G01X1163100Y557352D02*
Y565600D01*
G01X1163452Y557000D02*
X1163100Y557352D01*
G01X1163452Y555357D02*
Y557000D01*
G01X1162852Y554757D02*
X1163452Y555357D01*
G01X1162852Y549857D02*
Y554757D01*
G01X1163652Y549057D02*
X1162852Y549857D01*
G01X1163652Y547552D02*
Y549057D01*
G01X1163085Y546985D02*
X1163652Y547552D01*
G01X1163085Y538067D02*
Y546985D01*
G01X1163652Y537500D02*
X1163085Y538067D01*
G01X1163652Y536552D02*
Y537500D01*
G01X1162852Y535752D02*
X1163652Y536552D01*
G01X1162852Y530050D02*
Y535752D01*
G01X1163252Y529650D02*
X1162852Y530050D01*
G01X1163252Y527952D02*
Y529650D01*
G01X1163100Y527800D02*
X1163252Y527952D01*
G01X1200263Y528063D02*
X1199900Y527700D01*
G01X1200263Y529597D02*
Y528063D01*
G01X1199190Y530670D02*
X1200263Y529597D01*
G01X1199190Y535169D02*
Y530670D01*
G01X1200200Y536179D02*
X1199190Y535169D01*
G01X1200200Y537963D02*
Y536179D01*
G01X1199900Y538263D02*
X1200200Y537963D01*
G01X1199900Y546600D02*
Y538263D01*
G01X1200463Y547163D02*
X1199900Y546600D01*
G01X1200463Y548557D02*
Y547163D01*
G01X1197563Y551457D02*
X1200463Y548557D01*
G01X1197563Y555292D02*
Y551457D01*
G01X1198228Y555957D02*
X1197563Y555292D01*
G01X1168110Y588549D02*
Y593757D01*
G01X1171456Y588766D02*
Y588714D01*
G01X1161417Y588592D02*
Y593757D01*
G01X1236286Y29146D02*
X1235039Y27899D01*
G01X1236286Y30400D02*
Y29146D01*
G01X1237586Y31700D02*
X1236286Y30400D01*
G01X1238586Y31700D02*
X1237586D01*
G01X1240386Y33500D02*
X1238586Y31700D01*
G01X1242979Y29146D02*
X1241732Y27899D01*
G01X1242979Y30400D02*
Y29146D01*
G01X1244279Y31700D02*
X1242979Y30400D01*
G01X1245279Y31700D02*
X1244279D01*
G01X1247079Y33500D02*
X1245279Y31700D01*
G01X1221586Y31900D02*
X1220186D01*
G01X1223042Y33356D02*
X1221586Y31900D01*
G01X1240611Y53836D02*
X1241732Y54957D01*
G01X1240611Y50900D02*
Y53836D01*
G01X1243953Y47558D02*
X1240611Y50900D01*
G01X1243953Y46500D02*
Y47558D01*
G01X1242153Y44700D02*
X1243953Y46500D01*
G01X1242153Y43125D02*
Y44700D01*
G01X1243353Y41925D02*
X1242153Y43125D01*
G01X1243353Y40799D02*
Y41925D01*
G01X1242153Y39599D02*
X1243353Y40799D01*
G01X1242153Y38226D02*
Y39599D01*
G01X1243511Y36868D02*
X1242153Y38226D01*
G01X1243511Y35667D02*
Y36868D01*
G01X1245078Y34100D02*
X1243511Y35667D01*
G01X1243600Y91644D02*
Y96918D01*
G01X1243074Y91118D02*
X1243600Y91644D01*
G01X1243074Y86418D02*
Y91118D01*
G01X1243674Y85818D02*
X1243074Y86418D01*
G01X1243674Y73075D02*
Y85818D01*
G01X1243174Y72575D02*
X1243674Y73075D01*
G01X1243174Y66803D02*
Y72575D01*
G01X1243974Y66003D02*
X1243174Y66803D01*
G01X1243974Y58375D02*
Y66003D01*
G01X1241732Y56133D02*
X1243974Y58375D01*
G01X1241732Y54957D02*
Y56133D01*
G01X1236474Y51825D02*
X1238385Y49914D01*
G01X1236474Y53644D02*
Y51825D01*
G01X1238024Y55194D02*
X1236474Y53644D01*
G01X1238024Y56632D02*
Y55194D01*
G01X1239800Y58408D02*
X1238024Y56632D01*
G01X1239800Y66379D02*
Y58408D01*
G01X1240200Y66779D02*
X1239800Y66379D01*
G01X1240200Y72701D02*
Y66779D01*
G01X1239774Y73127D02*
X1240200Y72701D01*
G01X1239774Y85718D02*
Y73127D01*
G01X1240574Y86518D02*
X1239774Y85718D01*
G01X1240574Y91018D02*
Y86518D01*
G01X1239900Y91692D02*
X1240574Y91018D01*
G01X1239900Y110099D02*
Y91692D01*
G01X1240386Y34900D02*
Y33500D01*
G01X1239774Y35512D02*
X1240386Y34900D01*
G01X1239774Y48525D02*
Y35512D01*
G01X1238385Y49914D02*
X1239774Y48525D01*
G01X1220086Y34567D02*
X1220953Y33700D01*
G01X1220086Y36868D02*
Y34567D01*
G01X1219803Y42050D02*
Y41150D01*
G01X1220086Y48000D02*
Y46032D01*
G01X1220174Y66244D02*
Y64674D01*
G01X1219024Y67394D02*
X1220174Y66244D01*
G01X1219024Y72123D02*
Y67394D01*
G01X1220374Y73473D02*
X1219024Y72123D01*
G01X1220374Y85368D02*
Y73473D01*
G01X1219024Y86718D02*
X1220374Y85368D01*
G01X1219024Y90897D02*
Y86718D01*
G01X1220246Y92119D02*
X1219024Y90897D01*
G01X1220250Y92119D02*
X1220246D01*
G01X1220250Y94189D02*
Y92119D01*
G01X1247079Y34900D02*
Y33500D01*
G01X1246467Y35512D02*
X1247079Y34900D01*
G01X1246467Y48525D02*
Y35512D01*
G01X1245078Y49914D02*
X1246467Y48525D01*
G01X1243174Y51818D02*
X1245078Y49914D01*
G01X1243174Y53418D02*
Y51818D01*
G01X1246524Y56768D02*
X1243174Y53418D01*
G01X1246524Y66503D02*
Y56768D01*
G01X1247074Y67053D02*
X1246524Y66503D01*
G01X1247074Y72627D02*
Y67053D01*
G01X1246474Y73227D02*
X1247074Y72627D01*
G01X1246474Y85918D02*
Y73227D01*
G01X1247174Y86618D02*
X1246474Y85918D01*
G01X1247174Y91018D02*
Y86618D01*
G01X1246625Y91567D02*
X1247174Y91018D01*
G01X1246625Y118485D02*
Y91567D01*
G01X1236911Y35574D02*
X1238385Y34100D01*
G01X1236911Y36668D02*
Y35574D01*
G01X1235478Y38101D02*
X1236911Y36668D01*
G01X1235478Y39324D02*
Y38101D01*
G01X1236978Y40824D02*
X1235478Y39324D01*
G01X1236978Y42176D02*
Y40824D01*
G01X1235478Y43676D02*
X1236978Y42176D01*
G01X1235478Y44799D02*
Y43676D01*
G01X1237153Y46474D02*
X1235478Y44799D01*
G01X1237153Y47859D02*
Y46474D01*
G01X1234111Y50901D02*
X1237153Y47859D01*
G01X1234111Y54029D02*
Y50901D01*
G01X1235039Y54957D02*
X1234111Y54029D01*
G01X1235039Y57183D02*
Y54957D01*
G01X1236900Y59044D02*
X1235039Y57183D01*
G01X1236900Y66477D02*
Y59044D01*
G01X1236474Y66903D02*
X1236900Y66477D01*
G01X1236474Y72575D02*
Y66903D01*
G01X1237274Y73375D02*
X1236474Y72575D01*
G01X1237274Y85718D02*
Y73375D01*
G01X1236474Y86518D02*
X1237274Y85718D01*
G01X1236474Y91218D02*
Y86518D01*
G01X1236839Y91583D02*
X1236474Y91218D01*
G01X1236839Y94235D02*
Y91583D01*
G01X1235600Y95474D02*
X1236839Y94235D01*
G01X1223042Y34700D02*
Y33356D01*
G01X1222426Y35316D02*
X1223042Y34700D01*
G01X1222426Y48441D02*
Y35316D01*
G01X1220953Y49914D02*
X1222426Y48441D01*
G01X1218880Y51987D02*
X1220953Y49914D01*
G01X1218880Y53080D02*
Y51987D01*
G01X1220374Y54574D02*
X1218880Y53080D01*
G01X1220374Y61674D02*
Y54574D01*
G01X1222874Y64174D02*
X1220374Y61674D01*
G01X1222874Y94074D02*
Y64174D01*
G01X1224100Y95300D02*
X1222874Y94074D01*
G01X1242200Y114008D02*
Y119374D01*
G01X1243000Y113208D02*
X1242200Y114008D01*
G01X1243840Y113208D02*
X1243000D01*
G01X1244400Y112648D02*
X1243840Y113208D01*
G01X1244400Y110568D02*
Y112648D01*
G01X1243840Y110008D02*
X1244400Y110568D01*
G01X1243000Y110008D02*
X1243840D01*
G01X1242200Y109208D02*
X1243000Y110008D01*
G01X1242200Y107608D02*
Y109208D01*
G01X1243000Y106808D02*
X1242200Y107608D01*
G01X1243690Y106808D02*
X1243000D01*
G01X1244250Y106248D02*
X1243690Y106808D01*
G01X1244250Y104168D02*
Y106248D01*
G01X1243690Y103608D02*
X1244250Y104168D01*
G01X1243160Y103608D02*
X1243690D01*
G01X1242600Y103048D02*
X1243160Y103608D01*
G01X1242600Y100968D02*
Y103048D01*
G01X1243160Y100408D02*
X1242600Y100968D01*
G01X1243890Y100408D02*
X1243160D01*
G01X1244450Y99848D02*
X1243890Y100408D01*
G01X1244450Y97768D02*
Y99848D01*
G01X1243600Y96918D02*
X1244450Y97768D01*
G01X1238100Y111899D02*
X1239900Y110099D01*
G01X1238100Y113599D02*
Y111899D01*
G01X1239000Y114499D02*
X1238100Y113599D01*
G01X1239000Y117399D02*
Y114499D01*
G01X1238100Y118299D02*
X1239000Y117399D01*
G01X1238100Y119938D02*
Y118299D01*
G01X1218700Y97339D02*
Y95739D01*
G01X1220800Y98139D02*
X1219500D01*
G01X1221600Y98939D02*
X1220800Y98139D01*
G01X1221600Y100539D02*
Y98939D01*
G01X1220800Y101339D02*
X1221600Y100539D01*
G01X1219500Y101339D02*
X1220800D01*
G01X1218700Y103739D02*
Y102139D01*
G01X1220800Y104539D02*
X1219500D01*
G01X1221600Y105339D02*
X1220800Y104539D01*
G01X1221600Y106986D02*
Y105339D01*
G01X1235600Y111176D02*
Y95474D01*
G01X1231096Y115680D02*
X1235600Y111176D01*
G01X1231096Y116812D02*
Y115680D01*
G01X1233071Y118787D02*
X1231096Y116812D01*
G01X1233071Y119579D02*
Y118787D01*
G01X1231600Y121050D02*
X1233071Y119579D01*
G01X1230808Y121050D02*
X1231600D01*
G01X1228833Y119075D02*
X1230808Y121050D01*
G01X1227701Y119075D02*
X1228833D01*
G01X1226570Y120206D02*
X1227701Y119075D01*
G01X1226570Y121338D02*
Y120206D01*
G01X1228095Y122863D02*
X1226570Y121338D01*
G01X1228095Y123655D02*
Y122863D01*
G01X1226624Y125126D02*
X1228095Y123655D01*
G01X1225832Y125126D02*
X1226624D01*
G01X1224307Y123601D02*
X1225832Y125126D01*
G01X1223175Y123601D02*
X1224307D01*
G01X1222400Y124376D02*
X1223175Y123601D01*
G01X1222400Y132101D02*
Y124376D01*
G01X1224100Y108022D02*
Y95300D01*
G01X1223400Y519800D02*
Y527200D01*
G01X1222874Y519274D02*
X1223400Y519800D01*
G01X1222874Y493905D02*
Y519274D01*
G01X1245744Y498797D02*
Y489516D01*
G01X1246744Y499797D02*
X1245744Y498797D01*
G01X1248662Y499797D02*
X1246744D01*
G01X1249272Y500407D02*
X1248662Y499797D01*
G01X1249272Y501797D02*
Y500407D01*
G01X1248662Y502407D02*
X1249272Y501797D01*
G01X1246235Y502407D02*
X1248662D01*
G01X1245678Y502964D02*
X1246235Y502407D01*
G01X1245678Y504354D02*
Y502964D01*
G01X1246341Y505017D02*
X1245678Y504354D01*
G01X1248662Y505017D02*
X1246341D01*
G01X1249272Y505627D02*
X1248662Y505017D01*
G01X1249272Y507017D02*
Y505627D01*
G01X1248662Y507627D02*
X1249272Y507017D01*
G01X1246912Y507627D02*
X1248662D01*
G01X1246063Y508476D02*
X1246912Y507627D01*
G01X1246063Y511246D02*
Y508476D01*
G01X1247074Y512257D02*
X1246063Y511246D01*
G01X1247074Y516807D02*
Y512257D01*
G01X1246433Y517448D02*
X1247074Y516807D01*
G01X1246433Y529602D02*
Y517448D01*
G01X1243543Y517426D02*
Y529756D01*
G01X1243174Y517057D02*
X1243543Y517426D01*
G01X1243174Y511657D02*
Y517057D01*
G01X1243545Y511286D02*
X1243174Y511657D01*
G01X1243545Y490551D02*
Y511286D01*
G01X1220000Y519474D02*
Y527700D01*
G01X1220174Y519300D02*
X1220000Y519474D01*
G01X1220174Y517457D02*
Y519300D01*
G01X1219024Y516307D02*
X1220174Y517457D01*
G01X1219024Y512057D02*
Y516307D01*
G01X1220374Y510707D02*
X1219024Y512057D01*
G01X1220374Y494472D02*
Y510707D01*
G01X1241394Y525766D02*
Y526622D01*
G01X1240784Y525156D02*
X1241394Y525766D01*
G01X1239701Y525156D02*
X1240784D01*
G01X1239091Y524546D02*
X1239701Y525156D01*
G01X1239091Y522566D02*
Y524546D01*
G01X1239701Y521956D02*
X1239091Y522566D01*
G01X1240784Y521956D02*
X1239701D01*
G01X1241394Y521346D02*
X1240784Y521956D01*
G01X1241394Y520508D02*
Y521346D01*
G01X1239574Y518688D02*
X1241394Y520508D01*
G01X1239574Y517657D02*
Y518688D01*
G01X1240674Y516557D02*
X1239574Y517657D01*
G01X1240674Y512157D02*
Y516557D01*
G01X1239831Y511314D02*
X1240674Y512157D01*
G01X1239831Y505665D02*
Y511314D01*
G01X1239221Y505055D02*
X1239831Y505665D01*
G01X1237842Y505055D02*
X1239221D01*
G01X1237232Y504445D02*
X1237842Y505055D01*
G01X1237232Y503055D02*
Y504445D01*
G01X1237842Y502445D02*
X1237232Y503055D01*
G01X1239221Y502445D02*
X1237842D01*
G01X1239831Y501835D02*
X1239221Y502445D01*
G01X1239831Y500445D02*
Y501835D01*
G01X1239221Y499835D02*
X1239831Y500445D01*
G01X1237842Y499835D02*
X1239221D01*
G01X1237232Y499225D02*
X1237842Y499835D01*
G01X1237232Y497835D02*
Y499225D01*
G01X1237842Y497225D02*
X1237232Y497835D01*
G01X1239221Y497225D02*
X1237842D01*
G01X1239831Y496615D02*
X1239221Y497225D01*
G01X1239831Y489859D02*
Y496615D01*
G01X1236700Y519874D02*
Y527600D01*
G01X1237074Y519500D02*
X1236700Y519874D01*
G01X1237074Y517557D02*
Y519500D01*
G01X1236474Y516957D02*
X1237074Y517557D01*
G01X1236474Y512057D02*
Y516957D01*
G01X1236861Y511670D02*
X1236474Y512057D01*
G01X1236861Y508741D02*
Y511670D01*
G01X1235429Y507309D02*
X1236861Y508741D01*
G01X1235429Y488747D02*
Y507309D01*
G01X1219886Y566100D02*
X1219287Y566699D01*
G01X1219886Y564900D02*
Y566100D01*
G01X1218942Y563956D02*
X1219886Y564900D01*
G01X1218942Y562744D02*
Y563956D01*
G01X1219786Y561900D02*
X1218942Y562744D01*
G01X1219786Y560200D02*
Y561900D01*
G01X1218942Y559356D02*
X1219786Y560200D01*
G01X1218942Y557936D02*
Y559356D01*
G01X1220086Y556792D02*
X1218942Y557936D01*
G01X1220086Y555199D02*
Y556792D01*
G01X1219179Y554292D02*
X1220086Y555199D01*
G01X1219179Y552600D02*
Y554292D01*
G01X1220865Y550914D02*
X1219179Y552600D01*
G01X1220953Y550914D02*
X1220865D01*
G01X1220953Y550564D02*
Y550914D01*
G01X1222874Y548643D02*
X1220953Y550564D01*
G01X1222874Y547226D02*
Y548643D01*
G01X1223300Y546800D02*
X1222874Y547226D01*
G01X1223300Y538126D02*
Y546800D01*
G01X1222874Y537700D02*
X1223300Y538126D01*
G01X1222874Y527726D02*
Y537700D01*
G01X1223400Y527200D02*
X1222874Y527726D01*
G01X1243304Y552688D02*
X1245078Y550914D01*
G01X1243304Y554292D02*
Y552688D01*
G01X1243479Y554467D02*
X1243304Y554292D01*
G01X1243479Y557100D02*
Y554467D01*
G01X1242367Y558212D02*
X1243479Y557100D01*
G01X1242367Y559288D02*
Y558212D01*
G01X1243379Y560300D02*
X1242367Y559288D01*
G01X1243379Y561500D02*
Y560300D01*
G01X1242367Y562512D02*
X1243379Y561500D01*
G01X1242367Y563588D02*
Y562512D01*
G01X1243504Y564725D02*
X1242367Y563588D01*
G01X1243504Y565999D02*
Y564725D01*
G01X1242804Y566699D02*
X1243504Y565999D01*
G01X1241732Y566699D02*
X1242804D01*
G01X1246964Y530133D02*
X1246433Y529602D01*
G01X1246964Y535936D02*
Y530133D01*
G01X1246374Y536526D02*
X1246964Y535936D01*
G01X1246374Y549618D02*
Y536526D01*
G01X1245078Y550914D02*
X1246374Y549618D01*
G01X1241369Y555594D02*
X1241732Y555957D01*
G01X1241369Y551112D02*
Y555594D01*
G01X1243650Y548831D02*
X1241369Y551112D01*
G01X1243650Y536118D02*
Y548831D01*
G01X1242874Y535342D02*
X1243650Y536118D01*
G01X1242874Y530425D02*
Y535342D01*
G01X1243543Y529756D02*
X1242874Y530425D01*
G01X1240027Y567849D02*
X1245078Y572900D01*
G01X1240027Y557662D02*
Y567849D01*
G01X1241732Y555957D02*
X1240027Y557662D01*
G01X1220224Y547024D02*
Y548657D01*
G01X1220000Y546800D02*
X1220224Y547024D01*
G01X1220000Y537924D02*
Y546800D01*
G01X1220224Y537700D02*
X1220000Y537924D01*
G01X1220224Y536525D02*
Y537700D01*
G01X1218963Y535264D02*
X1220224Y536525D01*
G01X1218963Y530655D02*
Y535264D01*
G01X1220174Y529444D02*
X1218963Y530655D01*
G01X1220174Y527874D02*
Y529444D01*
G01X1220000Y527700D02*
X1220174Y527874D01*
G01X1219787Y572500D02*
X1220953D01*
G01X1239731Y549568D02*
X1238385Y550914D01*
G01X1239774Y549568D02*
X1239731D01*
G01X1239774Y546826D02*
Y549568D01*
G01X1240100Y546500D02*
X1239774Y546826D01*
G01X1240100Y538000D02*
Y546500D01*
G01X1239774Y537674D02*
X1240100Y538000D01*
G01X1239774Y536427D02*
Y537674D01*
G01X1240440Y535761D02*
X1239774Y536427D01*
G01X1240440Y530199D02*
Y535761D01*
G01X1239874Y529633D02*
X1240440Y530199D01*
G01X1239874Y528142D02*
Y529633D01*
G01X1241394Y526622D02*
X1239874Y528142D01*
G01X1236111Y566699D02*
X1235039D01*
G01X1236811Y565999D02*
X1236111Y566699D01*
G01X1236811Y564725D02*
Y565999D01*
G01X1235674Y563588D02*
X1236811Y564725D01*
G01X1235674Y562512D02*
Y563588D01*
G01X1236686Y561500D02*
X1235674Y562512D01*
G01X1236686Y560300D02*
Y561500D01*
G01X1235674Y559288D02*
X1236686Y560300D01*
G01X1235674Y558212D02*
Y559288D01*
G01X1236786Y557100D02*
X1235674Y558212D01*
G01X1236786Y554467D02*
Y557100D01*
G01X1236611Y554292D02*
X1236786Y554467D01*
G01X1236611Y552600D02*
Y554292D01*
G01X1238297Y550914D02*
X1236611Y552600D01*
G01X1238385Y550914D02*
X1238297D01*
G01X1233334Y567849D02*
X1238385Y572900D01*
G01X1233334Y557662D02*
Y567849D01*
G01X1235039Y555957D02*
X1233334Y557662D01*
G01X1234374Y555292D02*
X1235039Y555957D01*
G01X1234374Y551457D02*
Y555292D01*
G01X1237274Y548557D02*
X1234374Y551457D01*
G01X1237274Y546774D02*
Y548557D01*
G01X1236700Y546200D02*
X1237274Y546774D01*
G01X1236700Y537974D02*
Y546200D01*
G01X1237274Y537400D02*
X1236700Y537974D01*
G01X1237274Y536442D02*
Y537400D01*
G01X1236001Y535169D02*
X1237274Y536442D01*
G01X1236001Y530584D02*
Y535169D01*
G01X1237074Y529511D02*
X1236001Y530584D01*
G01X1237074Y527974D02*
Y529511D01*
G01X1236700Y527600D02*
X1237074Y527974D01*
M02*
